FILE_TYPE = MULTI_PHYS_TABLE;

PART 'Q_RES'

{========================================================================================}
:VALUE        | TOLERANCE | WATTAGE  | PACK_TYPE | MATERIAL | PART_NUMBER             = STANDARD        | LIFECYCLE          | PART_NUMBER             | JEDEC_TYPE          | ALT_SYMBOLS                    | VALUE     | TOL     | WATTAGE  | CLASS      | DESCRIPTION                                        | COMPONENT_TYPE | LEAD_LENGTH | DFM_EXCLUSION | DAY        ;
{========================================================================================}
 '64.9K'      | '1%'      | '1/10W'  | '0603LF'  | 'CHIP'   | 'TMP_QCS36493F913'(!)   = 'End of Design' | 'Comp-Approve'     | 'CS36493F913'           | 'R0603'             | '(SMR0603AW)'                  | '64.9K'   | '1%'    | '1/10W'  | 'DISCRETE' | '64.9Kohm 0603'                                    | 'CHIP0603'     | ''          | ''            | ''        
 '64.9K'      | '1%'      | '1/10W'  | '0603LF'  | 'EMPTY'  | 'TMP_QCS36493F913'(!)   = 'End of Design' | 'Comp-Approve'     | 'CS36493F913'           | 'R0603'             | '(SMR0603AW)'                  | '64.9K'   | '1%'    | '1/10W'  | 'IO'       | '64.9Kohm 0603'                                    | 'CHIP0603'     | ''          | ''            | ''        
 '107K'       | '1%'      | '1/10W'  | '0603LF'  | 'CHIP'   | 'TMP_QCS41073F918'(!)   = 'End of Design' | 'Comp-Approve'     | 'CS41073F918'           | 'R0603'             | '(SMR0603AW)'                  | '107K'    | '1%'    | '1/10W'  | 'DISCRETE' | '107Kohm 0603'                                     | 'CHIP0603'     | ''          | ''            | ''        
 '107K'       | '1%'      | '1/10W'  | '0603LF'  | 'EMPTY'  | 'TMP_QCS41073F918'(!)   = 'End of Design' | 'Comp-Approve'     | 'CS41073F918'           | 'R0603'             | '(SMR0603AW)'                  | '107K'    | '1%'    | '1/10W'  | 'IO'       | '107Kohm 0603'                                     | 'CHIP0603'     | ''          | ''            | ''        
 '3.6K'       | '1%'      | '1/10W'  | '0603LF'  | 'CHIP'   | 'TMP_QCS23603F910'(!)   = ''              | ''                 | 'CS23603F910'           | 'R0603'             | '(SMR0603AW)'                  | '3.6K'    | '1%'    | '1/10W'  | 'DISCRETE' | '3.6Kohm 0603'                                     | 'CHIP0603'     | ''          | ''            | ''        
 '3.6K'       | '1%'      | '1/10W'  | '0603LF'  | 'EMPTY'  | 'TMP_QCS23603F910'(!)   = ''              | ''                 | 'CS23603F910'           | 'R0603'             | '(SMR0603AW)'                  | '3.6K'    | '1%'    | '1/10W'  | 'IO'       | '3.6Kohm 0603'                                     | 'CHIP0603'     | ''          | ''            | ''        
 '169'        | '1%'      | '1/10W'  | '0603LF'  | 'CHIP'   | 'TMP_QCS11693F913'(!)   = 'End of Design' | 'Comp-Approve'     | 'CS11693F913'           | 'R0603'             | '(SMR0603AW)'                  | '169'     | '1%'    | '1/10W'  | 'DISCRETE' | '169ohm 0603'                                      | 'CHIP0603'     | ''          | ''            | ''        
 '169'        | '1%'      | '1/10W'  | '0603LF'  | 'EMPTY'  | 'TMP_QCS11693F913'(!)   = 'End of Design' | 'Comp-Approve'     | 'CS11693F913'           | 'R0603'             | '(SMR0603AW)'                  | '169'     | '1%'    | '1/10W'  | 'IO'       | '169ohm 0603'                                      | 'CHIP0603'     | ''          | ''            | ''        
 '210'        | '1%'      | '1/10W'  | '0603LF'  | 'CHIP'   | 'TMP_QCS12103F909'(!)   = ''              | ''                 | 'CS12103F909'           | 'R0603'             | '(SMR0603AW)'                  | '210'     | '1%'    | '1/10W'  | 'DISCRETE' | '210ohm 0603'                                      | 'CHIP0603'     | ''          | ''            | ''        
 '210'        | '1%'      | '1/10W'  | '0603LF'  | 'EMPTY'  | 'TMP_QCS12103F909'(!)   = ''              | ''                 | 'CS12103F909'           | 'R0603'             | '(SMR0603AW)'                  | '210'     | '1%'    | '1/10W'  | 'IO'       | '210ohm 0603'                                      | 'CHIP0603'     | ''          | ''            | ''        
 '9.53K'      | '1%'      | '1/10W'  | '0603LF'  | 'CHIP'   | 'TMP_QCS29533F908'(!)   = ''              | ''                 | 'CS29533F908'           | 'R0603'             | '(SMR0603AW)'                  | '9.53K'   | '1%'    | '1/10W'  | 'DISCRETE' | '9.53Kohm 0603'                                    | 'CHIP0603'     | ''          | ''            | ''        
 '9.53K'      | '1%'      | '1/10W'  | '0603LF'  | 'EMPTY'  | 'TMP_QCS29533F908'(!)   = ''              | ''                 | 'CS29533F908'           | 'R0603'             | '(SMR0603AW)'                  | '9.53K'   | '1%'    | '1/10W'  | 'IO'       | '9.53Kohm 0603'                                    | 'CHIP0603'     | ''          | ''            | ''        
 '787'        | '1%'      | '1/10W'  | '0603'    | 'CHIP'   | 'TMP_QCS17873F900'(!)   = ''              | ''                 | 'CS17873F900'           | 'R0603'             | '(SMR0603AW)'                  | '787'     | '1%'    | '1/10W'  | 'DISCRETE' | '787ohm 0603'                                      | 'CHIP0603'     | ''          | ''            | ''        
 '787'        | '1%'      | '1/10W'  | '0603'    | 'EMPTY'  | 'TMP_QCS17873F900'(!)   = ''              | ''                 | 'CS17873F900'           | 'R0603'             | '(SMR0603AW)'                  | '787'     | '1%'    | '1/10W'  | 'IO'       | '787ohm 0603'                                      | 'CHIP0603'     | ''          | ''            | ''        
 '30.1'       | '1%'      | '1/10W'  | '0603LF'  | 'CHIP'   | 'TMP_QCS03013F919'(!)   = ''              | ''                 | 'CS03013F919'           | 'R0603'             | '(SMR0603AW)'                  | '30.1'    | '1%'    | '1/10W'  | 'DISCRETE' | '30.1ohm 0603'                                     | 'CHIP0603'     | ''          | ''            | ''        
 '30.1'       | '1%'      | '1/10W'  | '0603LF'  | 'EMPTY'  | 'TMP_QCS03013F919'(!)   = ''              | ''                 | 'CS03013F919'           | 'R0603'             | '(SMR0603AW)'                  | '30.1'    | '1%'    | '1/10W'  | 'IO'       | '30.1ohm 0603'                                     | 'CHIP0603'     | ''          | ''            | ''        
 '2.2'        | '1%'      | '1/10W'  | '0603LF'  | 'CHIP'   | 'TMP_QCS-2203F911'(!)   = ''              | ''                 | 'CS-2203F911'           | 'R0603'             | '(SMR0603AW)'                  | '2.2'     | '1%'    | '1/10W'  | 'DISCRETE' | '2.2ohm 0603'                                      | 'CHIP0603'     | ''          | ''            | ''        
 '2.2'        | '1%'      | '1/10W'  | '0603LF'  | 'EMPTY'  | 'TMP_QCS-2203F911'(!)   = ''              | ''                 | 'CS-2203F911'           | 'R0603'             | '(SMR0603AW)'                  | '2.2'     | '1%'    | '1/10W'  | 'IO'       | '2.2ohm 0603'                                      | 'CHIP0603'     | ''          | ''            | ''        
 '32.4K'      | '1%'      | '1/10W'  | '0603LF'  | 'CHIP'   | 'TMP_QCS33243F915'(!)   = 'End of Design' | 'Comp-Approve'     | 'CS33243F915'           | 'R0603'             | '(SMR0603AW)'                  | '32.4K'   | '1%'    | '1/10W'  | 'DISCRETE' | '32.4Kohm 0603'                                    | 'CHIP0603'     | ''          | ''            | ''        
 '32.4K'      | '1%'      | '1/10W'  | '0603LF'  | 'EMPTY'  | 'TMP_QCS33243F915'(!)   = 'End of Design' | 'Comp-Approve'     | 'CS33243F915'           | 'R0603'             | '(SMR0603AW)'                  | '32.4K'   | '1%'    | '1/10W'  | 'IO'       | '32.4Kohm 0603'                                    | 'CHIP0603'     | ''          | ''            | ''        
 '1.87K'      | '1%'      | '1/16W'  | '0402LF'  | 'CHIP'   | 'TMP_QCS21872FB17'(!)   = 'End of Design' | 'Comp-Approve'     | 'CS21872FB17'           | 'R0402'             | '(R0402-0201)'                 | '1.87K'   | '1%'    | '1/16W'  | 'DISCRETE' | '1.87Kohm 0402'                                    | 'CHIP0402'     | ''          | ''            | ''        
 '1.87K'      | '1%'      | '1/16W'  | '0402LF'  | 'EMPTY'  | 'TMP_QCS21872FB17'(!)   = 'End of Design' | 'Comp-Approve'     | 'CS21872FB17'           | 'R0402'             | '(R0402-0201)'                 | '1.87K'   | '1%'    | '1/16W'  | 'IO'       | '1.87Kohm 0402'                                    | 'CHIP0402'     | ''          | ''            | ''        
 '18K'        | '1%'      | '1/16W'  | '0402LF'  | 'CHIP'   | 'TMP_QCS31802FB10'(!)   = 'End of Design' | 'Comp-Approve'     | 'CS31802FB10'           | 'R0402'             | '(R0402-0201)'                 | '18K'     | '1%'    | '1/16W'  | 'DISCRETE' | '18Kohm 0402'                                      | 'CHIP0402'     | ''          | ''            | ''        
 '18K'        | '1%'      | '1/16W'  | '0402LF'  | 'EMPTY'  | 'TMP_QCS31802FB10'(!)   = 'End of Design' | 'Comp-Approve'     | 'CS31802FB10'           | 'R0402'             | '(R0402-0201)'                 | '18K'     | '1%'    | '1/16W'  | 'IO'       | '18Kohm 0402'                                      | 'CHIP0402'     | ''          | ''            | ''        
 '17.8K'      | '1%'      | '1/16W'  | '0402LF'  | 'CHIP'   | 'TMP_QCS31782FB10'(!)   = 'End of Design' | 'Comp-Approve'     | 'CS31782FB10'           | 'R0402'             | '(R0402-0201)'                 | '17.8K'   | '1%'    | '1/16W'  | 'DISCRETE' | '17.8Kohm 0402'                                    | 'CHIP0402'     | ''          | ''            | ''        
 '17.8K'      | '1%'      | '1/16W'  | '0402LF'  | 'EMPTY'  | 'TMP_QCS31782FB10'(!)   = 'End of Design' | 'Comp-Approve'     | 'CS31782FB10'           | 'R0402'             | '(R0402-0201)'                 | '17.8K'   | '1%'    | '1/16W'  | 'IO'       | '17.8Kohm 0402'                                    | 'CHIP0402'     | ''          | ''            | ''        
 '4.53K'      | '1%'      | '1/16W'  | '0402LF'  | 'CHIP'   | 'TMP_QCS24532FB08'(!)   = 'End of Design' | 'Comp-Approve'     | 'CS24532FB08'           | 'R0402'             | '(R0402-0201)'                 | '4.53K'   | '1%'    | '1/16W'  | 'DISCRETE' | '4.53Kohm 0402'                                    | 'CHIP0402'     | ''          | ''            | ''        
 '4.53K'      | '1%'      | '1/16W'  | '0402LF'  | 'EMPTY'  | 'TMP_QCS24532FB08'(!)   = 'End of Design' | 'Comp-Approve'     | 'CS24532FB08'           | 'R0402'             | '(R0402-0201)'                 | '4.53K'   | '1%'    | '1/16W'  | 'IO'       | '4.53Kohm 0402'                                    | 'CHIP0402'     | ''          | ''            | ''        
 '715'        | '1%'      | '1/16W'  | '0402LF'  | 'CHIP'   | 'TMP_QCS17152FB17'(!)   = 'End of Design' | 'Comp-Approve'     | 'CS17152FB17'           | 'R0402'             | '(R0402-0201)'                 | '715'     | '1%'    | '1/16W'  | 'DISCRETE' | '715ohm 0402'                                      | 'CHIP0402'     | ''          | ''            | ''        
 '715'        | '1%'      | '1/16W'  | '0402LF'  | 'EMPTY'  | 'TMP_QCS17152FB17'(!)   = 'End of Design' | 'Comp-Approve'     | 'CS17152FB17'           | 'R0402'             | '(R0402-0201)'                 | '715'     | '1%'    | '1/16W'  | 'IO'       | '715ohm 0402'                                      | 'CHIP0402'     | ''          | ''            | ''        
 '1.15K'      | '1%'      | '1/16W'  | '0402LF'  | 'CHIP'   | 'TMP_QCS21152FB12'(!)   = 'End of Design' | 'Comp-Approve'     | 'CS21152FB12'           | 'R0402'             | '(R0402-0201)'                 | '1.15K'   | '1%'    | '1/16W'  | 'DISCRETE' | '1.15Kohm 0402'                                    | 'CHIP0402'     | ''          | ''            | ''        
 '1.15K'      | '1%'      | '1/16W'  | '0402LF'  | 'EMPTY'  | 'TMP_QCS21152FB12'(!)   = 'End of Design' | 'Comp-Approve'     | 'CS21152FB12'           | 'R0402'             | '(R0402-0201)'                 | '1.15K'   | '1%'    | '1/16W'  | 'IO'       | '1.15Kohm 0402'                                    | 'CHIP0402'     | ''          | ''            | ''        
 '68.1'       | '1%'      | '1/4W'   | '1206LF'  | 'CHIP'   | 'TMP_QCS06816F200'(!)   = ''              | ''                 | 'CS06816F200'           | 'R1206'             | '(SMR1206AW)'                  | '68.1'    | '1%'    | '1/4W'   | 'DISCRETE' | '68.1ohm 1206'                                     | 'CHIP1206'     | ''          | ''            | ''        
 '68.1'       | '1%'      | '1/4W'   | '1206LF'  | 'EMPTY'  | 'TMP_QCS06816F200'(!)   = ''              | ''                 | 'CS06816F200'           | 'R1206'             | '(SMR1206AW)'                  | '68.1'    | '1%'    | '1/4W'   | 'IO'       | '68.1ohm 1206'                                     | 'CHIP1206'     | ''          | ''            | ''        
 '549'        | '1%'      | '1/4W'   | '1206LF'  | 'CHIP'   | 'TMP_QCS15496F200'(!)   = ''              | ''                 | 'CS15496F200'           | 'R1206'             | '(SMR1206AW)'                  | '549'     | '1%'    | '1/4W'   | 'DISCRETE' | '549ohm 1206'                                      | 'CHIP1206'     | ''          | ''            | ''        
 '549'        | '1%'      | '1/4W'   | '1206LF'  | 'EMPTY'  | 'TMP_QCS15496F200'(!)   = ''              | ''                 | 'CS15496F200'           | 'R1206'             | '(SMR1206AW)'                  | '549'     | '1%'    | '1/4W'   | 'IO'       | '549ohm 1206'                                      | 'CHIP1206'     | ''          | ''            | ''        
 '649'        | '1%'      | '1/4W'   | '1206LF'  | 'CHIP'   | 'TMP_QCS16496F200'(!)   = ''              | ''                 | 'CS16496F200'           | 'R1206'             | '(SMR1206AW)'                  | '649'     | '1%'    | '1/4W'   | 'DISCRETE' | '649ohm 1206'                                      | 'CHIP1206'     | ''          | ''            | ''        
 '649'        | '1%'      | '1/4W'   | '1206LF'  | 'EMPTY'  | 'TMP_QCS16496F200'(!)   = ''              | ''                 | 'CS16496F200'           | 'R1206'             | '(SMR1206AW)'                  | '649'     | '1%'    | '1/4W'   | 'IO'       | '649ohm 1206'                                      | 'CHIP1206'     | ''          | ''            | ''        
 '5.49K'      | '1%'      | '1/4W'   | '1206LF'  | 'CHIP'   | 'TMP_QCS25496F200'(!)   = ''              | ''                 | 'CS25496F200'           | 'R1206'             | '(SMR1206AW)'                  | '5.49K'   | '1%'    | '1/4W'   | 'DISCRETE' | '5.49Kohm 1206'                                    | 'CHIP1206'     | ''          | ''            | ''        
 '5.49K'      | '1%'      | '1/4W'   | '1206LF'  | 'EMPTY'  | 'TMP_QCS25496F200'(!)   = ''              | ''                 | 'CS25496F200'           | 'R1206'             | '(SMR1206AW)'                  | '5.49K'   | '1%'    | '1/4W'   | 'IO'       | '5.49Kohm 1206'                                    | 'CHIP1206'     | ''          | ''            | ''        
 '6.04K'      | '1%'      | '1/4W'   | '1206LF'  | 'CHIP'   | 'TMP_QCS26046F200'(!)   = ''              | ''                 | 'CS26046F200'           | 'R1206'             | '(SMR1206AW)'                  | '6.04K'   | '1%'    | '1/4W'   | 'DISCRETE' | '6.04Kohm 1206'                                    | 'CHIP1206'     | ''          | ''            | ''        
 '6.04K'      | '1%'      | '1/4W'   | '1206LF'  | 'EMPTY'  | 'TMP_QCS26046F200'(!)   = ''              | ''                 | 'CS26046F200'           | 'R1206'             | '(SMR1206AW)'                  | '6.04K'   | '1%'    | '1/4W'   | 'IO'       | '6.04Kohm 1206'                                    | 'CHIP1206'     | ''          | ''            | ''        
 '9.53K'      | '1%'      | '1/4W'   | '1206LF'  | 'CHIP'   | 'TMP_QCS29536F200'(!)   = ''              | ''                 | 'CS29536F200'           | 'R1206'             | '(SMR1206AW)'                  | '9.53K'   | '1%'    | '1/4W'   | 'DISCRETE' | '9.53Kohm 1206'                                    | 'CHIP1206'     | ''          | ''            | ''        
 '9.53K'      | '1%'      | '1/4W'   | '1206LF'  | 'EMPTY'  | 'TMP_QCS29536F200'(!)   = ''              | ''                 | 'CS29536F200'           | 'R1206'             | '(SMR1206AW)'                  | '9.53K'   | '1%'    | '1/4W'   | 'IO'       | '9.53Kohm 1206'                                    | 'CHIP1206'     | ''          | ''            | ''        
 '63.4K'      | '1%'      | '1/4W'   | '1206LF'  | 'CHIP'   | 'TMP_QCS36346F200'(!)   = ''              | ''                 | 'CS36346F200'           | 'R1206'             | '(SMR1206AW)'                  | '63.4K'   | '1%'    | '1/4W'   | 'DISCRETE' | '63.4Kohm 1206'                                    | 'CHIP1206'     | ''          | ''            | ''        
 '63.4K'      | '1%'      | '1/4W'   | '1206LF'  | 'EMPTY'  | 'TMP_QCS36346F200'(!)   = ''              | ''                 | 'CS36346F200'           | 'R1206'             | '(SMR1206AW)'                  | '63.4K'   | '1%'    | '1/4W'   | 'IO'       | '63.4Kohm 1206'                                    | 'CHIP1206'     | ''          | ''            | ''        
 '0.015'      | '1%'      | '1/4W'   | '1206LF'  | 'CHIP'   | 'TMP_QCS+0156F200'(!)   = ''              | ''                 | 'CS+0156F200'           | 'R1206'             | '(SMR1206AW)'                  | '0.015'   | '1%'    | '1/4W'   | 'DISCRETE' | '0.015ohm 1206'                                    | 'CHIP1206'     | ''          | ''            | ''        
 '0.015'      | '1%'      | '1/4W'   | '1206LF'  | 'EMPTY'  | 'TMP_QCS+0156F200'(!)   = ''              | ''                 | 'CS+0156F200'           | 'R1206'             | '(SMR1206AW)'                  | '0.015'   | '1%'    | '1/4W'   | 'IO'       | '0.015ohm 1206'                                    | 'CHIP1206'     | ''          | ''            | ''        
 '0.025'      | '1%'      | '1/4W'   | '1206LF'  | 'CHIP'   | 'TMP_QCS+0256F200'(!)   = ''              | ''                 | 'CS+0256F200'           | 'R1206'             | '(SMR1206AW)'                  | '0.025'   | '1%'    | '1/4W'   | 'DISCRETE' | '0.025ohm 1206'                                    | 'CHIP1206'     | ''          | ''            | ''        
 '0.025'      | '1%'      | '1/4W'   | '1206LF'  | 'EMPTY'  | 'TMP_QCS+0256F200'(!)   = ''              | ''                 | 'CS+0256F200'           | 'R1206'             | '(SMR1206AW)'                  | '0.025'   | '1%'    | '1/4W'   | 'IO'       | '0.025ohm 1206'                                    | 'CHIP1206'     | ''          | ''            | ''        
 '5.11'       | '1%'      | '1/4W'   | '1206LF'  | 'CHIP'   | 'TMP_QCS-5116F208'(!)   = ''              | ''                 | 'CS-5116F208'           | 'R1206'             | '(SMR1206AW)'                  | '5.11'    | '1%'    | '1/4W'   | 'DISCRETE' | '5.11ohm 1206'                                     | 'CHIP1206'     | ''          | ''            | ''        
 '5.11'       | '1%'      | '1/4W'   | '1206LF'  | 'EMPTY'  | 'TMP_QCS-5116F208'(!)   = ''              | ''                 | 'CS-5116F208'           | 'R1206'             | '(SMR1206AW)'                  | '5.11'    | '1%'    | '1/4W'   | 'IO'       | '5.115ohm 1206'                                    | 'CHIP1206'     | ''          | ''            | ''        
 '22'         | '5%'      | '1/4W'   | '1206LF'  | 'CHIP'   | 'TMP_QCS02206J216'(!)   = 'End of Design' | 'Comp-Release Qty' | 'CS02206J216'           | 'R1206'             | '(SMR1206AW)'                  | '22'      | '5%'    | '1/4W'   | 'DISCRETE' | '22ohm 1206'                                       | 'CHIP1206'     | ''          | ''            | ''        
 '22'         | '5%'      | '1/4W'   | '1206LF'  | 'EMPTY'  | 'TMP_QCS02206J216'(!)   = 'End of Design' | 'Comp-Release Qty' | 'CS02206J216'           | 'R1206'             | '(SMR1206AW)'                  | '22'      | '5%'    | '1/4W'   | 'IO'       | '22ohm 1206'                                       | 'CHIP1206'     | ''          | ''            | ''        
 '53.6'       | '1%'      | '1/8W'   | '1206LF'  | 'CHIP'   | 'TMP_QCS05364FA07'(!)   = ''              | ''                 | 'CS05364FA07'           | 'R1206'             | '(SMR1206AW)'                  | '53.6'    | '1%'    | '1/8W'   | 'DISCRETE' | '53.6ohm 1206'                                     | 'CHIP1206'     | ''          | ''            | ''        
 '53.6'       | '1%'      | '1/8W'   | '1206LF'  | 'EMPTY'  | 'TMP_QCS05364FA07'(!)   = ''              | ''                 | 'CS05364FA07'           | 'R1206'             | '(SMR1206AW)'                  | '53.6'    | '1%'    | '1/8W'   | 'IO'       | '53.6ohm 1206'                                     | 'CHIP1206'     | ''          | ''            | ''        
 '2.49K'      | '1%'      | '1/8W'   | '0805LF'  | 'CHIP'   | 'TMP_QCS22494FA00'(!)   = ''              | ''                 | 'CS22494FA00'           | 'R0805'             | '(SMR0805AW)'                  | '2.49K'   | '1%'    | '1/8W'   | 'DISCRETE' | '2.49Kohm 0805'                                    | 'CHIP0805'     | ''          | ''            | ''        
 '2.49K'      | '1%'      | '1/8W'   | '0805LF'  | 'EMPTY'  | 'TMP_QCS22494FA00'(!)   = ''              | ''                 | 'CS22494FA00'           | 'R0805'             | '(SMR0805AW)'                  | '2.49K'   | '1%'    | '1/8W'   | 'IO'       | '2.49Kohm 0805'                                    | 'CHIP0805'     | ''          | ''            | ''        
 '174'        | '1%'      | '1/4W'   | '1206LF'  | 'CHIP'   | 'TMP_QCS11746F200'(!)   = ''              | ''                 | 'CS11746F200'           | 'R1206'             | '(SMR1206AW)'                  | '174'     | '1%'    | '1/4W'   | 'DISCRETE' | '174ohm 1206'                                      | 'CHIP1206'     | ''          | ''            | ''        
 '174'        | '1%'      | '1/4W'   | '1206LF'  | 'EMPTY'  | 'TMP_QCS11746F200'(!)   = ''              | ''                 | 'CS11746F200'           | 'R1206'             | '(SMR1206AW)'                  | '174'     | '1%'    | '1/4W'   | 'IO'       | '174ohm 1206'                                      | 'CHIP1206'     | ''          | ''            | ''        
 '3.16K'      | '1%'      | '1/4W'   | '1206LF'  | 'CHIP'   | 'TMP_QCS23166F200'(!)   = ''              | ''                 | 'CS23166F200'           | 'R1206'             | '(SMR1206AW)'                  | '3.16K'   | '1%'    | '1/4W'   | 'DISCRETE' | '3.16Kohm 1206'                                    | 'CHIP1206'     | ''          | ''            | ''        
 '3.16K'      | '1%'      | '1/4W'   | '1206LF'  | 'EMPTY'  | 'TMP_QCS23166F200'(!)   = ''              | ''                 | 'CS23166F200'           | 'R1206'             | '(SMR1206AW)'                  | '3.16K'   | '1%'    | '1/4W'   | 'IO'       | '3.16Kohm 1206'                                    | 'CHIP1206'     | ''          | ''            | ''        
 '3.83K'      | '1%'      | '1/4W'   | '1206LF'  | 'CHIP'   | 'TMP_QCS23836F200'(!)   = ''              | ''                 | 'CS23836F200'           | 'R1206'             | '(SMR1206AW)'                  | '3.83K'   | '1%'    | '1/4W'   | 'DISCRETE' | '3.83Kohm 1206'                                    | 'CHIP1206'     | ''          | ''            | ''        
 '3.83K'      | '1%'      | '1/4W'   | '1206LF'  | 'EMPTY'  | 'TMP_QCS23836F200'(!)   = ''              | ''                 | 'CS23836F200'           | 'R1206'             | '(SMR1206AW)'                  | '3.83K'   | '1%'    | '1/4W'   | 'IO'       | '3.83Kohm 1206'                                    | 'CHIP1206'     | ''          | ''            | ''        
 '15.4K'      | '1%'      | '1/4W'   | '1206LF'  | 'CHIP'   | 'TMP_QCS31546F200'(!)   = ''              | ''                 | 'CS31546F200'           | 'R1206'             | '(SMR1206AW)'                  | '15.4K'   | '1%'    | '1/4W'   | 'DISCRETE' | '15.4Kohm 1206'                                    | 'CHIP1206'     | ''          | ''            | ''        
 '15.4K'      | '1%'      | '1/4W'   | '1206LF'  | 'EMPTY'  | 'TMP_QCS31546F200'(!)   = ''              | ''                 | 'CS31546F200'           | 'R1206'             | '(SMR1206AW)'                  | '15.4K'   | '1%'    | '1/4W'   | 'IO'       | '15.4Kohm 1206'                                    | 'CHIP1206'     | ''          | ''            | ''        
 '20K'        | '1%'      | '1/4W'   | '1206LF'  | 'CHIP'   | 'TMP_QCS32006F200'(!)   = ''              | ''                 | 'CS32006F200'           | 'R1206'             | '(SMR1206AW)'                  | '20K'     | '1%'    | '1/4W'   | 'DISCRETE' | '20Kohm 1206'                                      | 'CHIP1206'     | ''          | ''            | ''        
 '20K'        | '1%'      | '1/4W'   | '1206LF'  | 'EMPTY'  | 'TMP_QCS32006F200'(!)   = ''              | ''                 | 'CS32006F200'           | 'R1206'             | '(SMR1206AW)'                  | '20K'     | '1%'    | '1/4W'   | 'IO'       | '20Kohm 1206'                                      | 'CHIP1206'     | ''          | ''            | ''        
 '22.1K'      | '1%'      | '1/4W'   | '1206LF'  | 'CHIP'   | 'TMP_QCS32216F200'(!)   = ''              | ''                 | 'CS32216F200'           | 'R1206'             | '(SMR1206AW)'                  | '22.1K'   | '1%'    | '1/4W'   | 'DISCRETE' | '22.1Kohm 1206'                                    | 'CHIP1206'     | ''          | ''            | ''        
 '22.1K'      | '1%'      | '1/4W'   | '1206LF'  | 'EMPTY'  | 'TMP_QCS32216F200'(!)   = ''              | ''                 | 'CS32216F200'           | 'R1206'             | '(SMR1206AW)'                  | '22.1K'   | '1%'    | '1/4W'   | 'IO'       | '22.1Kohm 1206'                                    | 'CHIP1206'     | ''          | ''            | ''        
 '1.5M'       | '1%'      | '1/4W'   | '1206LF'  | 'CHIP'   | 'TMP_QCS51506F200'(!)   = ''              | ''                 | 'CS51506F200'           | 'R1206'             | '(SMR1206AW)'                  | '1.5M'    | '1%'    | '1/4W'   | 'DISCRETE' | '1.5Mohm 1206'                                     | 'CHIP1206'     | ''          | ''            | ''        
 '1.5M'       | '1%'      | '1/4W'   | '1206LF'  | 'EMPTY'  | 'TMP_QCS51506F200'(!)   = ''              | ''                 | 'CS51506F200'           | 'R1206'             | '(SMR1206AW)'                  | '1.5M'    | '1%'    | '1/4W'   | 'IO'       | '1.5Mohm 1206'                                     | 'CHIP1206'     | ''          | ''            | ''        
 '60.4'       | '1%'      | '1/4W'   | '1206LF'  | 'CHIP'   | 'TMP_QCS06046F200'(!)   = ''              | ''                 | 'CS06046F200'           | 'R1206'             | '(SMR1206AW)'                  | '60.4'    | '1%'    | '1/4W'   | 'DISCRETE' | '60.4ohm 1206'                                     | 'CHIP1206'     | ''          | ''            | ''        
 '60.4'       | '1%'      | '1/4W'   | '1206LF'  | 'EMPTY'  | 'TMP_QCS06046F200'(!)   = ''              | ''                 | 'CS06046F200'           | 'R1206'             | '(SMR1206AW)'                  | '60.4'    | '1%'    | '1/4W'   | 'IO'       | '60.4ohm 1206'                                     | 'CHIP1206'     | ''          | ''            | ''        
 '787'        | '1%'      | '1/4W'   | '1206LF'  | 'CHIP'   | 'TMP_QCS17876F200'(!)   = ''              | ''                 | 'CS17876F200'           | 'R1206'             | '(SMR1206AW)'                  | '787'     | '1%'    | '1/4W'   | 'DISCRETE' | '787ohm 1206'                                      | 'CHIP1206'     | ''          | ''            | ''        
 '787'        | '1%'      | '1/4W'   | '1206LF'  | 'EMPTY'  | 'TMP_QCS17876F200'(!)   = ''              | ''                 | 'CS17876F200'           | 'R1206'             | '(SMR1206AW)'                  | '787'     | '1%'    | '1/4W'   | 'IO'       | '787ohm 1206'                                      | 'CHIP1206'     | ''          | ''            | ''        
 '953'        | '1%'      | '1/4W'   | '1206LF'  | 'CHIP'   | 'TMP_QCS19536F200'(!)   = ''              | ''                 | 'CS19536F200'           | 'R1206'             | '(SMR1206AW)'                  | '953'     | '1%'    | '1/4W'   | 'DISCRETE' | '953ohm 1206'                                      | 'CHIP1206'     | ''          | ''            | ''        
 '953'        | '1%'      | '1/4W'   | '1206LF'  | 'EMPTY'  | 'TMP_QCS19536F200'(!)   = ''              | ''                 | 'CS19536F200'           | 'R1206'             | '(SMR1206AW)'                  | '953'     | '1%'    | '1/4W'   | 'IO'       | '953ohm 1206'                                      | 'CHIP1206'     | ''          | ''            | ''        
 '1.3K'       | '1%'      | '1/4W'   | '1206LF'  | 'CHIP'   | 'TMP_QCS21306F200'(!)   = ''              | ''                 | 'CS21306F200'           | 'R1206'             | '(SMR1206AW)'                  | '1.3K'    | '1%'    | '1/4W'   | 'DISCRETE' | '1.3Kohm 1206'                                     | 'CHIP1206'     | ''          | ''            | ''        
 '1.3K'       | '1%'      | '1/4W'   | '1206LF'  | 'EMPTY'  | 'TMP_QCS21306F200'(!)   = ''              | ''                 | 'CS21306F200'           | 'R1206'             | '(SMR1206AW)'                  | '1.3K'    | '1%'    | '1/4W'   | 'IO'       | '1.3Kohm 1206'                                     | 'CHIP1206'     | ''          | ''            | ''        
 '1.82K'      | '1%'      | '1/4W'   | '1206LF'  | 'CHIP'   | 'TMP_QCS21826F200'(!)   = ''              | ''                 | 'CS21826F200'           | 'R1206'             | '(SMR1206AW)'                  | '1.82K'   | '1%'    | '1/4W'   | 'DISCRETE' | '1.82Kohm 1206'                                    | 'CHIP1206'     | ''          | ''            | ''        
 '1.82K'      | '1%'      | '1/4W'   | '1206LF'  | 'EMPTY'  | 'TMP_QCS21826F200'(!)   = ''              | ''                 | 'CS21826F200'           | 'R1206'             | '(SMR1206AW)'                  | '1.82K'   | '1%'    | '1/4W'   | 'IO'       | '1.82Kohm 1206'                                    | 'CHIP1206'     | ''          | ''            | ''        
 '4.7K'       | '1%'      | '1/4W'   | '1206LF'  | 'CHIP'   | 'TMP_QCS24706F200'(!)   = 'End of Design' | 'Comp-Approve'     | 'CS24706F200'           | 'R1206'             | '(SMR1206AW)'                  | '4.7K'    | '1%'    | '1/4W'   | 'DISCRETE' | '4.7Kohm 1206'                                     | 'CHIP1206'     | ''          | ''            | ''        
 '4.7K'       | '1%'      | '1/4W'   | '1206LF'  | 'EMPTY'  | 'TMP_QCS24706F200'(!)   = 'End of Design' | 'Comp-Approve'     | 'CS24706F200'           | 'R1206'             | '(SMR1206AW)'                  | '4.7K'    | '1%'    | '1/4W'   | 'IO'       | '4.7Kohm 1206'                                     | 'CHIP1206'     | ''          | ''            | ''        
 '17.4K'      | '1%'      | '1/4W'   | '1206LF'  | 'CHIP'   | 'TMP_QCS31746F200'(!)   = 'End of Design' | 'Comp-Approve'     | 'CS24706F200'           | 'R1206'             | '(SMR1206AW)'                  | '17.4K'   | '1%'    | '1/4W'   | 'DISCRETE' | '17.4Kohm 1206'                                    | 'CHIP1206'     | ''          | ''            | ''        
 '17.4K'      | '1%'      | '1/4W'   | '1206LF'  | 'EMPTY'  | 'TMP_QCS31746F200'(!)   = 'End of Design' | 'Comp-Approve'     | 'CS24706F200'           | 'R1206'             | '(SMR1206AW)'                  | '17.4K'   | '1%'    | '1/4W'   | 'IO'       | '17.4Kohm 1206'                                    | 'CHIP1206'     | ''          | ''            | ''        
 '130K'       | '1%'      | '1/10W'  | '0603LF'  | 'CHIP'   | 'TMP_QCS41303F917'(!)   = ''              | ''                 | 'CS41303F917'           | 'R0603'             | '(SMR0603AW)'                  | '130K'    | '1%'    | '1/10W'  | 'DISCRETE' | '130Kohm 0603'                                     | 'CHIP0603'     | ''          | ''            | ''        
 '130K'       | '1%'      | '1/10W'  | '0603LF'  | 'EMPTY'  | 'TMP_QCS41303F917'(!)   = ''              | ''                 | 'CS41303F917'           | 'R0603'             | '(SMR0603AW)'                  | '130K'    | '1%'    | '1/10W'  | 'IO'       | '130Kohm 0603'                                     | 'CHIP0603'     | ''          | ''            | ''        
 '12K'        | '1%'      | '1/16W'  | '0402LF'  | 'CHIP'   | 'TMP_QCS31202FB15'(!)   = 'End of Design' | 'Comp-Approve'     | 'CS31202FB15'           | 'R0402'             | '(R0402-0201)'                 | '12K'     | '1%'    | '1/16W'  | 'DISCRETE' | '12Kohm 0402'                                      | 'CHIP0402'     | ''          | ''            | ''        
 '12K'        | '1%'      | '1/16W'  | '0402LF'  | 'EMPTY'  | 'TMP_QCS31202FB15'(!)   = 'End of Design' | 'Comp-Approve'     | 'CS31202FB15'           | 'R0402'             | '(R0402-0201)'                 | '12K'     | '1%'    | '1/16W'  | 'IO'       | '12Kohm 0402'                                      | 'CHIP0402'     | ''          | ''            | ''        
 '68.1K'      | '1%'      | '1/4W'   | '1206LF'  | 'CHIP'   | 'TMP_QCS36816F200'(!)   = ''              | ''                 | 'CS36816F200'           | 'R1206'             | '(SMR1206AW)'                  | '68.1K'   | '1%'    | '1/4W'   | 'DISCRETE' | '68.1Kohm 1206'                                    | 'CHIP1206'     | ''          | ''            | ''        
 '68.1K'      | '1%'      | '1/4W'   | '1206LF'  | 'EMPTY'  | 'TMP_QCS36816F200'(!)   = ''              | ''                 | 'CS36816F200'           | 'R1206'             | '(SMR1206AW)'                  | '68.1K'   | '1%'    | '1/4W'   | 'IO'       | '68.1Kohm 1206'                                    | 'CHIP1206'     | ''          | ''            | ''        
 '1'          | '5%'      | '1/10W'  | '0603LF'  | 'CHIP'   | 'TMP_QCS-1003J913'(!)   = ''              | ''                 | 'CS-1003J913'           | 'R0603'             | '(SMR0603AW)'                  | '1'       | '5%'    | '1/10W'  | 'DISCRETE' | '1ohm 0603'                                        | 'CHIP0603'     | ''          | ''            | ''        
 '1'          | '5%'      | '1/10W'  | '0603LF'  | 'EMPTY'  | 'TMP_QCS-1003J913'(!)   = ''              | ''                 | 'CS-1003J913'           | 'R0603'             | '(SMR0603AW)'                  | '1'       | '5%'    | '1/10W'  | 'IO'       | '1ohm 0603'                                        | 'CHIP0603'     | ''          | ''            | ''        
 '10K'        | '1%'      | '1/4W'   | '1206LF'  | 'CHIP'   | 'TMP_QCS31006F200'(!)   = ''              | ''                 | 'CS31006F200'           | 'R1206'             | '(SMR1206AW)'                  | '10K'     | '1%'    | '1/4W'   | 'DISCRETE' | '10Kohm 1206'                                      | 'CHIP1206'     | ''          | ''            | ''        
 '10K'        | '1%'      | '1/4W'   | '1206LF'  | 'EMPTY'  | 'TMP_QCS31006F200'(!)   = ''              | ''                 | 'CS31006F200'           | 'R1206'             | '(SMR1206AW)'                  | '10K'     | '1%'    | '1/4W'   | 'IO'       | '10Kohm 1206'                                      | 'CHIP1206'     | ''          | ''            | ''        
 '8.66K'      | '1%'      | '1/4W'   | '1206LF'  | 'CHIP'   | 'TMP_QCS28666F200'(!)   = ''              | ''                 | 'CS28666F200'           | 'R1206'             | '(SMR1206AW)'                  | '8.66K'   | '1%'    | '1/4W'   | 'DISCRETE' | '8.66Kohm 1206'                                    | 'CHIP1206'     | ''          | ''            | ''        
 '8.66K'      | '1%'      | '1/4W'   | '1206LF'  | 'EMPTY'  | 'TMP_QCS28666F200'(!)   = ''              | ''                 | 'CS28666F200'           | 'R1206'             | '(SMR1206AW)'                  | '8.66K'   | '1%'    | '1/4W'   | 'IO'       | '8.66Kohm 1206'                                    | 'CHIP1206'     | ''          | ''            | ''        
 '7.15K'      | '1%'      | '1/4W'   | '1206LF'  | 'CHIP'   | 'TMP_QCS27156F200'(!)   = ''              | ''                 | 'CS27156F200'           | 'R1206'             | '(SMR1206AW)'                  | '7.15K'   | '1%'    | '1/4W'   | 'DISCRETE' | '7.15Kohm 1206'                                    | 'CHIP1206'     | ''          | ''            | ''        
 '7.15K'      | '1%'      | '1/4W'   | '1206LF'  | 'EMPTY'  | 'TMP_QCS27156F200'(!)   = ''              | ''                 | 'CS27156F200'           | 'R1206'             | '(SMR1206AW)'                  | '7.15K'   | '1%'    | '1/4W'   | 'IO'       | '7.15Kohm 1206'                                    | 'CHIP1206'     | ''          | ''            | ''        
 '2.15K'      | '1%'      | '1/4W'   | '1206LF'  | 'CHIP'   | 'TMP_QCS22156F200'(!)   = ''              | ''                 | 'CS22156F200'           | 'R1206'             | '(SMR1206AW)'                  | '2.15K'   | '1%'    | '1/4W'   | 'DISCRETE' | '2.15Kohm 1206'                                    | 'CHIP1206'     | ''          | ''            | ''        
 '2.15K'      | '1%'      | '1/4W'   | '1206LF'  | 'EMPTY'  | 'TMP_QCS22156F200'(!)   = ''              | ''                 | 'CS22156F200'           | 'R1206'             | '(SMR1206AW)'                  | '2.15K'   | '1%'    | '1/4W'   | 'IO'       | '2.15Kohm 1206'                                    | 'CHIP1206'     | ''          | ''            | ''        
 '4.32K'      | '1%'      | '1/4W'   | '1206LF'  | 'CHIP'   | 'TMP_QCS24326F200'(!)   = ''              | ''                 | 'CS24326F200'           | 'R1206'             | '(SMR1206AW)'                  | '4.32K'   | '1%'    | '1/4W'   | 'DISCRETE' | '4.32Kohm 1206'                                    | 'CHIP1206'     | ''          | ''            | ''        
 '4.32K'      | '1%'      | '1/4W'   | '1206LF'  | 'EMPTY'  | 'TMP_QCS24326F200'(!)   = ''              | ''                 | 'CS24326F200'           | 'R1206'             | '(SMR1206AW)'                  | '4.32K'   | '1%'    | '1/4W'   | 'IO'       | '4.32Kohm 1206'                                    | 'CHIP1206'     | ''          | ''            | ''        
 '5.9K'       | '1%'      | '1/4W'   | '1206LF'  | 'CHIP'   | 'TMP_QCS25906F200'(!)   = ''              | ''                 | 'CS25906F200'           | 'R1206'             | '(SMR1206AW)'                  | '5.9K'    | '1%'    | '1/4W'   | 'DISCRETE' | '5.9Kohm 1206'                                     | 'CHIP1206'     | ''          | ''            | ''        
 '5.9K'       | '1%'      | '1/4W'   | '1206LF'  | 'EMPTY'  | 'TMP_QCS25906F200'(!)   = ''              | ''                 | 'CS25906F200'           | 'R1206'             | '(SMR1206AW)'                  | '5.9K'    | '1%'    | '1/4W'   | 'IO'       | '5.9Kohm 1206'                                     | 'CHIP1206'     | ''          | ''            | ''        
 '243'        | '1%'      | '1/4W'   | '1206LF'  | 'CHIP'   | 'TMP_QCS12436F200'(!)   = ''              | ''                 | 'CS12436F200'           | 'R1206'             | '(SMR1206AW)'                  | '243'     | '1%'    | '1/4W'   | 'DISCRETE' | '243ohm 1206'                                      | 'CHIP1206'     | ''          | ''            | ''        
 '243'        | '1%'      | '1/4W'   | '1206LF'  | 'EMPTY'  | 'TMP_QCS12436F200'(!)   = ''              | ''                 | 'CS12436F200'           | 'R1206'             | '(SMR1206AW)'                  | '243'     | '1%'    | '1/4W'   | 'IO'       | '243ohm 1206'                                      | 'CHIP1206'     | ''          | ''            | ''        
 '0.020'      | '1%'      | '2W'     | '2512LF'  | 'CHIP'   | 'TMP_QCS+020AFR00'(!)   = ''              | ''                 | 'CS+020AFR00'           | 'R2512'             | '(SMR2512AW)'                  | '0.020'   | '1%'    | '2W'     | 'DISCRETE' | '0.020ohm 2512'                                    | 'CHIP2512'     | ''          | ''            | ''        
 '0.020'      | '1%'      | '2W'     | '2512LF'  | 'EMPTY'  | 'TMP_QCS+020AFR00'(!)   = ''              | ''                 | 'CS+020AFR00'           | 'R2512'             | '(SMR2512AW)'                  | '0.020'   | '1%'    | '2W'     | 'IO'       | '0.020ohm 2512'                                    | 'CHIP2512'     | ''          | ''            | ''        
 '8.2K'       | '1%'      | '1/4W'   | '1206LF'  | 'CHIP'   | 'TMP-C_T2I_0912_ALEX_2'(!) = ''              | ''                 | 'TMP-C_T2I_0912_ALEX_2' | 'R1206'             | '(SMR1206AW)'                  | '8.2K'    | '1%'    | '1/4W'   | 'DISCRETE' | '8.2Kohm 1206'                                     | 'CHIP1206'     | ''          | ''            | ''        
 '8.2K'       | '1%'      | '1/4W'   | '1206LF'  | 'EMPTY'  | 'TMP-C_T2I_0912_ALEX_2'(!) = ''              | ''                 | 'TMP-C_T2I_0912_ALEX_2' | 'R1206'             | '(SMR1206AW)'                  | '8.2K'    | '1%'    | '1/4W'   | 'IO'       | '8.2Kohm 1206'                                     | 'CHIP1206'     | ''          | ''            | ''        
 '48.7k'      | '1%'      | '1/4W'   | '1206LF'  | 'CHIP'   | 'TMP-C_T2I_0912_ALEX_3'(!) = ''              | ''                 | 'TMP-C_T2I_0912_ALEX_3' | 'R1206'             | '(SMR1206AW)'                  | '48.7k'   | '1%'    | '1/4W'   | 'DISCRETE' | '48.7kohm 1206'                                    | 'CHIP1206'     | ''          | ''            | ''        
 '48.7k'      | '1%'      | '1/4W'   | '1206LF'  | 'EMPTY'  | 'TMP-C_T2I_0912_ALEX_3'(!) = ''              | ''                 | 'TMP-C_T2I_0912_ALEX_3' | 'R1206'             | '(SMR1206AW)'                  | '48.7k'   | '1%'    | '1/4W'   | 'IO'       | '48.7kohm 1206'                                    | 'CHIP1206'     | ''          | ''            | ''        
 '3.4K'       | '1%'      | '1/4W'   | '1206LF'  | 'CHIP'   | 'TMP-C_T2I_0912_ALEX_4'(!) = ''              | ''                 | 'TMP-C_T2I_0912_ALEX_4' | 'R1206'             | '(SMR1206AW)'                  | '3.4K'    | '1%'    | '1/4W'   | 'DISCRETE' | '3.4Kohm 1206'                                     | 'CHIP1206'     | ''          | ''            | ''        
 '3.4K'       | '1%'      | '1/4W'   | '1206LF'  | 'EMPTY'  | 'TMP-C_T2I_0912_ALEX_4'(!) = ''              | ''                 | 'TMP-C_T2I_0912_ALEX_4' | 'R1206'             | '(SMR1206AW)'                  | '3.4K'    | '1%'    | '1/4W'   | 'IO'       | '3.4Kohm 1206'                                     | 'CHIP1206'     | ''          | ''            | ''        
 '3.3K'       | '1%'      | '1/4W'   | '1206LF'  | 'CHIP'   | 'TMP-C_T2I_0912_ALEX_5'(!) = ''              | ''                 | 'TMP-C_T2I_0912_ALEX_5' | 'R1206'             | '(SMR1206AW)'                  | '3.3K'    | '1%'    | '1/4W'   | 'DISCRETE' | '3.3Kohm 1206'                                     | 'CHIP1206'     | ''          | ''            | ''        
 '3.3K'       | '1%'      | '1/4W'   | '1206LF'  | 'EMPTY'  | 'TMP-C_T2I_0912_ALEX_5'(!) = ''              | ''                 | 'TMP-C_T2I_0912_ALEX_5' | 'R1206'             | '(SMR1206AW)'                  | '3.3K'    | '1%'    | '1/4W'   | 'IO'       | '3.3Kohm 1206'                                     | 'CHIP1206'     | ''          | ''            | ''        
 '6.65K'      | '1%'      | '1/4W'   | '1206LF'  | 'CHIP'   | 'TMP-C_T2I_0912_ALEX_6'(!) = ''              | ''                 | 'TMP-C_T2I_0912_ALEX_6' | 'R1206'             | '(SMR1206AW)'                  | '6.65K'   | '1%'    | '1/4W'   | 'DISCRETE' | '6.65Kohm 1206'                                    | 'CHIP1206'     | ''          | ''            | ''        
 '6.65K'      | '1%'      | '1/4W'   | '1206LF'  | 'EMPTY'  | 'TMP-C_T2I_0912_ALEX_6'(!) = ''              | ''                 | 'TMP-C_T2I_0912_ALEX_6' | 'R1206'             | '(SMR1206AW)'                  | '6.65K'   | '1%'    | '1/4W'   | 'IO'       | '6.65Kohm 1206'                                    | 'CHIP1206'     | ''          | ''            | ''        
 '2K'         | '1%'      | '1/4W'   | '1206LF'  | 'CHIP'   | 'TMP_QCS22006F200'(!)   = ''              | ''                 | 'CS22006F200'           | 'R1206'             | '(SMR1206AW)'                  | '2K'      | '1%'    | '1/4W'   | 'DISCRETE' | '2Kohm 1206'                                       | 'CHIP1206'     | ''          | ''            | ''        
 '2K'         | '1%'      | '1/4W'   | '1206LF'  | 'EMPTY'  | 'TMP_QCS22006F200'(!)   = ''              | ''                 | 'CS22006F200'           | 'R1206'             | '(SMR1206AW)'                  | '2K'      | '1%'    | '1/4W'   | 'IO'       | '2Kohm 1206'                                       | 'CHIP1206'     | ''          | ''            | ''        
 '27'         | '1%'      | '1/4W'   | '1206LF'  | 'CHIP'   | 'TMP_QCS02706F200'(!)   = 'End of Design' | 'Comp-Approve'     | 'CS02706F200'           | 'R1206'             | '(SMR1206AW)'                  | '27'      | '1%'    | '1/4W'   | 'DISCRETE' | '27ohm 1206'                                       | 'CHIP1206'     | ''          | ''            | ''        
 '27'         | '1%'      | '1/4W'   | '1206LF'  | 'EMPTY'  | 'TMP_QCS02706F200'(!)   = 'End of Design' | 'Comp-Approve'     | 'CS02706F200'           | 'R1206'             | '(SMR1206AW)'                  | '27'      | '1%'    | '1/4W'   | 'IO'       | '27ohm 1206'                                       | 'CHIP1206'     | ''          | ''            | ''        
 '4.99K'      | '1%'      | '1/4W'   | '1206LF'  | 'CHIP'   | 'TMP_QCS24996F210'(!)   = ''              | ''                 | 'CS24996F210'           | 'R1206'             | '(SMR1206AW)'                  | '4.99K'   | '1%'    | '1/4W'   | 'DISCRETE' | '4.99Kohm 1206'                                    | 'CHIP1206'     | ''          | ''            | ''        
 '4.99K'      | '1%'      | '1/4W'   | '1206LF'  | 'EMPTY'  | 'TMP_QCS24996F210'(!)   = ''              | ''                 | 'CS24996F210'           | 'R1206'             | '(SMR1206AW)'                  | '4.99K'   | '1%'    | '1/4W'   | 'IO'       | '4.99Kohm 1206'                                    | 'CHIP1206'     | ''          | ''            | ''        
 '3.24K'      | '1%'      | '1/4W'   | '1206LF'  | 'CHIP'   | 'TMP_QCS23246F200'(!)   = ''              | ''                 | 'CS23246F200'           | 'R1206'             | '(SMR1206AW)'                  | '3.24K'   | '1%'    | '1/4W'   | 'DISCRETE' | '3.24Kohm 1206'                                    | 'CHIP1206'     | ''          | ''            | ''        
 '3.24K'      | '1%'      | '1/4W'   | '1206LF'  | 'EMPTY'  | 'TMP_QCS23246F200'(!)   = ''              | ''                 | 'CS23246F200'           | 'R1206'             | '(SMR1206AW)'                  | '3.24K'   | '1%'    | '1/4W'   | 'IO'       | '3.24Kohm 1206'                                    | 'CHIP1206'     | ''          | ''            | ''        
 '301K'       | '1%'      | '1/4W'   | '1206LF'  | 'CHIP'   | 'TMP_QCS43016F200'(!)   = ''              | ''                 | 'CS43016F200'           | 'R1206'             | '(SMR1206AW)'                  | '301K'    | '1%'    | '1/4W'   | 'DISCRETE' | '301Kohm 1206'                                     | 'CHIP1206'     | ''          | ''            | ''        
 '301K'       | '1%'      | '1/4W'   | '1206LF'  | 'EMPTY'  | 'TMP_QCS43016F200'(!)   = ''              | ''                 | 'CS43016F200'           | 'R1206'             | '(SMR1206AW)'                  | '301K'    | '1%'    | '1/4W'   | 'IO'       | '301Kohm 1206'                                     | 'CHIP1206'     | ''          | ''            | ''        
 '1K'         | '0.1%'    | '1/8W'   | '1206LF'  | 'CHIP'   | 'TMP_QCS21004B200'(!)   = ''              | ''                 | 'CS21004B200'           | 'R1206'             | '(SMR1206AW)'                  | '1K'      | '0.1%'  | '1/8W'   | 'DISCRETE' | '1Kohm 1206'                                       | 'CHIP1206'     | ''          | ''            | ''        
 '1K'         | '0.1%'    | '1/8W'   | '1206LF'  | 'EMPTY'  | 'TMP_QCS21004B200'(!)   = ''              | ''                 | 'CS21004B200'           | 'R1206'             | '(SMR1206AW)'                  | '1K'      | '0.1%'  | '1/8W'   | 'IO'       | '1Kohm 1206'                                       | 'CHIP1206'     | ''          | ''            | ''        
 '2K'         | '0.1%'    | '1/8W'   | '1206LF'  | 'CHIP'   | 'TMP_QCS22004B200'(!)   = ''              | ''                 | 'CS22004B200'           | 'R1206'             | '(SMR1206AW)'                  | '2K'      | '0.1%'  | '1/8W'   | 'DISCRETE' | '2Kohm 1206'                                       | 'CHIP1206'     | ''          | ''            | ''        
 '2K'         | '0.1%'    | '1/8W'   | '1206LF'  | 'EMPTY'  | 'TMP_QCS22004B200'(!)   = ''              | ''                 | 'CS22004B200'           | 'R1206'             | '(SMR1206AW)'                  | '2K'      | '0.1%'  | '1/8W'   | 'IO'       | '2Kohm 1206'                                       | 'CHIP1206'     | ''          | ''            | ''        
 '49.9K'      | '1%'      | '1/4W'   | '1206LF'  | 'CHIP'   | 'TMP_QCS34996F200'(!)   = ''              | ''                 | 'CS34996F200'           | 'R1206'             | '(SMR1206AW)'                  | '49.9K'   | '1%'    | '1/4W'   | 'DISCRETE' | '49.9Kohm 1206'                                    | 'CHIP1206'     | ''          | ''            | ''        
 '49.9K'      | '1%'      | '1/4W'   | '1206LF'  | 'EMPTY'  | 'TMP_QCS34996F200'(!)   = ''              | ''                 | 'CS34996F200'           | 'R1206'             | '(SMR1206AW)'                  | '49.9K'   | '1%'    | '1/4W'   | 'IO'       | '49.9Kohm 1206'                                    | 'CHIP1206'     | ''          | ''            | ''        
 '100K'       | '1%'      | '1/4W'   | '1206LF'  | 'CHIP'   | 'TMP_QCS41006F200'(!)   = ''              | ''                 | 'CS41006F200'           | 'R1206'             | '(SMR1206AW)'                  | '100K'    | '1%'    | '1/4W'   | 'DISCRETE' | '100Kohm 1206'                                     | 'CHIP1206'     | ''          | ''            | ''        
 '100K'       | '1%'      | '1/4W'   | '1206LF'  | 'EMPTY'  | 'TMP_QCS41006F200'(!)   = ''              | ''                 | 'CS41006F200'           | 'R1206'             | '(SMR1206AW)'                  | '100K'    | '1%'    | '1/4W'   | 'IO'       | '100Kohm 1206'                                     | 'CHIP1206'     | ''          | ''            | ''        
 '1.2M'       | '1%'      | '1/4W'   | '1206LF'  | 'CHIP'   | 'TMP_QCS51206F200'(!)   = ''              | ''                 | 'CS51206F200'           | 'R1206'             | '(SMR1206AW)'                  | '1.2M'    | '1%'    | '1/4W'   | 'DISCRETE' | '1.2Mohm 1206'                                     | 'CHIP1206'     | ''          | ''            | ''        
 '1.2M'       | '1%'      | '1/4W'   | '1206LF'  | 'EMPTY'  | 'TMP_QCS51206F200'(!)   = ''              | ''                 | 'CS51206F200'           | 'R1206'             | '(SMR1206AW)'                  | '1.2M'    | '1%'    | '1/4W'   | 'IO'       | '1.2Mohm 1206'                                     | 'CHIP1206'     | ''          | ''            | ''        
 '1.54K'      | '0.1%'    | '1/8W'   | '1206LF'  | 'CHIP'   | 'TMP_QCS21544B200'(!)   = ''              | ''                 | 'CS21544B200'           | 'R1206'             | '(SMR1206AW)'                  | '1.54K'   | '0.1%'  | '1/8W'   | 'DISCRETE' | '1.54Kohm 1206'                                    | 'CHIP1206'     | ''          | ''            | ''        
 '1.54K'      | '0.1%'    | '1/8W'   | '1206LF'  | 'EMPTY'  | 'TMP_QCS21544B200'(!)   = ''              | ''                 | 'CS21544B200'           | 'R1206'             | '(SMR1206AW)'                  | '1.54K'   | '0.1%'  | '1/8W'   | 'IO'       | '1.54Kohm 1206'                                    | 'CHIP1206'     | ''          | ''            | ''        
 '3.16K'      | '0.1%'    | '1/8W'   | '1206LF'  | 'CHIP'   | 'TMP_QCS23164B200'(!)   = ''              | ''                 | 'CS23164B200'           | 'R1206'             | '(SMR1206AW)'                  | '3.16K'   | '0.1%'  | '1/8W'   | 'DISCRETE' | '3.16Kohm 1206'                                    | 'CHIP1206'     | ''          | ''            | ''        
 '3.16K'      | '0.1%'    | '1/8W'   | '1206LF'  | 'EMPTY'  | 'TMP_QCS23164B200'(!)   = ''              | ''                 | 'CS23164B200'           | 'R1206'             | '(SMR1206AW)'                  | '3.16K'   | '0.1%'  | '1/8W'   | 'IO'       | '3.16Kohm 1206'                                    | 'CHIP1206'     | ''          | ''            | ''        
 '10K'        | '0.1%'    | '1/8W'   | '1206LF'  | 'CHIP'   | 'TMP_QCS31004B200'(!)   = ''              | ''                 | 'CS31004B200'           | 'R1206'             | '(SMR1206AW)'                  | '10K'     | '0.1%'  | '1/8W'   | 'DISCRETE' | '10Kohm 1206'                                      | 'CHIP1206'     | ''          | ''            | ''        
 '10K'        | '0.1%'    | '1/8W'   | '1206LF'  | 'EMPTY'  | 'TMP_QCS31004B200'(!)   = ''              | ''                 | 'CS31004B200'           | 'R1206'             | '(SMR1206AW)'                  | '10K'     | '0.1%'  | '1/8W'   | 'IO'       | '10Kohm 1206'                                      | 'CHIP1206'     | ''          | ''            | ''        
 '0.5'        | '1%'      | '1W'     | '2512LF'  | 'CHIP'   | 'TMP_QCS+5008FR00'(!)   = ''              | ''                 | 'CS+5008FR00'           | 'R2512'             | '(SMR2512AW)'                  | '0.5'     | '1%'    | '1W'     | 'DISCRETE' | '0.5ohm 2512'                                      | 'CHIP2512'     | ''          | ''            | ''        
 '0.5'        | '1%'      | '1W'     | '2512LF'  | 'EMPTY'  | 'TMP_QCS+5008FR00'(!)   = ''              | ''                 | 'CS+5008FR00'           | 'R2512'             | '(SMR2512AW)'                  | '0.5'     | '1%'    | '1W'     | 'IO'       | '0.5ohm 2512'                                      | 'CHIP2512'     | ''          | ''            | ''        
 '255'        | '1%'      | '1/4W'   | '1206LF'  | 'CHIP'   | 'TMP_QCS12556F200'(!)   = ''              | ''                 | 'CS12556F200'           | 'R1206'             | '(SMR1206AW)'                  | '255'     | '1%'    | '1/4W'   | 'DISCRETE' | '255ohm 1206'                                      | 'CHIP1206'     | ''          | ''            | ''        
 '255'        | '1%'      | '1/4W'   | '1206LF'  | 'EMPTY'  | 'TMP_QCS12556F200'(!)   = ''              | ''                 | 'CS12556F200'           | 'R1206'             | '(SMR1206AW)'                  | '255'     | '1%'    | '1/4W'   | 'IO'       | '255ohm 1206'                                      | 'CHIP1206'     | ''          | ''            | ''        
 '4.53K'      | '1%'      | '1/4W'   | '1206LF'  | 'CHIP'   | 'TMP_QCS24536F200'(!)   = ''              | ''                 | 'CS24536F200'           | 'R1206'             | '(SMR1206AW)'                  | '4.53K'   | '1%'    | '1/4W'   | 'DISCRETE' | '4.53Kohm 1206'                                    | 'CHIP1206'     | ''          | ''            | ''        
 '4.53K'      | '1%'      | '1/4W'   | '1206LF'  | 'EMPTY'  | 'TMP_QCS24536F200'(!)   = ''              | ''                 | 'CS24536F200'           | 'R1206'             | '(SMR1206AW)'                  | '4.53K'   | '1%'    | '1/4W'   | 'IO'       | '4.53Kohm 1206'                                    | 'CHIP1206'     | ''          | ''            | ''        
 '130'        | '1%'      | '1/4W'   | '1206LF'  | 'CHIP'   | 'TMP_QCS11306F200'(!)   = ''              | ''                 | 'CS11306F200'           | 'R1206'             | '(SMR1206AW)'                  | '130'     | '1%'    | '1/4W'   | 'DISCRETE' | '130ohm 1206'                                      | 'CHIP1206'     | ''          | ''            | ''        
 '130'        | '1%'      | '1/4W'   | '1206LF'  | 'EMPTY'  | 'TMP_QCS11306F200'(!)   = ''              | ''                 | 'CS11306F200'           | 'R1206'             | '(SMR1206AW)'                  | '130'     | '1%'    | '1/4W'   | 'IO'       | '130ohm 1206'                                      | 'CHIP1206'     | ''          | ''            | ''        
 '261'        | '1%'      | '1/4W'   | '1206LF'  | 'CHIP'   | 'TMP_QCS12616F200'(!)   = ''              | ''                 | 'CS12616F200'           | 'R1206'             | '(SMR1206AW)'                  | '261'     | '1%'    | '1/4W'   | 'DISCRETE' | '261ohm 1206'                                      | 'CHIP1206'     | ''          | ''            | ''        
 '261'        | '1%'      | '1/4W'   | '1206LF'  | 'EMPTY'  | 'TMP_QCS12616F200'(!)   = ''              | ''                 | 'CS12616F200'           | 'R1206'             | '(SMR1206AW)'                  | '261'     | '1%'    | '1/4W'   | 'IO'       | '261ohm 1206'                                      | 'CHIP1206'     | ''          | ''            | ''        
 '1K'         | '1%'      | '1/4W'   | '1206LF'  | 'CHIP'   | 'TMP_QCS21006F200'(!)   = ''              | ''                 | 'CS21006F200'           | 'R1206'             | '(SMR1206AW)'                  | '1K'      | '1%'    | '1/4W'   | 'DISCRETE' | '1Kohm 1206'                                       | 'CHIP1206'     | ''          | ''            | ''        
 '1K'         | '1%'      | '1/4W'   | '1206LF'  | 'EMPTY'  | 'TMP_QCS21006F200'(!)   = ''              | ''                 | 'CS21006F200'           | 'R1206'             | '(SMR1206AW)'                  | '1K'      | '1%'    | '1/4W'   | 'IO'       | '1Kohm 1206'                                       | 'CHIP1206'     | ''          | ''            | ''        
 '2.2'        | '1%'      | '1/4W'   | '1206LF'  | 'CHIP'   | 'TMP_QCS-2206F200'(!)   = ''              | ''                 | 'CS-2206F200'           | 'R1206'             | '(SMR1206AW)'                  | '2.2'     | '1%'    | '1/4W'   | 'DISCRETE' | '2.2ohm 1206'                                      | 'CHIP1206'     | ''          | ''            | ''        
 '2.2'        | '1%'      | '1/4W'   | '1206LF'  | 'EMPTY'  | 'TMP_QCS-2206F200'(!)   = ''              | ''                 | 'CS-2206F200'           | 'R1206'             | '(SMR1206AW)'                  | '2.2'     | '1%'    | '1/4W'   | 'IO'       | '2.2ohm 1206'                                      | 'CHIP1206'     | ''          | ''            | ''        
 '732'        | '1%'      | '1/4W'   | '1206LF'  | 'CHIP'   | 'TMP_QCS17326F200'(!)   = ''              | ''                 | 'CS17326F200'           | 'R1206'             | '(SMR1206AW)'                  | '732'     | '1%'    | '1/4W'   | 'DISCRETE' | '732ohm 1206'                                      | 'CHIP1206'     | ''          | ''            | ''        
 '732'        | '1%'      | '1/4W'   | '1206LF'  | 'EMPTY'  | 'TMP_QCS17326F200'(!)   = ''              | ''                 | 'CS17326F200'           | 'R1206'             | '(SMR1206AW)'                  | '732'     | '1%'    | '1/4W'   | 'IO'       | '732ohm 1206'                                      | 'CHIP1206'     | ''          | ''            | ''        
 '143K'       | '1%'      | '1/16W'  | '0402LF'  | 'CHIP'   | 'TMP_QCS41432FB18'(!)   = 'End of Design' | 'Comp-Approve'     | 'CS41432FB18'           | 'R0402'             | '(R0402-0201)'                 | '143K'    | '1%'    | '1/16W'  | 'DISCRETE' | '143Kohm 0402'                                     | 'CHIP0402'     | ''          | ''            | ''        
 '143K'       | '1%'      | '1/16W'  | '0402LF'  | 'EMPTY'  | 'TMP_QCS41432FB18'(!)   = 'End of Design' | 'Comp-Approve'     | 'CS41432FB18'           | 'R0402'             | '(R0402-0201)'                 | '143K'    | '1%'    | '1/16W'  | 'IO'       | '143Kohm 0402'                                     | 'CHIP0402'     | ''          | ''            | ''        
 '255'        | '1%'      | '1/2W'   | '1206LF'  | 'CHIP'   | 'TMP_QCS12557F200'(!)   = ''              | ''                 | 'CS12557F200'           | 'R1206'             | '(SMR1206AW)'                  | '255'     | '1%'    | '1/2W'   | 'DISCRETE' | '255ohm 1206'                                      | 'CHIP1206'     | ''          | ''            | ''        
 '255'        | '1%'      | '1/2W'   | '1206LF'  | 'EMPTY'  | 'TMP_QCS12557F200'(!)   = ''              | ''                 | 'CS12557F200'           | 'R1206'             | '(SMR1206AW)'                  | '255'     | '1%'    | '1/2W'   | 'IO'       | '255ohm 1206'                                      | 'CHIP1206'     | ''          | ''            | ''        
 '100'        | '1%'      | '1/2W'   | '1206LF'  | 'CHIP'   | 'TMP_QCS11007F200'(!)   = ''              | ''                 | 'CS11007F200'           | 'R1206XI'           | '(SMR1206AW)'                  | '100'     | '1%'    | '1/2W'   | 'DISCRETE' | 'RES CHIP 100 1/2W +-1%(1206)'                     | 'CHIP1206'     | ''          | ''            | '20221027'
 '100'        | '1%'      | '1/2W'   | '1206LF'  | 'EMPTY'  | 'TMP_QCS11007F200'(!)   = ''              | ''                 | 'CS11007F200'           | 'R1206XI'           | '(SMR1206AW)'                  | '100'     | '1%'    | '1/2W'   | 'IO'       | 'RES CHIP 100 1/2W +-1%(1206)'                     | 'CHIP1206'     | ''          | ''            | '20221027'
 '18'         | '1%'      | '1/4W'   | '0805LF'  | 'CHIP'   | 'TMP_QCS01806FA00'(!)   = ''              | ''                 | 'CS01806FA00'           | 'R0805'             | '(SMR0805AW)'                  | '18'      | '1%'    | '1/4W'   | 'DISCRETE' | '18ohm 0805'                                       | 'CHIP0805'     | ''          | ''            | ''        
 '18'         | '1%'      | '1/4W'   | '0805LF'  | 'EMPTY'  | 'TMP_QCS01806FA00'(!)   = ''              | ''                 | 'CS01806FA00'           | 'R0805'             | '(SMR0805AW)'                  | '18'      | '1%'    | '1/4W'   | 'IO'       | '18ohm 0805'                                       | 'CHIP0805'     | ''          | ''            | ''        
 '820'        | '1%'      | '1/4W'   | '0805LF'  | 'CHIP'   | 'TMP_QCS18206FA00'(!)   = ''              | ''                 | 'CS18206FA00'           | 'R0805'             | '(SMR0805AW)'                  | '820'     | '1%'    | '1/4W'   | 'DISCRETE' | '820ohm 0805'                                      | 'CHIP0805'     | ''          | ''            | ''        
 '820'        | '1%'      | '1/4W'   | '0805LF'  | 'EMPTY'  | 'TMP_QCS18206FA00'(!)   = ''              | ''                 | 'CS18206FA00'           | 'R0805'             | '(SMR0805AW)'                  | '820'     | '1%'    | '1/4W'   | 'IO'       | '820ohm 0805'                                      | 'CHIP0805'     | ''          | ''            | ''        
 '10K'        | '5%'      | '1/10W'  | '0603'    | 'CHIP'   | 'TMP_QCS31003J941'(!)   = ''              | ''                 | 'CS31003J941'           | 'R0603'             | '(SMR0603AW)'                  | '10K'     | '5%'    | '1/10W'  | 'DISCRETE' | '10Kohm 0603'                                      | 'CHIP0603'     | ''          | ''            | ''        
 '10K'        | '5%'      | '1/10W'  | '0603'    | 'EMPTY'  | 'TMP_QCS31003J941'(!)   = ''              | ''                 | 'CS31003J941'           | 'R0603'             | '(SMR0603AW)'                  | '10K'     | '5%'    | '1/10W'  | 'IO'       | '10Kohm 0603'                                      | 'CHIP0603'     | ''          | ''            | ''        
 '243'        | '1%'      | '1/10W'  | '0603'    | 'CHIP'   | 'TMP_QCS12433F900'(!)   = ''              | ''                 | 'CS12433F900'           | 'R0603'             | '(SMR0603AW)'                  | '243'     | '1%'    | '1/10W'  | 'DISCRETE' | '243ohm 0603'                                      | 'CHIP0603'     | ''          | ''            | ''        
 '243'        | '1%'      | '1/10W'  | '0603'    | 'EMPTY'  | 'TMP_QCS12433F900'(!)   = ''              | ''                 | 'CS12433F900'           | 'R0603'             | '(SMR0603AW)'                  | '243'     | '1%'    | '1/10W'  | 'IO'       | '243ohm 0603'                                      | 'CHIP0603'     | ''          | ''            | ''        
 '69.8'       | '1%'      | '1/10W'  | '0603'    | 'CHIP'   | 'TMP_QCS06983F911'(!)   = ''              | ''                 | 'CS06983F911'           | 'R0603'             | '(SMR0603AW)'                  | '69.8'    | '1%'    | '1/10W'  | 'DISCRETE' | '69.8ohm 0603'                                     | 'CHIP0603'     | ''          | ''            | ''        
 '69.8'       | '1%'      | '1/10W'  | '0603'    | 'EMPTY'  | 'TMP_QCS06983F911'(!)   = ''              | ''                 | 'CS06983F911'           | 'R0603'             | '(SMR0603AW)'                  | '69.8'    | '1%'    | '1/10W'  | 'IO'       | '69.8ohm 0603'                                     | 'CHIP0603'     | ''          | ''            | ''        
 '10'         | '1%'      | '1/4W'   | '1206LF'  | 'CHIP'   | 'TMP_QCS01006F214'(!)   = ''              | ''                 | 'CS01006F214'           | 'R1206'             | '(SMR1206AW)'                  | '10'      | '1%'    | '1/4W'   | 'DISCRETE' | '10ohm 1206'                                       | 'CHIP1206'     | ''          | ''            | ''        
 '10'         | '1%'      | '1/4W'   | '1206LF'  | 'EMPTY'  | 'TMP_QCS01006F214'(!)   = ''              | ''                 | 'CS01006F214'           | 'R1206'             | '(SMR1206AW)'                  | '10'      | '1%'    | '1/4W'   | 'IO'       | '10ohm 1206'                                       | 'CHIP1206'     | ''          | ''            | ''        
 '0.05'       | '1%'      | '1W'     | '2512LF'  | 'CHIP'   | 'TMP_QCS+0508FR00'(!)   = ''              | ''                 | 'CS+0508FR00'           | 'R2512'             | '(SMR2512AW)'                  | '0.05'    | '1%'    | '1W'     | 'DISCRETE' | '0.05ohm 2512'                                     | 'CHIP2512'     | ''          | ''            | ''        
 '0.05'       | '1%'      | '1W'     | '2512LF'  | 'EMPTY'  | 'TMP_QCS+0508FR00'(!)   = ''              | ''                 | 'CS+0508FR00'           | 'R2512'             | '(SMR2512AW)'                  | '0.05'    | '1%'    | '1W'     | 'IO'       | '0.05ohm 2512'                                     | 'CHIP2512'     | ''          | ''            | ''        
 '0.3'        | '1%'      | '1W'     | '2512LF'  | 'CHIP'   | 'TMP_QCS+3008FR00'(!)   = ''              | ''                 | 'CS+3008FR00'           | 'R2512'             | '(SMR2512AW)'                  | '0.3'     | '1%'    | '1W'     | 'DISCRETE' | '0.3ohm 2512'                                      | 'CHIP2512'     | ''          | ''            | ''        
 '0.3'        | '1%'      | '1W'     | '2512LF'  | 'EMPTY'  | 'TMP_QCS+3008FR00'(!)   = ''              | ''                 | 'CS+3008FR00'           | 'R2512'             | '(SMR2512AW)'                  | '0.3'     | '1%'    | '1W'     | 'IO'       | '0.3ohm 2512'                                      | 'CHIP2512'     | ''          | ''            | ''        
 '110'        | '1%'      | '1/16W'  | '0402LF'  | 'CHIP'   | 'TMP_QCS11102FB18'(!)   = 'End of Design' | 'Comp-Approve'     | 'CS11102FB18'           | 'R0402'             | '(R0402-0201)'                 | '110'     | '1%'    | '1/16W'  | 'DISCRETE' | '110ohm 0402'                                      | 'CHIP0402'     | ''          | ''            | ''        
 '110'        | '1%'      | '1/16W'  | '0402LF'  | 'EMPTY'  | 'TMP_QCS11102FB18'(!)   = 'End of Design' | 'Comp-Approve'     | 'CS11102FB18'           | 'R0402'             | '(R0402-0201)'                 | '110'     | '1%'    | '1/16W'  | 'IO'       | '110ohm 0402'                                      | 'CHIP0402'     | ''          | ''            | ''        
 '4.02K'      | '1%'      | '1/16W'  | '0402LF'  | 'CHIP'   | 'TMP_QCS24022FB13'(!)   = 'End of Design' | 'Comp-Approve'     | 'CS24022FB13'           | 'R0402'             | '(R0402-0201)'                 | '4.02K'   | '1%'    | '1/16W'  | 'DISCRETE' | '4.02Kohm 0402'                                    | 'CHIP0402'     | ''          | ''            | ''        
 '4.02K'      | '1%'      | '1/16W'  | '0402LF'  | 'EMPTY'  | 'TMP_QCS24022FB13'(!)   = 'End of Design' | 'Comp-Approve'     | 'CS24022FB13'           | 'R0402'             | '(R0402-0201)'                 | '4.02K'   | '1%'    | '1/16W'  | 'IO'       | '4.02Kohm 0402'                                    | 'CHIP0402'     | ''          | ''            | ''        
 '8.06K'      | '1%'      | '1/16W'  | '0402LF'  | 'CHIP'   | 'TMP_QCS28062FB21'(!)   = 'End of Design' | 'Comp-Approve'     | 'CS28062FB21'           | 'R0402'             | '(R0402-0201)'                 | '8.06K'   | '1%'    | '1/16W'  | 'DISCRETE' | '8.06Kohm 0402'                                    | 'CHIP0402'     | ''          | ''            | ''        
 '8.06K'      | '1%'      | '1/16W'  | '0402LF'  | 'EMPTY'  | 'TMP_QCS28062FB21'(!)   = 'End of Design' | 'Comp-Approve'     | 'CS28062FB21'           | 'R0402'             | '(R0402-0201)'                 | '8.06K'   | '1%'    | '1/16W'  | 'IO'       | '8.06Kohm 0402'                                    | 'CHIP0402'     | ''          | ''            | ''        
 '2.49K'      | '1%'      | '1/16W'  | '0402LF'  | 'CHIP'   | 'TMP_QCS22492FB22'(!)   = 'End of Design' | 'Comp-Approve'     | 'CS22492FB22'           | 'R0402'             | '(R0402-0201)'                 | '2.49K'   | '1%'    | '1/16W'  | 'DISCRETE' | '2.49Kohm 0402'                                    | 'CHIP0402'     | ''          | ''            | ''        
 '2.49K'      | '1%'      | '1/16W'  | '0402LF'  | 'EMPTY'  | 'TMP_QCS22492FB22'(!)   = 'End of Design' | 'Comp-Approve'     | 'CS22492FB22'           | 'R0402'             | '(R0402-0201)'                 | '2.49K'   | '1%'    | '1/16W'  | 'IO'       | '2.49Kohm 0402'                                    | 'CHIP0402'     | ''          | ''            | ''        
 '11K'        | '1%'      | '1/16W'  | '0402LF'  | 'CHIP'   | 'TMP_QCS31102FB11'(!)   = 'End of Design' | 'Comp-Approve'     | 'CS31102FB11'           | 'R0402'             | '(R0402-0201)'                 | '11K'     | '1%'    | '1/16W'  | 'DISCRETE' | '11Kohm 0402'                                      | 'CHIP0402'     | ''          | ''            | ''        
 '11K'        | '1%'      | '1/16W'  | '0402LF'  | 'EMPTY'  | 'TMP_QCS31102FB11'(!)   = 'End of Design' | 'Comp-Approve'     | 'CS31102FB11'           | 'R0402'             | '(R0402-0201)'                 | '11K'     | '1%'    | '1/16W'  | 'IO'       | '11Kohm 0402'                                      | 'CHIP0402'     | ''          | ''            | ''        
 '10.7K'      | '0.1%'    | '1/4W'   | '1206LF'  | 'CHIP'   | 'TMP_QCS31076B200'(!)   = ''              | ''                 | 'CS31076B200'           | 'R1206'             | '(SMR1206AW)'                  | '10.7K'   | '0.1%'  | '1/4W'   | 'DISCRETE' | '10.7Kohm 1206'                                    | 'CHIP1206'     | ''          | ''            | ''        
 '10.7K'      | '0.1%'    | '1/4W'   | '1206LF'  | 'EMPTY'  | 'TMP_QCS31076B200'(!)   = ''              | ''                 | 'CS31076B200'           | 'R1206'             | '(SMR1206AW)'                  | '10.7K'   | '0.1%'  | '1/4W'   | 'IO'       | '10.7Kohm 1206'                                    | 'CHIP1206'     | ''          | ''            | ''        
 '56.2K'      | '0.1%'    | '1/4W'   | '1206LF'  | 'CHIP'   | 'TMP_QCS35626B200'(!)   = ''              | ''                 | 'CS35626B200'           | 'R1206'             | '(SMR1206AW)'                  | '56.2K'   | '0.1%'  | '1/4W'   | 'DISCRETE' | '56.2Kohm 1206'                                    | 'CHIP1206'     | ''          | ''            | ''        
 '56.2K'      | '0.1%'    | '1/4W'   | '1206LF'  | 'EMPTY'  | 'TMP_QCS35626B200'(!)   = ''              | ''                 | 'CS35626B200'           | 'R1206'             | '(SMR1206AW)'                  | '56.2K'   | '0.1%'  | '1/4W'   | 'IO'       | '56.2Kohm 1206'                                    | 'CHIP1206'     | ''          | ''            | ''        
 '80.6K'      | '0.1%'    | '1/4W'   | '1206LF'  | 'CHIP'   | 'TMP_QCS38066B200'(!)   = ''              | ''                 | 'CS38066B200'           | 'R1206'             | '(SMR1206AW)'                  | '80.6K'   | '0.1%'  | '1/4W'   | 'DISCRETE' | '80.6Kohm 1206'                                    | 'CHIP1206'     | ''          | ''            | ''        
 '80.6K'      | '0.1%'    | '1/4W'   | '1206LF'  | 'EMPTY'  | 'TMP_QCS38066B200'(!)   = ''              | ''                 | 'CS38066B200'           | 'R1206'             | '(SMR1206AW)'                  | '80.6K'   | '0.1%'  | '1/4W'   | 'IO'       | '80.6Kohm 1206'                                    | 'CHIP1206'     | ''          | ''            | ''        
 '0.001'      | '0.1%'    | '1W'     | '2512LF'  | 'CHIP'   | 'TMP_QCS+0018BR00'(!)   = 'End of Design' | 'Comp-Release Qty' | 'CS+0018BR00'           | 'R2512'             | '(SMR2512AW)'                  | '0.001'   | '0.1%'  | '1W'     | 'DISCRETE' | '0.001ohm 2512'                                    | 'CHIP2512'     | ''          | ''            | ''        
 '0.001'      | '0.1%'    | '1W'     | '2512LF'  | 'EMPTY'  | 'TMP_QCS+0018BR00'(!)   = 'End of Design' | 'Comp-Release Qty' | 'CS+0018BR00'           | 'R2512'             | '(SMR2512AW)'                  | '0.001'   | '0.1%'  | '1W'     | 'IO'       | '0.001ohm 2512'                                    | 'CHIP2512'     | ''          | ''            | ''        
 '0.2'        | '0.1%'    | '1W'     | '2512LF'  | 'CHIP'   | 'TMP_QCS+2008BR00'(!)   = ''              | ''                 | 'CS+2008BR00'           | 'R2512'             | '(SMR2512AW)'                  | '0.2'     | '0.1%'  | '1W'     | 'DISCRETE' | '0.2ohm 2512'                                      | 'CHIP2512'     | ''          | ''            | ''        
 '0.2'        | '0.1%'    | '1W'     | '2512LF'  | 'EMPTY'  | 'TMP_QCS+2008BR00'(!)   = ''              | ''                 | 'CS+2008BR00'           | 'R2512'             | '(SMR2512AW)'                  | '0.2'     | '0.1%'  | '1W'     | 'IO'       | '0.2ohm 2512'                                      | 'CHIP2512'     | ''          | ''            | ''        
 '0.03'       | '0.1%'    | '1W'     | '2512LF'  | 'CHIP'   | 'TMP_QCS+0308BR00'(!)   = ''              | ''                 | 'CS+0308BR00'           | 'R2512'             | '(SMR2512AW)'                  | '0.03'    | '0.1%'  | '1W'     | 'DISCRETE' | '0.03ohm 2512'                                     | 'CHIP2512'     | ''          | ''            | ''        
 '0.03'       | '0.1%'    | '1W'     | '2512LF'  | 'EMPTY'  | 'TMP_QCS+0308BR00'(!)   = ''              | ''                 | 'CS+0308BR00'           | 'R2512'             | '(SMR2512AW)'                  | '0.03'    | '0.1%'  | '1W'     | 'IO'       | '0.03ohm 2512'                                     | 'CHIP2512'     | ''          | ''            | ''        
 '2.67K'      | '1%'      | '1/10W'  | '0603'    | 'CHIP'   | 'TMP_QCS22673F927'(!)   = 'End of Design' | 'Comp-Approve'     | 'CS22673F927'           | 'R0603'             | '(SMR0603AW)'                  | '2.67K'   | '1%'    | '1/10W'  | 'DISCRETE' | '2.67Kohm 0603'                                    | 'CHIP0603'     | ''          | ''            | ''        
 '2.67K'      | '1%'      | '1/10W'  | '0603'    | 'EMPTY'  | 'TMP_QCS22673F927'(!)   = 'End of Design' | 'Comp-Approve'     | 'CS22673F927'           | 'R0603'             | '(SMR0603AW)'                  | '2.67K'   | '1%'    | '1/10W'  | 'IO'       | '2.67Kohm 0603'                                    | 'CHIP0603'     | ''          | ''            | ''        
 '23.2K'      | '1%'      | '1/16W'  | '0402LF'  | 'CHIP'   | 'TMP_QCS32322FB11'(!)   = 'End of Design' | 'Comp-Approve'     | 'CS32322FB11'           | 'R0402'             | '(R0402-0201)'                 | '23.2K'   | '1%'    | '1/16W'  | 'DISCRETE' | '23.2Kohm 0402'                                    | 'CHIP0402'     | ''          | ''            | ''        
 '23.2K'      | '1%'      | '1/16W'  | '0402LF'  | 'EMPTY'  | 'TMP_QCS32322FB11'(!)   = 'End of Design' | 'Comp-Approve'     | 'CS32322FB11'           | 'R0402'             | '(R0402-0201)'                 | '23.2K'   | '1%'    | '1/16W'  | 'IO'       | '23.2Kohm 0402'                                    | 'CHIP0402'     | ''          | ''            | ''        
 '174'        | '1%'      | '1/10W'  | '0603'    | 'CHIP'   | 'TMP_QCS11743F900'(!)   = ''              | ''                 | 'CS11743F900'           | 'R0603'             | '(SMR0603AW)'                  | '174'     | '1%'    | '1/10W'  | 'DISCRETE' | '174ohm 0603'                                      | 'CHIP0603'     | ''          | ''            | ''        
 '174'        | '1%'      | '1/10W'  | '0603'    | 'EMPTY'  | 'TMP_QCS11743F900'(!)   = ''              | ''                 | 'CS11743F900'           | 'R0603'             | '(SMR0603AW)'                  | '174'     | '1%'    | '1/10W'  | 'IO'       | '174ohm 0603'                                      | 'CHIP0603'     | ''          | ''            | ''        
 '7.32K'      | '1%'      | '1/10W'  | '0603'    | 'CHIP'   | 'TMP_QCS27323F919'(!)   = ''              | ''                 | 'CS27323F919'           | 'R0603'             | '(SMR0603AW)'                  | '7.32K'   | '1%'    | '1/10W'  | 'DISCRETE' | '7.32Kohm 0603'                                    | 'CHIP0603'     | ''          | ''            | ''        
 '7.32K'      | '1%'      | '1/10W'  | '0603'    | 'EMPTY'  | 'TMP_QCS27323F919'(!)   = ''              | ''                 | 'CS27323F919'           | 'R0603'             | '(SMR0603AW)'                  | '7.32K'   | '1%'    | '1/10W'  | 'IO'       | '7.32Kohm 0603'                                    | 'CHIP0603'     | ''          | ''            | ''        
 '255'        | '0.1%'    | '1/10W'  | '0603'    | 'CHIP'   | 'TMP_QCS12553B900'(!)   = ''              | ''                 | 'CS12553B900'           | 'R0603'             | '(SMR0603AW)'                  | '255'     | '0.1%'  | '1/10W'  | 'DISCRETE' | '255ohm 0603'                                      | 'CHIP0603'     | ''          | ''            | ''        
 '255'        | '0.1%'    | '1/10W'  | '0603'    | 'EMPTY'  | 'TMP_QCS12553B900'(!)   = ''              | ''                 | 'CS12553B900'           | 'R0603'             | '(SMR0603AW)'                  | '255'     | '0.1%'  | '1/10W'  | 'IO'       | '255ohm 0603'                                      | 'CHIP0603'     | ''          | ''            | ''        
 '22'         | '1%'      | '1/10W'  | '0603'    | 'CHIP'   | 'TMP_QCS02203F919'(!)   = 'End of Design' | 'Comp-Approve'     | 'CS02203F919'           | 'R0603'             | '(SMR0603AW)'                  | '22'      | '1%'    | '1/10W'  | 'DISCRETE' | '22ohm 0603'                                       | 'CHIP0603'     | ''          | ''            | ''        
 '22'         | '1%'      | '1/10W'  | '0603'    | 'EMPTY'  | 'TMP_QCS02203F919'(!)   = 'End of Design' | 'Comp-Approve'     | 'CS02203F919'           | 'R0603'             | '(SMR0603AW)'                  | '22'      | '1%'    | '1/10W'  | 'IO'       | '22ohm 0603'                                       | 'CHIP0603'     | ''          | ''            | ''        
 '4.99K'      | '1%'      | '1/10W'  | '0603'    | 'CHIP'   | 'TMP_QCS24993F949'(!)   = 'End of Design' | 'Comp-Approve'     | 'CS24993F949'           | 'R0603'             | '(SMR0603AW)'                  | '4.99K'   | '1%'    | '1/10W'  | 'DISCRETE' | '4.99Kohm 0603'                                    | 'CHIP0603'     | ''          | ''            | ''        
 '4.99K'      | '1%'      | '1/10W'  | '0603'    | 'EMPTY'  | 'TMP_QCS24993F949'(!)   = 'End of Design' | 'Comp-Approve'     | 'CS24993F949'           | 'R0603'             | '(SMR0603AW)'                  | '4.99K'   | '1%'    | '1/10W'  | 'IO'       | '4.99Kohm 0603'                                    | 'CHIP0603'     | ''          | ''            | ''        
 '0.5'        | '1%'      | '1/4W'   | '1206'    | 'CHIP'   | 'TMP_QCS+5006F200'(!)   = ''              | ''                 | 'CS+5006F200'           | 'R1206'             | '(SMR1206AW)'                  | '0.5'     | '1%'    | '1/4W'   | 'DISCRETE' | '0.5ohm 1206'                                      | 'CHIP1206'     | ''          | ''            | ''        
 '0.5'        | '1%'      | '1/4W'   | '1206'    | 'EMPTY'  | 'TMP_QCS+5006F200'(!)   = ''              | ''                 | 'CS+5006F200'           | 'R1206'             | '(SMR1206AW)'                  | '0.5'     | '1%'    | '1/4W'   | 'IO'       | '0.5ohm 1206'                                      | 'CHIP1206'     | ''          | ''            | ''        
 '0.51'       | '5%'      | '1/4W'   | '1206'    | 'CHIP'   | 'TMP_QCS+5106J203'(!)   = ''              | ''                 | 'CS+5106J203'           | 'R1206'             | '(SMR1206AW)'                  | '0.51'    | '5%'    | '1/4W'   | 'DISCRETE' | '0.51ohm 1206'                                     | 'CHIP1206'     | ''          | ''            | ''        
 '0.51'       | '5%'      | '1/4W'   | '1206'    | 'EMPTY'  | 'TMP_QCS+5106J203'(!)   = ''              | ''                 | 'CS+5106J203'           | 'R1206'             | '(SMR1206AW)'                  | '0.51'    | '5%'    | '1/4W'   | 'IO'       | '0.51ohm 1206'                                     | 'CHIP1206'     | ''          | ''            | ''        
 '1.5K'       | '5%'      | '1/16W'  | '0402LF'  | 'CHIP'   | 'TMP_QCS21502JB16'(!)   = 'End of Design' | 'Comp-Approve'     | 'CS21502JB16'           | 'R0402'             | '(R0402-0201)'                 | '1.5K'    | '5%'    | '1/16W'  | 'DISCRETE' | '1.5Kohm 0402'                                     | 'CHIP0402'     | ''          | ''            | ''        
 '1.5K'       | '5%'      | '1/16W'  | '0402LF'  | 'EMPTY'  | 'TMP_QCS21502JB16'(!)   = 'End of Design' | 'Comp-Approve'     | 'CS21502JB16'           | 'R0402'             | '(R0402-0201)'                 | '1.5K'    | '5%'    | '1/16W'  | 'IO'       | '1.5Kohm 0402'                                     | 'CHIP0402'     | ''          | ''            | ''        
 '3.3K'       | '5%'      | '1/16W'  | '0402LF'  | 'CHIP'   | 'TMP_QCS23302JB22'(!)   = 'End of Design' | 'Comp-Approve'     | 'CS23302JB22'           | 'R0402'             | '(R0402-0201)'                 | '3.3K'    | '5%'    | '1/16W'  | 'DISCRETE' | '3.3Kohm 0402'                                     | 'CHIP0402'     | ''          | ''            | ''        
 '3.3K'       | '5%'      | '1/16W'  | '0402LF'  | 'EMPTY'  | 'TMP_QCS23302JB22'(!)   = 'End of Design' | 'Comp-Approve'     | 'CS23302JB22'           | 'R0402'             | '(R0402-0201)'                 | '3.3K'    | '5%'    | '1/16W'  | 'IO'       | '3.3Kohm 0402'                                     | 'CHIP0402'     | ''          | ''            | ''        
 '4.7K'       | '5%'      | '1/16W'  | '0402LF'  | 'CHIP'   | 'TMP_QCS24702JB38'(!)   = 'End of Design' | 'Comp-Approve'     | 'CS24702JB38'           | 'R0402'             | '(R0402-0201)'                 | '4.7K'    | '5%'    | '1/16W'  | 'DISCRETE' | '4.7Kohm 0402'                                     | 'CHIP0402'     | ''          | ''            | ''        
 '4.7K'       | '5%'      | '1/16W'  | '0402LF'  | 'EMPTY'  | 'TMP_QCS24702JB38'(!)   = 'End of Design' | 'Comp-Approve'     | 'CS24702JB38'           | 'R0402'             | '(R0402-0201)'                 | '4.7K'    | '5%'    | '1/16W'  | 'IO'       | '4.7Kohm 0402'                                     | 'CHIP0402'     | ''          | ''            | ''        
 '470K'       | '1%'      | '1/16W'  | '0402LF'  | 'CHIP'   | 'TMP_QCS44702FB13'(!)   = 'End of Design' | 'Comp-Approve'     | 'CS44702FB13'           | 'R0402'             | '(R0402-0201)'                 | '470K'    | '1%'    | '1/16W'  | 'DISCRETE' | '470Kohm 0402'                                     | 'CHIP0402'     | ''          | ''            | ''        
 '470K'       | '1%'      | '1/16W'  | '0402LF'  | 'EMPTY'  | 'TMP_QCS44702FB13'(!)   = 'End of Design' | 'Comp-Approve'     | 'CS44702FB13'           | 'R0402'             | '(R0402-0201)'                 | '470K'    | '1%'    | '1/16W'  | 'IO'       | '470Kohm 0402'                                     | 'CHIP0402'     | ''          | ''            | ''        
 '15K'        | '5%'      | '1/16W'  | '0402LF'  | 'CHIP'   | 'TMP_QCS31502JB26'(!)   = 'End of Design' | 'Comp-Approve'     | 'CS31502JB26'           | 'R0402'             | '(R0402-0201)'                 | '15K'     | '5%'    | '1/16W'  | 'DISCRETE' | '15Kohm 0402'                                      | 'CHIP0402'     | ''          | ''            | ''        
 '15K'        | '5%'      | '1/16W'  | '0402LF'  | 'EMPTY'  | 'TMP_QCS31502JB26'(!)   = 'End of Design' | 'Comp-Approve'     | 'CS31502JB26'           | 'R0402'             | '(R0402-0201)'                 | '15K'     | '5%'    | '1/16W'  | 'IO'       | '15Kohm 0402'                                      | 'CHIP0402'     | ''          | ''            | ''        
 '47K'        | '5%'      | '1/16W'  | '0402LF'  | 'CHIP'   | 'TMP_QCS34702JB21'(!)   = 'End of Design' | 'Comp-Approve'     | 'CS34702JB21'           | 'R0402'             | '(R0402-0201)'                 | '47K'     | '5%'    | '1/16W'  | 'DISCRETE' | '47Kohm 0402'                                      | 'CHIP0402'     | ''          | ''            | ''        
 '47K'        | '5%'      | '1/16W'  | '0402LF'  | 'EMPTY'  | 'TMP_QCS34702JB21'(!)   = 'End of Design' | 'Comp-Approve'     | 'CS34702JB21'           | 'R0402'             | '(R0402-0201)'                 | '47K'     | '5%'    | '1/16W'  | 'IO'       | '47Kohm 0402'                                      | 'CHIP0402'     | ''          | ''            | ''        
 '100'        | '0.1%'    | '1/10W'  | '0603'    | 'CHIP'   | 'TMP_QCS11003B900'(!)   = 'End of Design' | 'Comp-Approve'     | 'CS11003B900'           | 'R0603'             | '(SMR0603AW)'                  | '100'     | '0.1%'  | '1/10W'  | 'DISCRETE' | '100ohm 0603'                                      | 'CHIP0603'     | ''          | ''            | ''        
 '100'        | '0.1%'    | '1/10W'  | '0603'    | 'EMPTY'  | 'TMP_QCS11003B900'(!)   = 'End of Design' | 'Comp-Approve'     | 'CS11003B900'           | 'R0603'             | '(SMR0603AW)'                  | '100'     | '0.1%'  | '1/10W'  | 'IO'       | '100ohm 0603'                                      | 'CHIP0603'     | ''          | ''            | ''        
 '10.7K'      | '0.1%'    | '1/10W'  | '0603'    | 'CHIP'   | 'TMP_QCS31073B900'(!)   = ''              | ''                 | 'CS31073B900'           | 'R0603'             | '(SMR0603AW)'                  | '10.7K'   | '0.1%'  | '1/10W'  | 'DISCRETE' | '10.7Kohm 0603'                                    | 'CHIP0603'     | ''          | ''            | ''        
 '10.7K'      | '0.1%'    | '1/10W'  | '0603'    | 'EMPTY'  | 'TMP_QCS31073B900'(!)   = ''              | ''                 | 'CS31073B900'           | 'R0603'             | '(SMR0603AW)'                  | '10.7K'   | '0.1%'  | '1/10W'  | 'IO'       | '10.7Kohm 0603'                                    | 'CHIP0603'     | ''          | ''            | ''        
 '80.6K'      | '0.1%'    | '1/10W'  | '0603'    | 'CHIP'   | 'TMP_QCS38063B900'(!)   = ''              | ''                 | 'CS38063B900'           | 'R0603'             | '(SMR0603AW)'                  | '80.6K'   | '0.1%'  | '1/10W'  | 'DISCRETE' | '80.6Kohm 0603'                                    | 'CHIP0603'     | ''          | ''            | ''        
 '80.6K'      | '0.1%'    | '1/10W'  | '0603'    | 'EMPTY'  | 'TMP_QCS38063B900'(!)   = ''              | ''                 | 'CS38063B900'           | 'R0603'             | '(SMR0603AW)'                  | '80.6K'   | '0.1%'  | '1/10W'  | 'IO'       | '80.6Kohm 0603'                                    | 'CHIP0603'     | ''          | ''            | ''        
 '56.2K'      | '0.1%'    | '1/10W'  | '0603'    | 'CHIP'   | 'TMP_QCS35623B900'(!)   = ''              | ''                 | 'CS35623B900'           | 'R0603'             | '(SMR0603AW)'                  | '56.2K'   | '0.1%'  | '1/10W'  | 'DISCRETE' | '56.2Kohm 0603'                                    | 'CHIP0603'     | ''          | ''            | ''        
 '56.2K'      | '0.1%'    | '1/10W'  | '0603'    | 'EMPTY'  | 'TMP_QCCS35623B90'(!)   = ''              | ''                 | 'CS35623B900'           | 'R0603'             | '(SMR0603AW)'                  | '56.2K'   | '0.1%'  | '1/10W'  | 'IO'       | '56.2Kohm 0603'                                    | 'CHIP0603'     | ''          | ''            | ''        
 '215K'       | '0.1%'    | '1/10W'  | '0603'    | 'CHIP'   | 'TMP_QCS42153B900'(!)   = ''              | ''                 | 'CS42153B900'           | 'R0603'             | '(SMR0603AW)'                  | '215K'    | '0.1%'  | '1/10W'  | 'DISCRETE' | '215Kohm 0603'                                     | 'CHIP0603'     | ''          | ''            | ''        
 '215K'       | '0.1%'    | '1/10W'  | '0603'    | 'EMPTY'  | 'TMP_QCS42153B900'(!)   = ''              | ''                 | 'CS42153B900'           | 'R0603'             | '(SMR0603AW)'                  | '215K'    | '0.1%'  | '1/10W'  | 'IO'       | '215Kohm 0603'                                     | 'CHIP0603'     | ''          | ''            | ''        
 '1.65K'      | '1%'      | '1/16W'  | '0402LF'  | 'CHIP'   | 'TMP_QCS21652FB29'(!)   = 'End of Design' | 'Comp-Approve'     | 'CS21652FB29'           | 'R0402'             | '(R0402-0201)'                 | '1.65K'   | '1%'    | '1/16W'  | 'DISCRETE' | '1.65Kohm 0402'                                    | 'CHIP0402'     | ''          | ''            | ''        
 '1.65K'      | '1%'      | '1/16W'  | '0402LF'  | 'EMPTY'  | 'TMP_QCS21652FB29'(!)   = 'End of Design' | 'Comp-Approve'     | 'CS21652FB29'           | 'R0402'             | '(R0402-0201)'                 | '1.65K'   | '1%'    | '1/16W'  | 'IO'       | '1.65Kohm 0402'                                    | 'CHIP0402'     | ''          | ''            | ''        
 '41.2K'      | '1%'      | '1/16W'  | '0402LF'  | 'CHIP'   | 'TMP_QCS34122FB19'(!)   = ''              | ''                 | 'CS34122FB19'           | 'R0402'             | '(R0402-0201)'                 | '41.2K'   | '1%'    | '1/16W'  | 'DISCRETE' | '41.2Kohm 0402'                                    | 'CHIP0402'     | ''          | ''            | ''        
 '41.2K'      | '1%'      | '1/16W'  | '0402LF'  | 'EMPTY'  | 'TMP_QCS34122FB19'(!)   = ''              | ''                 | 'CS34122FB19'           | 'R0402'             | '(R0402-0201)'                 | '41.2K'   | '1%'    | '1/16W'  | 'IO'       | '41.2Kohm 0402'                                    | 'CHIP0402'     | ''          | ''            | ''        
 '1.62K'      | '1%'      | '1/16W'  | '0402LF'  | 'CHIP'   | 'TMP_QCS21622FB17'(!)   = 'End of Design' | 'Comp-Approve'     | 'CS21622FB17'           | 'R0402'             | '(R0402-0201)'                 | '1.62K'   | '1%'    | '1/16W'  | 'DISCRETE' | '1.62Kohm 0402'                                    | 'CHIP0402'     | ''          | ''            | ''        
 '1.62K'      | '1%'      | '1/16W'  | '0402LF'  | 'EMPTY'  | 'TMP_QCS21622FB17'(!)   = 'End of Design' | 'Comp-Approve'     | 'CS21622FB17'           | 'R0402'             | '(R0402-0201)'                 | '1.62K'   | '1%'    | '1/16W'  | 'IO'       | '1.62Kohm 0402'                                    | 'CHIP0402'     | ''          | ''            | ''        
 '86.6K'      | '1%'      | '1/16W'  | '0402LF'  | 'CHIP'   | 'TMP_QCS38662FB16'(!)   = 'End of Design' | 'Comp-Approve'     | 'CS38662FB16'           | 'R0402'             | '(R0402-0201)'                 | '86.6K'   | '1%'    | '1/16W'  | 'DISCRETE' | '86.6Kohm 0402'                                    | 'CHIP0402'     | ''          | ''            | ''        
 '86.6K'      | '1%'      | '1/16W'  | '0402LF'  | 'EMPTY'  | 'TMP_QCS38662FB16'(!)   = 'End of Design' | 'Comp-Approve'     | 'CS38662FB16'           | 'R0402'             | '(R0402-0201)'                 | '86.6K'   | '1%'    | '1/16W'  | 'IO'       | '86.6Kohm 0402'                                    | 'CHIP0402'     | ''          | ''            | ''        
 '40.2K'      | '1%'      | '1/16W'  | '0402LF'  | 'CHIP'   | 'TMP_QCS34022FB15'(!)   = 'End of Design' | 'Comp-Approve'     | 'CS34022FB15'           | 'R0402'             | '(R0402-0201)'                 | '40.2K'   | '1%'    | '1/16W'  | 'DISCRETE' | '40.2Kohm 0402'                                    | 'CHIP0402'     | ''          | ''            | ''        
 '40.2K'      | '1%'      | '1/16W'  | '0402LF'  | 'EMPTY'  | 'TMP_QCS34022FB15'(!)   = 'End of Design' | 'Comp-Approve'     | 'CS34022FB15'           | 'R0402'             | '(R0402-0201)'                 | '40.2K'   | '1%'    | '1/16W'  | 'IO'       | '40.2Kohm 0402'                                    | 'CHIP0402'     | ''          | ''            | ''        
 '27K'        | '1%'      | '1/16W'  | '0402LF'  | 'CHIP'   | 'TMP_QCS32702FB16'(!)   = 'End of Design' | 'Comp-Approve'     | 'CS32702FB16'           | 'R0402'             | '(R0402-0201)'                 | '27K'     | '1%'    | '1/16W'  | 'DISCRETE' | '27Kohm 0402'                                      | 'CHIP0402'     | ''          | ''            | ''        
 '27K'        | '1%'      | '1/16W'  | '0402LF'  | 'EMPTY'  | 'TMP_QCS32702FB16'(!)   = 'End of Design' | 'Comp-Approve'     | 'CS32702FB16'           | 'R0402'             | '(R0402-0201)'                 | '27K'     | '1%'    | '1/16W'  | 'IO'       | '27Kohm 0402'                                      | 'CHIP0402'     | ''          | ''            | ''        
 '47'         | '1%'      | '1/16W'  | '0402LF'  | 'CHIP'   | 'TMP_QCS04702FB16'(!)   = 'End of Design' | 'Comp-Approve'     | 'CS04702FB16'           | 'R0402'             | '(R0402-0201)'                 | '47'      | '1%'    | '1/16W'  | 'DISCRETE' | '47ohm 0402'                                       | 'CHIP0402'     | ''          | ''            | ''        
 '47'         | '1%'      | '1/16W'  | '0402LF'  | 'EMPTY'  | 'TMP_QCS04702FB16'(!)   = 'End of Design' | 'Comp-Approve'     | 'CS04702FB16'           | 'R0402'             | '(R0402-0201)'                 | '47'      | '1%'    | '1/16W'  | 'IO'       | '47ohm 0402'                                       | 'CHIP0402'     | ''          | ''            | ''        
 '16.2K'      | '1%'      | '1/16W'  | '0402LF'  | 'CHIP'   | 'TMP_QCS31622FB27'(!)   = 'End of Design' | 'Comp-Approve'     | 'CS31622FB27'           | 'R0402'             | '(R0402-0201)'                 | '16.2K'   | '1%'    | '1/16W'  | 'DISCRETE' | '16.2Kohm 0402'                                    | 'CHIP0402'     | ''          | ''            | ''        
 '16.2K'      | '1%'      | '1/16W'  | '0402LF'  | 'EMPTY'  | 'TMP_QCS31622FB27'(!)   = 'End of Design' | 'Comp-Approve'     | 'CS31622FB27'           | 'R0402'             | '(R0402-0201)'                 | '16.2K'   | '1%'    | '1/16W'  | 'IO'       | '16.2Kohm 0402'                                    | 'CHIP0402'     | ''          | ''            | ''        
 '69.8K'      | '1%'      | '1/16W'  | '0402LF'  | 'CHIP'   | 'TMP_QCS36982FB11'(!)   = 'End of Design' | 'Comp-Approve'     | 'CS36982FB11'           | 'R0402'             | '(R0402-0201)'                 | '69.8K'   | '1%'    | '1/16W'  | 'DISCRETE' | '69.8Kohm 0402'                                    | 'CHIP0402'     | ''          | ''            | ''        
 '69.8K'      | '1%'      | '1/16W'  | '0402LF'  | 'EMPTY'  | 'TMP_QCS36982FB11'(!)   = 'End of Design' | 'Comp-Approve'     | 'CS36982FB11'           | 'R0402'             | '(R0402-0201)'                 | '69.8K'   | '1%'    | '1/16W'  | 'IO'       | '69.8Kohm 0402'                                    | 'CHIP0402'     | ''          | ''            | ''        
 '7.32K'      | '1%'      | '1/16W'  | '0402LF'  | 'CHIP'   | 'TMP_QCS27322FB12'(!)   = 'End of Design' | 'Comp-Approve'     | 'CS27322FB12'           | 'R0402'             | '(R0402-0201)'                 | '7.32K'   | '1%'    | '1/16W'  | 'DISCRETE' | '7.32Kohm 0402'                                    | 'CHIP0402'     | ''          | ''            | ''        
 '7.32K'      | '1%'      | '1/16W'  | '0402LF'  | 'EMPTY'  | 'TMP_QCS27322FB12'(!)   = 'End of Design' | 'Comp-Approve'     | 'CS27322FB12'           | 'R0402'             | '(R0402-0201)'                 | '7.32K'   | '1%'    | '1/16W'  | 'IO'       | '7.32Kohm 0402'                                    | 'CHIP0402'     | ''          | ''            | ''        
 '57.6K'      | '1%'      | '1/16W'  | '0402LF'  | 'CHIP'   | 'TMP_QCS35762FB11'(!)   = 'End of Design' | 'Comp-Approve'     | 'CS35762FB11'           | 'R0402'             | '(R0402-0201)'                 | '57.6K'   | '1%'    | '1/16W'  | 'DISCRETE' | '57.6Kohm 0402'                                    | 'CHIP0402'     | ''          | ''            | ''        
 '57.6K'      | '1%'      | '1/16W'  | '0402LF'  | 'EMPTY'  | 'TMP_QCS35762FB11'(!)   = 'End of Design' | 'Comp-Approve'     | 'CS35762FB11'           | 'R0402'             | '(R0402-0201)'                 | '57.6K'   | '1%'    | '1/16W'  | 'IO'       | '57.6Kohm 0402'                                    | 'CHIP0402'     | ''          | ''            | ''        
 '4.99K'      | '1%'      | '1/16W'  | '0402LF'  | 'CHIP'   | 'TMP_QCS24992FB26'(!)   = 'End of Design' | 'Comp-Approve'     | 'CS24992FB26'           | 'R0402'             | '(R0402-0201)'                 | '4.99K'   | '1%'    | '1/16W'  | 'DISCRETE' | '4.99Kohm 0402'                                    | 'CHIP0402'     | ''          | ''            | ''        
 '4.99K'      | '1%'      | '1/16W'  | '0402LF'  | 'EMPTY'  | 'TMP_QCS24992FB26'(!)   = 'End of Design' | 'Comp-Approve'     | 'CS24992FB26'           | 'R0402'             | '(R0402-0201)'                 | '4.99K'   | '1%'    | '1/16W'  | 'IO'       | '4.99Kohm 0402'                                    | 'CHIP0402'     | ''          | ''            | ''        
 '82K'        | '1%'      | '1/16W'  | '0402LF'  | 'CHIP'   | 'TMP_QCS38202FB14'(!)   = 'End of Design' | 'Comp-Approve'     | 'CS38202FB14'           | 'R0402'             | '(R0402-0201)'                 | '82K'     | '1%'    | '1/16W'  | 'DISCRETE' | '82Kohm 0402'                                      | 'CHIP0402'     | ''          | ''            | ''        
 '82K'        | '1%'      | '1/16W'  | '0402LF'  | 'EMPTY'  | 'TMP_QCS38202FB14'(!)   = 'End of Design' | 'Comp-Approve'     | 'CS38202FB14'           | 'R0402'             | '(R0402-0201)'                 | '82K'     | '1%'    | '1/16W'  | 'IO'       | '82Kohm 0402'                                      | 'CHIP0402'     | ''          | ''            | ''        
 '11.8K'      | '1%'      | '1/16W'  | '0402LF'  | 'CHIP'   | 'TMP_QCS31182FB18'(!)   = 'End of Design' | 'Comp-Approve'     | 'CS31182FB18'           | 'R0402'             | '(R0402-0201)'                 | '11.8K'   | '1%'    | '1/16W'  | 'DISCRETE' | '11.8Kohm 0402'                                    | 'CHIP0402'     | ''          | ''            | ''        
 '11.8K'      | '1%'      | '1/16W'  | '0402LF'  | 'EMPTY'  | 'TMP_QCS31182FB18'(!)   = 'End of Design' | 'Comp-Approve'     | 'CS31182FB18'           | 'R0402'             | '(R0402-0201)'                 | '11.8K'   | '1%'    | '1/16W'  | 'IO'       | '11.8Kohm 0402'                                    | 'CHIP0402'     | ''          | ''            | ''        
 '45.3K'      | '1%'      | '1/16W'  | '0402LF'  | 'CHIP'   | 'TMP_QCS34532FB18'(!)   = 'End of Design' | 'Comp-Approve'     | 'CS34532FB18'           | 'R0402'             | '(R0402-0201)'                 | '45.3K'   | '1%'    | '1/16W'  | 'DISCRETE' | '45.3Kohm 0402'                                    | 'CHIP0402'     | ''          | ''            | ''        
 '45.3K'      | '1%'      | '1/16W'  | '0402LF'  | 'EMPTY'  | 'TMP_QCS34532FB18'(!)   = 'End of Design' | 'Comp-Approve'     | 'CS34532FB18'           | 'R0402'             | '(R0402-0201)'                 | '45.3K'   | '1%'    | '1/16W'  | 'IO'       | '45.3Kohm 0402'                                    | 'CHIP0402'     | ''          | ''            | ''        
 '16K'        | '1%'      | '1/16W'  | '0402LF'  | 'CHIP'   | 'TMP_QCS31602FB00'(!)   = 'End of Design' | 'Comp-Approve'     | 'CS31602FB00'           | 'R0402'             | '(R0402-0201)'                 | '16K'     | '1%'    | '1/16W'  | 'DISCRETE' | '16Kohm 0402'                                      | 'CHIP0402'     | ''          | ''            | ''        
 '16K'        | '1%'      | '1/16W'  | '0402LF'  | 'EMPTY'  | 'TMP_QCS31602FB00'(!)   = 'End of Design' | 'Comp-Approve'     | 'CS31602FB00'           | 'R0402'             | '(R0402-0201)'                 | '16K'     | '1%'    | '1/16W'  | 'IO'       | '16Kohm 0402'                                      | 'CHIP0402'     | ''          | ''            | ''        
 '150'        | '1%'      | '1/16W'  | '0402LF'  | 'CHIP'   | 'TMP_QCS11502FB21'(!)   = 'End of Design' | 'Comp-Approve'     | 'CS11502FB21'           | 'R0402'             | '(R0402-0201)'                 | '150'     | '1%'    | '1/16W'  | 'DISCRETE' | '150ohm 0402'                                      | 'CHIP0402'     | ''          | ''            | ''        
 '150'        | '1%'      | '1/16W'  | '0402LF'  | 'EMPTY'  | 'TMP_QCS11502FB21'(!)   = 'End of Design' | 'Comp-Approve'     | 'CS11502FB21'           | 'R0402'             | '(R0402-0201)'                 | '150'     | '1%'    | '1/16W'  | 'IO'       | '150ohm 0402'                                      | 'CHIP0402'     | ''          | ''            | ''        
 '2.37K'      | '1%'      | '1/16W'  | '0402LF'  | 'CHIP'   | 'TMP_QCS22372FB11'(!)   = 'End of Design' | 'Comp-Approve'     | 'CS22372FB11'           | 'R0402'             | '(R0402-0201)'                 | '2.37K'   | '1%'    | '1/16W'  | 'DISCRETE' | '2.37Kohm 0402'                                    | 'CHIP0402'     | ''          | ''            | ''        
 '2.37K'      | '1%'      | '1/16W'  | '0402LF'  | 'EMPTY'  | 'TMP_QCS22372FB11'(!)   = 'End of Design' | 'Comp-Approve'     | 'CS22372FB11'           | 'R0402'             | '(R0402-0201)'                 | '2.37K'   | '1%'    | '1/16W'  | 'IO'       | '2.37Kohm 0402'                                    | 'CHIP0402'     | ''          | ''            | ''        
 '3.16K'      | '1%'      | '1/16W'  | '0402LF'  | 'CHIP'   | 'TMP_QCS23162FB04'(!)   = 'End of Design' | 'Comp-Approve'     | 'CS23162FB04'           | 'R0402'             | '(R0402-0201)'                 | '3.16K'   | '1%'    | '1/16W'  | 'DISCRETE' | '3.16Kohm 0402'                                    | 'CHIP0402'     | ''          | ''            | ''        
 '3.16K'      | '1%'      | '1/16W'  | '0402LF'  | 'EMPTY'  | 'TMP_QCS23162FB04'(!)   = 'End of Design' | 'Comp-Approve'     | 'CS23162FB04'           | 'R0402'             | '(R0402-0201)'                 | '3.16K'   | '1%'    | '1/16W'  | 'IO'       | '3.16Kohm 0402'                                    | 'CHIP0402'     | ''          | ''            | ''        
 '42.2K'      | '1%'      | '1/16W'  | '0402LF'  | 'CHIP'   | 'TMP_QCS34222FB00'(!)   = 'End of Design' | 'Comp-Approve'     | 'CS34222FB00'           | 'R0402'             | '(R0402-0201)'                 | '42.2K'   | '1%'    | '1/16W'  | 'DISCRETE' | '42.2Kohm 0402'                                    | 'CHIP0402'     | ''          | ''            | ''        
 '42.2K'      | '1%'      | '1/16W'  | '0402LF'  | 'EMPTY'  | 'TMP_QCS34222FB00'(!)   = 'End of Design' | 'Comp-Approve'     | 'CS34222FB00'           | 'R0402'             | '(R0402-0201)'                 | '42.2K'   | '1%'    | '1/16W'  | 'IO'       | '42.2Kohm 0402'                                    | 'CHIP0402'     | ''          | ''            | ''        
 '56K'        | '1%'      | '1/16W'  | '0402LF'  | 'CHIP'   | 'TMP_QCS35602FB11'(!)   = 'End of Design' | 'Comp-Approve'     | 'CS35602FB11'           | 'R0402'             | '(R0402-0201)'                 | '56K'     | '1%'    | '1/16W'  | 'DISCRETE' | '56Kohm 0402'                                      | 'CHIP0402'     | ''          | ''            | ''        
 '56K'        | '1%'      | '1/16W'  | '0402LF'  | 'EMPTY'  | 'TMP_QCS35602FB11'(!)   = 'End of Design' | 'Comp-Approve'     | 'CS35602FB11'           | 'R0402'             | '(R0402-0201)'                 | '56K'     | '1%'    | '1/16W'  | 'IO'       | '56Kohm 0402'                                      | 'CHIP0402'     | ''          | ''            | ''        
 '80.6K'      | '1%'      | '1/16W ' | '0402LF ' | 'CHIP'   | 'TMP_QCS38062FB14'(!)   = 'End of Design' | 'Comp-Approve'     | 'CS38062FB14'           | 'R0402'             | '(R0402-0201)'                 | '80.6K'   | '1%'    | '1/16W ' | 'DISCRETE' | 'RES CHIP 80.6K 1/16W +-1% (0402)'                 | 'CHIP0402 '    | ''          | ''            | ''        
 '80.6K'      | '1%'      | '1/16W ' | '0402LF ' | 'EMPTY'  | 'TMP_QCS38062FB14'(!)   = 'End of Design' | 'Comp-Approve'     | 'CS38062FB14'           | 'R0402'             | '(R0402-0201)'                 | '80.6K'   | '1%'    | '1/16W ' | 'IO'       | 'RES CHIP 80.6K 1/16W +-1% (0402)'                 | 'CHIP0402 '    | ''          | ''            | ''        
 '22K'        | '1%'      | '1/16W'  | '0402LF'  | 'CHIP'   | 'TMP_QCS32202FB18'(!)   = 'End of Design' | 'Comp-Approve'     | 'CS32202FB18'           | 'R0402'             | '(R0402-0201)'                 | '22K'     | '1%'    | '1/16W'  | 'DISCRETE' | 'RES CHIP 22K 1/16W+-1%(0402)'                     | 'CHIP0402'     | ''          | ''            | ''        
 '22K'        | '1%'      | '1/16W'  | '0402LF'  | 'EMPTY'  | 'TMP_QCS32202FB18'(!)   = 'End of Design' | 'Comp-Approve'     | 'CS32202FB18'           | 'R0402'             | '(R0402-0201)'                 | '22K'     | '1%'    | '1/16W'  | 'IO'       | 'RES CHIP 22K 1/16W+-1%(0402)'                     | 'CHIP0402'     | ''          | ''            | ''        
 '12.1K'      | '1%'      | '1/16W'  | '0402LF'  | 'CHIP'   | 'TMP_QCS31212FB28'(!)   = 'End of Design' | 'Comp-Approve'     | 'CS31212FB28'           | 'R0402'             | '(R0402-0201)'                 | '12.1K'   | '1%'    | '1/16W'  | 'DISCRETE' | 'RES CHIP 12.1K 1/16W +-1%(0402)'                  | 'CHIP0402'     | ''          | ''            | ''        
 '12.1K'      | '1%'      | '1/16W'  | '0402LF'  | 'EMPTY'  | 'TMP_QCS31212FB28'(!)   = 'End of Design' | 'Comp-Approve'     | 'CS31212FB28'           | 'R0402'             | '(R0402-0201)'                 | '12.1K'   | '1%'    | '1/16W'  | 'IO'       | 'RES CHIP 12.1K 1/16W +-1%(0402)'                  | 'CHIP0402'     | ''          | ''            | ''        
 '37.4K'      | '1%'      | '1/16W'  | '0402LF'  | 'CHIP'   | 'TMP_QCS33742FB17'(!)   = 'End of Design' | 'Comp-Approve'     | 'CS33742FB17'           | 'R0402'             | '(R0402-0201)'                 | '37.4K'   | '1%'    | '1/16W ' | 'DISCRETE' | 'RES CHIP 37.4K 1/16W +-1% (0402)'                 | 'CHIP0402'     | ''          | ''            | ''        
 '37.4K'      | '1%'      | '1/16W'  | '0402LF'  | 'EMPTY'  | 'TMP_QCS33742FB17'(!)   = 'End of Design' | 'Comp-Approve'     | 'CS33742FB17'           | 'R0402'             | '(R0402-0201)'                 | '37.4K'   | '1%'    | '1/16W ' | 'IO'       | 'RES CHIP 37.4K 1/16W +-1% (0402)'                 | 'CHIP0402'     | ''          | ''            | ''        
 '680'        | '5%'      | '1/16W ' | '0402LF ' | 'CHIP'   | 'TMP_QCS16802JB27'(!)   = 'End of Design' | 'Comp-Approve'     | 'CS16802JB27'           | 'R0402'             | '(R0402-0201)'                 | '680'     | '5%'    | '1/16W ' | 'DISCRETE' | 'RES CHIP 680 1/16W +-5%(0402)'                    | 'CHIP0402 '    | ''          | ''            | ''        
 '680'        | '5%'      | '1/16W ' | '0402LF ' | 'EMPTY'  | 'TMP_QCS16802JB27'(!)   = 'End of Design' | 'Comp-Approve'     | 'CS16802JB27'           | 'R0402'             | '(R0402-0201)'                 | '680'     | '5%'    | '1/16W ' | 'IO'       | 'RES CHIP 680 1/16W +-5%(0402)'                    | 'CHIP0402 '    | ''          | ''            | ''        
 '5.1'        | '1%'      | '1/10W'  | '0603LF'  | 'CHIP'   | 'TMP_QCS-5103F916'(!)   = ''              | ''                 | 'CS-5103F916'           | 'R0603'             | '(SMR0603AW)'                  | '5.1'     | '1%'    | '1/10W'  | 'DISCRETE' | 'RES CHIP 5.1 1/10W +-1%(0603)'                    | 'CHIP0603'     | ''          | ''            | ''        
 '5.1'        | '1%'      | '1/10W'  | '0603LF'  | 'EMPTY'  | 'TMP_QCS-5103F916'(!)   = ''              | ''                 | 'CS-5103F916'           | 'R0603'             | '(SMR0603AW)'                  | '5.1'     | '1%'    | '1/10W'  | 'IO'       | 'RES CHIP 5.1 1/10W +-1%(0603)'                    | 'CHIP0603'     | ''          | ''            | ''        
 '2M'         | '1%'      | '1/16W'  | '0402LF'  | 'CHIP'   | 'TMP_QCS52002FB06'(!)   = 'End of Design' | 'Comp-Approve'     | 'CS52002FB06'           | 'R0402'             | '(R0402-0201)'                 | '2M'      | '1%'    | '1/16W ' | 'DISCRETE' | 'RES CHIP 2M 1/16W +-1%(0402)'                     | 'CHIP0402 '    | ''          | ''            | ''        
 '2M'         | '1%'      | '1/16W'  | '0402LF'  | 'EMPTY'  | 'TMP_QCS52002FB06'(!)   = 'End of Design' | 'Comp-Approve'     | 'CS52002FB06'           | 'R0402'             | '(R0402-0201)'                 | '2M'      | '1%'    | '1/16W ' | 'IO'       | 'RES CHIP 2M 1/16W +-1%(0402)'                     | 'CHIP0402 '    | ''          | ''            | ''        
 '165'        | '1%'      | '1/16W'  | '0402LF'  | 'CHIP'   | 'TMP_QCS11652FB19'(!)   = 'End of Design' | 'Comp-Approve'     | 'CS11652FB19'           | 'R0402'             | '(R0402-0201)'                 | '165'     | '1%'    | '1/16W ' | 'DISCRETE' | 'RES CHIP 165 1/16W +-1%(0402)'                    | 'CHIP0402 '    | ''          | ''            | ''        
 '165'        | '1%'      | '1/16W'  | '0402LF'  | 'EMPTY'  | 'TMP_QCS11652FB19'(!)   = 'End of Design' | 'Comp-Approve'     | 'CS11652FB19'           | 'R0402'             | '(R0402-0201)'                 | '165'     | '1%'    | '1/16W ' | 'IO'       | 'RES CHIP 165 1/16W +-1%(0402)'                    | 'CHIP0402 '    | ''          | ''            | ''        
 '49.9K'      | '1%'      | '1/16W ' | '0402LF ' | 'CHIP'   | 'TMP_QCS34992FB10'(!)   = 'End of Design' | 'Comp-Approve'     | 'CS34992FB10'           | 'R0402'             | '(R0402-0201)'                 | '49.9K'   | '1%'    | '1/16W ' | 'DISCRETE' | 'RES CHIP 49.9K 1/16W +-1%(0402)'                  | 'CHIP0402 '    | ''          | ''            | ''        
 '49.9K'      | '1%'      | '1/16W ' | '0402LF ' | 'EMPTY'  | 'TMP_QCS34992FB10'(!)   = 'End of Design' | 'Comp-Approve'     | 'CS34992FB10'           | 'R0402'             | '(R0402-0201)'                 | '49.9K'   | '1%'    | '1/16W ' | 'IO'       | 'RES CHIP 49.9K 1/16W +-1%(0402)'                  | 'CHIP0402 '    | ''          | ''            | ''        
 '15K'        | '1%'      | '1/16W'  | '0402LF'  | 'CHIP'   | 'TMP_QCS31502FB24'(!)   = 'End of Design' | 'Comp-Approve'     | 'CS31502FB24'           | 'R0402'             | '(R0402-0201)'                 | '15K'     | '1%'    | '1/16W ' | 'DISCRETE' | 'RES CHIP 15K 1/16W +-1% (0402)'                   | 'CHIP0402'     | ''          | ''            | ''        
 '15K'        | '1%'      | '1/16W'  | '0402LF'  | 'EMPTY'  | 'TMP_QCS31502FB24'(!)   = 'End of Design' | 'Comp-Approve'     | 'CS31502FB24'           | 'R0402'             | '(R0402-0201)'                 | '15K'     | '1%'    | '1/16W ' | 'IO'       | 'RES CHIP 15K 1/16W +-1% (0402)'                   | 'CHIP0402'     | ''          | ''            | ''        
 '10K'        | '1%'      | '1/16W'  | '0402LF'  | 'CHIP'   | 'TMP_QCS31002FB26'(!)   = 'End of Design' | 'Comp-Approve'     | 'CS31002FB26'           | 'R0402'             | '(R0402-0201)'                 | '10K'     | '1%'    | '1/16W'  | 'DISCRETE' | 'RES CHIP 10K 1/16W +-1% (0402)'                   | 'CHIP0402'     | ''          | ''            | ''        
 '10K'        | '1%'      | '1/16W'  | '0402LF'  | 'EMPTY'  | 'TMP_QCS31002FB26'(!)   = 'End of Design' | 'Comp-Approve'     | 'CS31002FB26'           | 'R0402'             | '(R0402-0201)'                 | '10K'     | '1%'    | '1/16W'  | 'IO'       | 'RES CHIP 10K 1/16W +-1% (0402)'                   | 'CHIP0402'     | ''          | ''            | ''        
 '2.7K'       | '1%'      | '1/16W'  | '0402LF'  | 'CHIP'   | 'TMP_QCS22702FB14'(!)   = 'End of Design' | 'Comp-Approve'     | 'CS22702FB14'           | 'R0402'             | '(R0402-0201)'                 | '2.7K'    | '1%'    | '1/16W ' | 'DISCRETE' | 'RES CHIP 2.7K 1/16W +-1%(0402)'                   | 'CHIP0402 '    | ''          | ''            | ''        
 '2.7K'       | '1%'      | '1/16W'  | '0402LF'  | 'EMPTY'  | 'TMP_QCS22702FB14'(!)   = 'End of Design' | 'Comp-Approve'     | 'CS22702FB14'           | 'R0402'             | '(R0402-0201)'                 | '2.7K'    | '1%'    | '1/16W ' | 'IO'       | 'RES CHIP 2.7K 1/16W +-1%(0402)'                   | 'CHIP0402 '    | ''          | ''            | ''        
 '402K'       | '1%'      | '1/16W'  | '0402LF'  | 'CHIP'   | 'TMP_QCS44022FB25'(!)   = 'End of Design' | 'Comp-Approve'     | 'CS44022FB25'           | 'R0402'             | '(R0402-0201)'                 | '402K'    | '1%'    | '1/16W ' | 'DISCRETE' | 'RES CHIP 402K 1/16W +-1% (0402)'                  | 'CHIP0402 '    | ''          | ''            | ''        
 '402K'       | '1%'      | '1/16W'  | '0402LF'  | 'EMPTY'  | 'TMP_QCS44022FB25'(!)   = 'End of Design' | 'Comp-Approve'     | 'CS44022FB25'           | 'R0402'             | '(R0402-0201)'                 | '402K'    | '1%'    | '1/16W ' | 'IO'       | 'RES CHIP 402K 1/16W +-1% (0402)'                  | 'CHIP0402 '    | ''          | ''            | ''        
 '511K'       | '1%'      | '1/10W'  | '0603LF ' | 'CHIP'   | 'TMP_QCS45113F900'(!)   = 'End of Design' | 'Comp-Approve'     | 'CS45113F900'           | 'R0603'             | '(SMR0603AW)'                  | '511K'    | '1%'    | '1/10W ' | 'DISCRETE' | 'RES CHIP 511K 1/10W +-1%(0603)'                   | 'CHIP0603 '    | ''          | ''            | ''        
 '511K'       | '1%'      | '1/10W'  | '0603LF ' | 'EMPTY'  | 'TMP_QCS45113F900'(!)   = 'End of Design' | 'Comp-Approve'     | 'CS45113F900'           | 'R0603'             | '(SMR0603AW)'                  | '511K'    | '1%'    | '1/10W ' | 'IO'       | 'RES CHIP 511K 1/10W +-1%(0603)'                   | 'CHIP0603 '    | ''          | ''            | ''        
 '220'        | '5%'      | '1/2W'   | '1210LF ' | 'CHIP'   | 'TMP_QCS12207J300'(!)   = ''              | ''                 | 'CS12207J300'           | 'R1210'             | '(SMR1210AW)'                  | '220'     | '5%'    | '1/2W'   | 'DISCRETE' | 'RES CHIP 220 1/2W +-5%(1210)'                     | 'CHIP1210 '    | ''          | ''            | ''        
 '220'        | '5%'      | '1/2W'   | '1210LF ' | 'EMPTY'  | 'TMP_QCS12207J300'(!)   = ''              | ''                 | 'CS12207J300'           | 'R1210'             | '(SMR1210AW)'                  | '220'     | '5%'    | '1/2W'   | 'IO'       | 'RES CHIP 220 1/2W +-5%(1210)'                     | 'CHIP1210 '    | ''          | ''            | ''        
 '56'         | '5%'      | '1/10W'  | '0603LF ' | 'CHIP'   | 'TMP_QCS05603J930'(!)   = ''              | ''                 | 'CS05603J930'           | 'R0603'             | '(SMR0603AW)'                  | '56'      | '5%'    | '1/10W ' | 'DISCRETE' | 'RESISTOR CHIP 56 1/10W,+-5%(1608)'                | 'CHIP0603 '    | ''          | ''            | ''        
 '56'         | '5%'      | '1/10W'  | '0603LF ' | 'EMPTY'  | 'TMP_QCS05603J930'(!)   = ''              | ''                 | 'CS05603J930'           | 'R0603'             | '(SMR0603AW)'                  | '56'      | '5%'    | '1/10W ' | 'IO'       | 'RESISTOR CHIP 56 1/10W,+-5%(1608)'                | 'CHIP0603 '    | ''          | ''            | ''        
 '2.55K'      | '1%'      | '1/16W ' | '0402LF ' | 'CHIP'   | 'TMP_QCS22552FB01'(!)   = 'End of Design' | 'Comp-Approve'     | 'CS22552FB01'           | 'R0402'             | '(R0402-0201)'                 | '2.55K'   | '1%'    | '1/16W ' | 'DISCRETE' | 'RES CHIP 2.55K 1/16W +-1%(0402)'                  | 'CHIP0402 '    | ''          | ''            | ''        
 '2.55K'      | '1%'      | '1/16W ' | '0402LF ' | 'EMPTY'  | 'TMP_QCS22552FB01'(!)   = 'End of Design' | 'Comp-Approve'     | 'CS22552FB01'           | 'R0402'             | '(R0402-0201)'                 | '2.55K'   | '1%'    | '1/16W ' | 'IO'       | 'RES CHIP 2.55K 1/16W +-1%(0402)'                  | 'CHIP0402 '    | ''          | ''            | ''        
 '9.53K'      | '1%'      | '1/16W ' | '0402LF ' | 'CHIP'   | 'TMP_QCS29532FB10'(!)   = 'End of Design' | 'Comp-Approve'     | 'CS29532FB10'           | 'R0402'             | '(R0402-0201)'                 | '9.53K'   | '1%'    | '1/16W ' | 'DISCRETE' | 'RES CHIP 9.53K 1/16W +-1%(0402)'                  | 'CHIP0402 '    | ''          | ''            | ''        
 '9.53K'      | '1%'      | '1/16W ' | '0402LF ' | 'EMPTY'  | 'TMP_QCS29532FB10'(!)   = 'End of Design' | 'Comp-Approve'     | 'CS29532FB10'           | 'R0402'             | '(R0402-0201)'                 | '9.53K'   | '1%'    | '1/16W ' | 'IO'       | 'RES CHIP 9.53K 1/16W +-1%(0402)'                  | 'CHIP0402 '    | ''          | ''            | ''        
 '909'        | '1%'      | '1/16W'  | '0402LF'  | 'CHIP'   | 'TMP_QCS19092FB17'(!)   = 'End of Design' | 'Comp-Approve'     | 'CS19092FB17'           | 'R0402'             | '(R0402-0201)'                 | '909'     | '1%'    | '1/16W'  | 'DISCRETE' | 'RES CHIP 909(1/16W,1%,0402)'                      | 'CHIP0402'     | ''          | ''            | ''        
 '909'        | '1%'      | '1/16W'  | '0402LF'  | 'EMPTY'  | 'TMP_QCS19092FB17'(!)   = 'End of Design' | 'Comp-Approve'     | 'CS19092FB17'           | 'R0402'             | '(R0402-0201)'                 | '909'     | '1%'    | '1/16W'  | 'IO'       | 'RES CHIP 909(1/16W,1%,0402)'                      | 'CHIP0402'     | ''          | ''            | ''        
 '51'         | '1%'      | '1/16W ' | '0402LF ' | 'CHIP'   | 'TMP_QCS05102FB09'(!)   = 'End of Design' | 'Comp-Approve'     | 'CS05102FB09'           | 'R0402'             | '(R0402-0201)'                 | '51'      | '1%'    | '1/16W ' | 'DISCRETE' | 'RES CHIP 51 1/16W +-1% (0402)'                    | 'CHIP0402 '    | ''          | ''            | ''        
 '51'         | '1%'      | '1/16W ' | '0402LF ' | 'EMPTY'  | 'TMP_QCS05102FB09'(!)   = 'End of Design' | 'Comp-Approve'     | 'CS05102FB09'           | 'R0402'             | '(R0402-0201)'                 | '51'      | '1%'    | '1/16W ' | 'IO'       | 'RES CHIP 51 1/16W +-1% (0402)'                    | 'CHIP0402 '    | ''          | ''            | ''        
 '59K'        | '1%'      | '1/16W ' | '0402LF ' | 'CHIP'   | 'TMP_QCS35902FB03'(!)   = ''              | ''                 | 'CS35902FB03'           | 'R0402'             | '(R0402-0201)'                 | '59K'     | '1%'    | '1/16W ' | 'DISCRETE' | 'RESISTOR CHIP 59K 1/16W +-1%(0402)'               | 'CHIP0402 '    | ''          | ''            | ''        
 '59K'        | '1%'      | '1/16W ' | '0402LF ' | 'EMPTY'  | 'TMP_QCS35902FB03'(!)   = ''              | ''                 | 'CS35902FB03'           | 'R0402'             | '(R0402-0201)'                 | '59K'     | '1%'    | '1/16W ' | 'IO'       | 'RESISTOR CHIP 59K 1/16W +-1%(0402)'               | 'CHIP0402 '    | ''          | ''            | ''        
 '0.39'       | '1%'      | '1/10W'  | '0603LF ' | 'CHIP'   | 'TMP_QCS+3903F900'(!)   = ''              | ''                 | 'CS+3903F900'           | 'R0603'             | '(SMR0603AW)'                  | '0.39'    | '1%'    | '1/10W ' | 'DISCRETE' | 'RES CHIP 0.39 1/10W +-1%(0603)'                   | 'CHIP0603'     | ''          | ''            | ''        
 '0.39'       | '1%'      | '1/10W'  | '0603LF ' | 'EMPTY'  | 'TMP_QCS+3903F900'(!)   = ''              | ''                 | 'CS+3903F900'           | 'R0603'             | '(SMR0603AW)'                  | '0.39'    | '1%'    | '1/10W ' | 'IO'       | 'RES CHIP 0.39 1/10W +-1%(0603)'                   | 'CHIP0603'     | ''          | ''            | ''        
 '2.61K'      | '1%'      | '1/16W ' | '0402LF ' | 'CHIP'   | 'TMP_QCS22612FB15'(!)   = 'End of Design' | 'Comp-Approve'     | 'CS22612FB15'           | 'R0402'             | '(R0402-0201)'                 | '2.61K'   | '1%'    | '1/16W ' | 'DISCRETE' | 'RES CHIP 2.61K 1/16W +-1%(0402)'                  | 'CHIP0402 '    | ''          | ''            | ''        
 '2.61K'      | '1%'      | '1/16W ' | '0402LF ' | 'EMPTY'  | 'TMP_QCS22612FB15'(!)   = 'End of Design' | 'Comp-Approve'     | 'CS22612FB15'           | 'R0402'             | '(R0402-0201)'                 | '2.61K'   | '1%'    | '1/16W ' | 'IO'       | 'RES CHIP 2.61K 1/16W +-1%(0402)'                  | 'CHIP0402 '    | ''          | ''            | ''        
 '52.3K'      | '1%'      | '1/10W'  | '0603LF ' | 'CHIP'   | 'TMP_QCS35233F916'(!)   = ''              | ''                 | 'CS35233F916'           | 'R0603'             | '(SMR0603AW)'                  | '52.3K'   | '1%'    | '1/10W ' | 'DISCRETE' | 'RES CHIP 52.3K 1/10W +-1% (0603)'                 | 'CHIP0603'     | ''          | ''            | ''        
 '52.3K'      | '1%'      | '1/10W'  | '0603LF ' | 'EMPTY'  | 'TMP_QCS35233F916'(!)   = ''              | ''                 | 'CS35233F916'           | 'R0603'             | '(SMR0603AW)'                  | '52.3K'   | '1%'    | '1/10W ' | 'IO'       | 'RES CHIP 52.3K 1/10W +-1% (0603)'                 | 'CHIP0603'     | ''          | ''            | ''        
 '6.49K'      | '1%'      | '1/16W ' | '0402LF ' | 'CHIP'   | 'TMP_QCS26492FB23'(!)   = 'End of Design' | 'Comp-Approve'     | 'CS26492FB23'           | 'R0402'             | '(R0402-0201)'                 | '6.49K'   | '1%'    | '1/16W ' | 'DISCRETE' | 'RES CHIP 6.49K 1/16W +-1%(0402)'                  | 'CHIP0402 '    | ''          | ''            | ''        
 '6.49K'      | '1%'      | '1/16W ' | '0402LF ' | 'EMPTY'  | 'TMP_QCS26492FB23'(!)   = 'End of Design' | 'Comp-Approve'     | 'CS26492FB23'           | 'R0402'             | '(R0402-0201)'                 | '6.49K'   | '1%'    | '1/16W ' | 'IO'       | 'RES CHIP 6.49K 1/16W +-1%(0402)'                  | 'CHIP0402 '    | ''          | ''            | ''        
 '1.47K'      | '1%'      | '1/16W ' | '0402LF ' | 'CHIP'   | 'TMP_QCS21472FB21'(!)   = 'End of Design' | 'Comp-Approve'     | 'CS21472FB21'           | 'R0402'             | '(R0402-0201)'                 | '1.47K'   | '1%'    | '1/16W ' | 'DISCRETE' | 'RES CHIP 1.47K 1/16W +-1% (0402)'                 | 'CHIP0402 '    | ''          | ''            | ''        
 '1.47K'      | '1%'      | '1/16W ' | '0402LF ' | 'EMPTY'  | 'TMP_QCS21472FB21'(!)   = 'End of Design' | 'Comp-Approve'     | 'CS21472FB21'           | 'R0402'             | '(R0402-0201)'                 | '1.47K'   | '1%'    | '1/16W ' | 'IO'       | 'RES CHIP 1.47K 1/16W +-1% (0402)'                 | 'CHIP0402 '    | ''          | ''            | ''        
 '9.1K'       | '0.5%'    | '1/10W'  | '0603LF ' | 'CHIP'   | 'TMP_QCS29103D915'(!)   = ''              | ''                 | 'CS29103D915'           | 'R0603'             | '(SMR0603AW)'                  | '9.1K'    | '0.5%'  | '1/10W ' | 'DISCRETE' | 'RES CHIP 9.1K 1/10W +-0.5%(0603)'                 | 'CHIP0603'     | ''          | ''            | ''        
 '9.1K'       | '0.5%'    | '1/10W'  | '0603LF ' | 'EMPTY'  | 'TMP_QCS29103D915'(!)   = ''              | ''                 | 'CS29103D915'           | 'R0603'             | '(SMR0603AW)'                  | '9.1K'    | '0.5%'  | '1/10W ' | 'IO'       | 'RES CHIP 9.1K 1/10W +-0.5%(0603)'                 | 'CHIP0603'     | ''          | ''            | ''        
 '4.32K'      | '1%'      | '1/16W'  | '0402LF'  | 'CHIP'   | 'TMP_QCS24322FB14'(!)   = 'End of Design' | 'Comp-Approve'     | 'CS24322FB14'           | 'R0402'             | '(R0402-0201)'                 | '4.32K'   | '1%'    | '1/16W'  | 'DISCRETE' | 'RES CHIP 4.32K 1/16W +-1%(0402)'                  | 'CHIP0402'     | ''          | ''            | ''        
 '4.32K'      | '1%'      | '1/16W'  | '0402LF'  | 'EMPTY'  | 'TMP_QCS24322FB14'(!)   = 'End of Design' | 'Comp-Approve'     | 'CS24322FB14'           | 'R0402'             | '(R0402-0201)'                 | '4.32K'   | '1%'    | '1/16W'  | 'IO'       | 'RES CHIP 4.32K 1/16W +-1%(0402)'                  | 'CHIP0402'     | ''          | ''            | ''        
 '7.5K'       | '1%'      | '1/16W'  | '0402LF'  | 'CHIP'   | 'TMP_QCS27502FB11'(!)   = 'End of Design' | 'Comp-Approve'     | 'CS27502FB11'           | 'R0402'             | '(R0402-0201)'                 | '7.5K'    | '1%'    | '1/16W'  | 'DISCRETE' | 'RES CHIP 7.5K 1/16W +-1% (0402)'                  | 'CHIP0402'     | ''          | ''            | ''        
 '7.5K'       | '1%'      | '1/16W'  | '0402LF'  | 'EMPTY'  | 'TMP_QCS27502FB11'(!)   = 'End of Design' | 'Comp-Approve'     | 'CS27502FB11'           | 'R0402'             | '(R0402-0201)'                 | '7.5K'    | '1%'    | '1/16W'  | 'IO'       | 'RES CHIP 7.5K 1/16W +-1% (0402)'                  | 'CHIP0402'     | ''          | ''            | ''        
 '300'        | '1%'      | '1/16W ' | '0402LF ' | 'CHIP'   | 'TMP_QCS13002FB00'(!)   = 'End of Design' | 'Comp-Approve'     | 'CS13002FB00'           | 'R0402'             | '(R0402-0201)'                 | '300'     | '1%'    | '1/16W ' | 'DISCRETE' | 'RES CHIP 300 1/16W +-1%(0402)'                    | 'CHIP0402 '    | ''          | ''            | ''        
 '300'        | '1%'      | '1/16W ' | '0402LF ' | 'EMPTY'  | 'TMP_QCS13002FB00'(!)   = 'End of Design' | 'Comp-Approve'     | 'CS13002FB00'           | 'R0402'             | '(R0402-0201)'                 | '300'     | '1%'    | '1/16W ' | 'IO'       | 'RES CHIP 300 1/16W +-1%(0402)'                    | 'CHIP0402 '    | ''          | ''            | ''        
 '120'        | '5%'      | '1/10W'  | '0603LF ' | 'CHIP'   | 'TMP_QCS11203J936'(!)   = ''              | ''                 | 'CS11203J936'           | 'R0603'             | '(SMR0603AW)'                  | '120'     | '5%'    | '1/10W ' | 'DISCRETE' | 'RES CHIP 120 1/10W +-5%(0603)'                    | 'CHIP0603'     | ''          | ''            | ''        
 '120'        | '5%'      | '1/10W'  | '0603LF ' | 'EMPTY'  | 'TMP_QCS11203J936'(!)   = ''              | ''                 | 'CS11203J936'           | 'R0603'             | '(SMR0603AW)'                  | '120'     | '5%'    | '1/10W ' | 'IO'       | 'RES CHIP 120 1/10W +-5%(0603)'                    | 'CHIP0603'     | ''          | ''            | ''        
 '150'        | '5%'      | '1/10W'  | '0603LF ' | 'CHIP'   | 'TMP_QCS11503J937'(!)   = ''              | ''                 | 'CS11503J937'           | 'R0603'             | '(SMR0603AW)'                  | '150'     | '5%'    | '1/10W ' | 'DISCRETE' | 'RES CHIP 150 1/10W +-5%(0603)'                    | 'CHIP0603'     | ''          | ''            | ''        
 '150'        | '5%'      | '1/10W'  | '0603LF ' | 'EMPTY'  | 'TMP_QCS11503J937'(!)   = ''              | ''                 | 'CS11503J937'           | 'R0603'             | '(SMR0603AW)'                  | '150'     | '5%'    | '1/10W ' | 'IO'       | 'RES CHIP 150 1/10W +-5%(0603)'                    | 'CHIP0603'     | ''          | ''            | ''        
 '93.1K'      | '1%'      | '1/16W ' | '0402LF ' | 'CHIP'   | 'TMP_QCS39312FB15'(!)   = 'End of Design' | 'Comp-Approve'     | 'CS39312FB15'           | 'R0402'             | '(R0402-0201)'                 | '93.1K'   | '1%'    | '1/16W ' | 'DISCRETE' | 'RES CHIP 93.1K 1/16W +-1%(0402)'                  | 'CHIP0402 '    | ''          | ''            | ''        
 '93.1K'      | '1%'      | '1/16W ' | '0402LF ' | 'EMPTY'  | 'TMP_QCS39312FB15'(!)   = 'End of Design' | 'Comp-Approve'     | 'CS39312FB15'           | 'R0402'             | '(R0402-0201)'                 | '93.1K'   | '1%'    | '1/16W ' | 'IO'       | 'RES CHIP 93.1K 1/16W +-1%(0402)'                  | 'CHIP0402 '    | ''          | ''            | ''        
 '10.2K'      | '1%'      | '1/16W ' | '0402LF ' | 'CHIP'   | 'TMP_QCS31022FB17'(!)   = 'End of Design' | 'Comp-Approve'     | 'CS31022FB17'           | 'R0402'             | '(R0402-0201)'                 | '10.2K'   | '1%'    | '1/16W ' | 'DISCRETE' | 'RES CHIP 10.2K 1/16W +-1%(0402)'                  | 'CHIP0402 '    | ''          | ''            | ''        
 '10.2K'      | '1%'      | '1/16W ' | '0402LF ' | 'EMPTY'  | 'TMP_QCS31022FB17'(!)   = 'End of Design' | 'Comp-Approve'     | 'CS31022FB17'           | 'R0402'             | '(R0402-0201)'                 | '10.2K'   | '1%'    | '1/16W ' | 'IO'       | 'RES CHIP 10.2K 1/16W +-1%(0402)'                  | 'CHIP0402 '    | ''          | ''            | ''        
 '1.37K'      | '1%'      | '1/16W ' | '0402LF ' | 'CHIP'   | 'TMP_QCS21372FB19'(!)   = 'End of Design' | 'Comp-Approve'     | 'CS21372FB19'           | 'R0402'             | '(R0402-0201)'                 | '1.37K'   | '1%'    | '1/16W ' | 'DISCRETE' | 'RES CHIP 1.37K 1/16W +-1%(0402)'                  | 'CHIP0402 '    | ''          | ''            | ''        
 '1.37K'      | '1%'      | '1/16W ' | '0402LF ' | 'EMPTY'  | 'TMP_QCS21372FB19'(!)   = 'End of Design' | 'Comp-Approve'     | 'CS21372FB19'           | 'R0402'             | '(R0402-0201)'                 | '1.37K'   | '1%'    | '1/16W ' | 'IO'       | 'RES CHIP 1.37K 1/16W +-1%(0402)'                  | 'CHIP0402 '    | ''          | ''            | ''        
 '90.9K'      | '1%'      | '1/16W ' | '0402LF ' | 'CHIP'   | 'TMP_QCS39092FB11'(!)   = 'End of Design' | 'Comp-Approve'     | 'CS39092FB11'           | 'R0402'             | '(R0402-0201)'                 | '90.9K'   | '1%'    | '1/16W ' | 'DISCRETE' | 'RES CHIP 90.9K 1/16W +-1% (0402)'                 | 'CHIP0402 '    | ''          | ''            | ''        
 '90.9K'      | '1%'      | '1/16W ' | '0402LF ' | 'EMPTY'  | 'TMP_QCS39092FB11'(!)   = 'End of Design' | 'Comp-Approve'     | 'CS39092FB11'           | 'R0402'             | '(R0402-0201)'                 | '90.9K'   | '1%'    | '1/16W ' | 'IO'       | 'RES CHIP 90.9K 1/16W +-1% (0402)'                 | 'CHIP0402 '    | ''          | ''            | ''        
 '45.3K'      | '1%'      | '1/16W ' | '0402LF ' | 'CHIP'   | 'TMP_QCS34532FB18'(!)   = 'End of Design' | 'Comp-Approve'     | 'CS34532FB18'           | 'R0402'             | '(R0402-0201)'                 | '45.3K'   | '1%'    | '1/16W ' | 'DISCRETE' | 'RES CHIP 45.3K 1/16W +-1% (0402)'                 | 'CHIP0402 '    | ''          | ''            | ''        
 '45.3K'      | '1%'      | '1/16W ' | '0402LF ' | 'EMPTY'  | 'TMP_QCS34532FB18'(!)   = 'End of Design' | 'Comp-Approve'     | 'CS34532FB18'           | 'R0402'             | '(R0402-0201)'                 | '45.3K'   | '1%'    | '1/16W ' | 'IO'       | 'RES CHIP 45.3K 1/16W +-1% (0402)'                 | 'CHIP0402 '    | ''          | ''            | ''        
 '5.49K'      | '1%'      | '1/16W ' | '0402LF ' | 'CHIP'   | 'TMP_QCS25492FB12'(!)   = 'End of Design' | 'Comp-Approve'     | 'CS25492FB12'           | 'R0402'             | '(R0402-0201)'                 | '5.49K'   | '1%'    | '1/16W ' | 'DISCRETE' | 'RES CHIP 5.49K 1/16W +-1%(0402)'                  | 'CHIP0402 '    | ''          | ''            | ''        
 '5.49K'      | '1%'      | '1/16W ' | '0402LF ' | 'EMPTY'  | 'TMP_QCS25492FB12'(!)   = 'End of Design' | 'Comp-Approve'     | 'CS25492FB12'           | 'R0402'             | '(R0402-0201)'                 | '5.49K'   | '1%'    | '1/16W ' | 'IO'       | 'RES CHIP 5.49K 1/16W +-1%(0402)'                  | 'CHIP0402 '    | ''          | ''            | ''        
 '5.1K'       | '1%'      | '1/10W'  | '0603LF ' | 'CHIP'   | 'TMP_QCS25103F917'(!)   = 'End of Design' | 'Comp-Release Qty' | 'CS25103F917'           | 'R0603'             | '(SMR0603AW)'                  | '5.1K'    | '1%'    | '1/10W ' | 'DISCRETE' | 'RES CHIP 5.1K 1/10W +-1% (0603)'                  | 'CHIP0603'     | ''          | ''            | ''        
 '5.1K'       | '1%'      | '1/10W'  | '0603LF ' | 'EMPTY'  | 'TMP_QCS25103F917'(!)   = 'End of Design' | 'Comp-Release Qty' | 'CS25103F917'           | 'R0603'             | '(SMR0603AW)'                  | '5.1K'    | '1%'    | '1/10W ' | 'IO'       | 'RES CHIP 5.1K 1/10W +-1% (0603)'                  | 'CHIP0603'     | ''          | ''            | ''        
 '10'         | '1%'      | '1/16W'  | '0402LF'  | 'CHIP'   | 'TMP_QCS01002FB21'(!)   = 'End of Design' | 'Comp-Approve'     | 'CS01002FB21'           | 'R0402'             | '(R0402-0201)'                 | '10'      | '1%'    | '1/16W'  | 'DISCRETE' | 'RES CHIP 10 1/16W +-1%(0402)'                     | 'CHIP0402'     | ''          | ''            | ''        
 '10'         | '1%'      | '1/16W'  | '0402LF'  | 'EMPTY'  | 'TMP_QCS01002FB21'(!)   = 'End of Design' | 'Comp-Approve'     | 'CS01002FB21'           | 'R0402'             | '(R0402-0201)'                 | '10'      | '1%'    | '1/16W'  | 'IO'       | 'RES CHIP 10 1/16W +-1%(0402)'                     | 'CHIP0402'     | ''          | ''            | ''        
 '56'         | '1%'      | '1/16W'  | '0402LF'  | 'CHIP'   | 'TMP_QCS05602FB15'(!)   = 'End of Design' | 'Comp-Approve'     | 'CS05602FB15'           | 'R0402'             | '(R0402-0201)'                 | '56'      | '1%'    | '1/16W'  | 'DISCRETE' | 'RESISTOR CHIP 56 1/16W +-1% (0402)'               | 'CHIP0402'     | ''          | ''            | ''        
 '56'         | '1%'      | '1/16W'  | '0402LF'  | 'EMPTY'  | 'TMP_QCS05602FB15'(!)   = 'End of Design' | 'Comp-Approve'     | 'CS05602FB15'           | 'R0402'             | '(R0402-0201)'                 | '56'      | '1%'    | '1/16W'  | 'IO'       | 'RESISTOR CHIP 56 1/16W +-1% (0402)'               | 'CHIP0402'     | ''          | ''            | ''        
 '82.5'       | '1%'      | '1/16W'  | '0402LF'  | 'CHIP'   | 'TMP_QCS08252FB11'(!)   = 'End of Design' | 'Comp-Approve'     | 'CS08252FB11'           | 'R0402'             | '(R0402-0201)'                 | '82.5'    | '1%'    | '1/16W'  | 'DISCRETE' | 'RES CHIP 82.5 1/16W +-1%(0402)'                   | 'CHIP0402'     | ''          | ''            | ''        
 '82.5'       | '1%'      | '1/16W'  | '0402LF'  | 'EMPTY'  | 'TMP_QCS08252FB11'(!)   = 'End of Design' | 'Comp-Approve'     | 'CS08252FB11'           | 'R0402'             | '(R0402-0201)'                 | '82.5'    | '1%'    | '1/16W'  | 'IO'       | 'RES CHIP 82.5 1/16W +-1%(0402)'                   | 'CHIP0402'     | ''          | ''            | ''        
 '100'        | '1%'      | '1/16W'  | '0402LF'  | 'CHIP'   | 'TMP_QCS11002FB22'(!)   = 'End of Design' | 'Comp-Approve'     | 'CS11002FB22'           | 'R0402'             | '(R0402-0201)'                 | '100'     | '1%'    | '1/16W'  | 'DISCRETE' | 'RES CHIP 100 1/16W +-1%(0402)'                    | 'CHIP0402'     | ''          | ''            | ''        
 '100'        | '1%'      | '1/16W'  | '0402LF'  | 'EMPTY'  | 'TMP_QCS11002FB22'(!)   = 'End of Design' | 'Comp-Approve'     | 'CS11002FB22'           | 'R0402'             | '(R0402-0201)'                 | '100'     | '1%'    | '1/16W'  | 'IO'       | 'RES CHIP 100 1/16W +-1%(0402)'                    | 'CHIP0402'     | ''          | ''            | ''        
 '100'        | '5%'      | '1/16W'  | '0402LF'  | 'CHIP'   | 'TMP_QCS11002JB32'(!)   = 'End of Design' | 'Comp-Approve'     | 'CS11002JB32'           | 'R0402'             | '(R0402-0201)'                 | '100'     | '5%'    | '1/16W'  | 'DISCRETE' | 'RES CHIP 100 1/16W +-5% (0402)'                   | 'CHIP0402'     | ''          | ''            | ''        
 '100'        | '5%'      | '1/16W'  | '0402LF'  | 'EMPTY'  | 'TMP_QCS11002JB32'(!)   = 'End of Design' | 'Comp-Approve'     | 'CS11002JB32'           | 'R0402'             | '(R0402-0201)'                 | '100'     | '5%'    | '1/16W'  | 'IO'       | 'RES CHIP 100 1/16W +-5% (0402)'                   | 'CHIP0402'     | ''          | ''            | ''        
 '178'        | '1%'      | '1/10W'  | '0603LF'  | 'CHIP'   | 'TMP_QCS11783F912'(!)   = ''              | ''                 | 'CS11783F912'           | 'R0603'             | '(SMR0603AW)'                  | '178'     | '1%'    | '1/10W'  | 'DISCRETE' | 'RES CHIP 178 1/10W +-1%(0603)'                    | 'CHIP0603'     | ''          | ''            | ''        
 '178'        | '1%'      | '1/10W'  | '0603LF'  | 'EMPTY'  | 'TMP_QCS11783F912'(!)   = ''              | ''                 | 'CS11783F912'           | 'R0603'             | '(SMR0603AW)'                  | '178'     | '1%'    | '1/10W'  | 'IO'       | 'RES CHIP 178 1/10W +-1%(0603)'                    | 'CHIP0603'     | ''          | ''            | ''        
 '301'        | '1%'      | '1/16W'  | '0402LF'  | 'CHIP'   | 'TMP_QCS13012FB14'(!)   = 'End of Design' | 'Comp-Approve'     | 'CS13012FB14'           | 'R0402'             | '(R0402-0201)'                 | '301'     | '1%'    | '1/16W'  | 'DISCRETE' | 'RES CHIP 301 1/16W +-1%(0402)'                    | 'CHIP0402'     | ''          | ''            | ''        
 '301'        | '1%'      | '1/16W'  | '0402LF'  | 'EMPTY'  | 'TMP_QCS13012FB14'(!)   = 'End of Design' | 'Comp-Approve'     | 'CS13012FB14'           | 'R0402'             | '(R0402-0201)'                 | '301'     | '1%'    | '1/16W'  | 'IO'       | 'RES CHIP 301 1/16W +-1%(0402)'                    | 'CHIP0402'     | ''          | ''            | ''        
 '340'        | '1%'      | '1/10W'  | '0603LF'  | 'CHIP'   | 'TMP_QCS13403F902'(!)   = ''              | ''                 | 'CS13403F902'           | 'R0603'             | '(SMR0603AW)'                  | '340'     | '1%'    | '1/10W'  | 'DISCRETE' | 'RES CHIP 340 1/10W +-1%(0603)'                    | 'CHIP0402'     | ''          | ''            | ''        
 '340'        | '1%'      | '1/10W'  | '0603LF'  | 'EMPTY'  | 'TMP_QCS13403F902'(!)   = ''              | ''                 | 'CS13403F902'           | 'R0603'             | '(SMR0603AW)'                  | '340'     | '1%'    | '1/10W'  | 'IO'       | 'RES CHIP 340 1/10W +-1%(0603)'                    | 'CHIP0402'     | ''          | ''            | ''        
 '953'        | '1%'      | '1/16W'  | '0402LF'  | 'CHIP'   | 'TMP_QCS19532FB00'(!)   = 'End of Design' | 'Comp-Approve'     | 'CS19532FB00'           | 'R0402'             | '(R0402-0201)'                 | '953'     | '1%'    | '1/16W'  | 'DISCRETE' | 'RES CHIP 953 1/16W +-1% (0402)'                   | 'CHIP0402'     | ''          | ''            | ''        
 '953'        | '1%'      | '1/16W'  | '0402LF'  | 'EMPTY'  | 'TMP_QCS19532FB00'(!)   = 'End of Design' | 'Comp-Approve'     | 'CS19532FB00'           | 'R0402'             | '(R0402-0201)'                 | '953'     | '1%'    | '1/16W'  | 'IO'       | 'RES CHIP 953 1/16W +-1% (0402)'                   | 'CHIP0402'     | ''          | ''            | ''        
 '1K'         | '5%'      | '1/16W'  | '0402LF'  | 'CHIP'   | 'TMP_QCS21002JB34'(!)   = 'End of Design' | 'Comp-Approve'     | 'CS21002JB34'           | 'R0402'             | '(R0402-0201)'                 | '1K'      | '5%'    | '1/16W'  | 'DISCRETE' | 'RES CHIP 1K 1/16W 5%(0402)'                       | 'CHIP0402'     | ''          | ''            | ''        
 '1K'         | '5%'      | '1/16W'  | '0402LF'  | 'EMPTY'  | 'TMP_QCS21002JB34'(!)   = 'End of Design' | 'Comp-Approve'     | 'CS21002JB34'           | 'R0402'             | '(R0402-0201)'                 | '1K'      | '5%'    | '1/16W'  | 'IO'       | 'RES CHIP 1K 1/16W 5%(0402)'                       | 'CHIP0402'     | ''          | ''            | ''        
 '1.21K'      | '1%'      | '1/16W'  | '0402LF'  | 'CHIP'   | 'TMP_QCS21212FB18'(!)   = 'End of Design' | 'Comp-Approve'     | 'CS21212FB18'           | 'R0402'             | '(R0402-0201)'                 | '1.21K'   | '1%'    | '1/16W'  | 'DISCRETE' | 'RES CHIP 1.21K 1/16W +-1%(0402)'                  | 'CHIP0402'     | ''          | ''            | ''        
 '1.21K'      | '1%'      | '1/16W'  | '0402LF'  | 'EMPTY'  | 'TMP_QCS21212FB18'(!)   = 'End of Design' | 'Comp-Approve'     | 'CS21212FB18'           | 'R0402'             | '(R0402-0201)'                 | '1.21K'   | '1%'    | '1/16W'  | 'IO'       | 'RES CHIP 1.21K 1/16W +-1%(0402)'                  | 'CHIP0402'     | ''          | ''            | ''        
 '2K'         | '1%'      | '1/16W'  | '0402LF'  | 'CHIP'   | 'TMP_QCS22002FB19'(!)   = 'End of Design' | 'Comp-Approve'     | 'CS22002FB19'           | 'R0402'             | '(R0402-0201)'                 | '2K'      | '1%'    | '1/16W'  | 'DISCRETE' | 'RES CHIP 2K 1/16W +-1%(0402)'                     | 'CHIP0402'     | ''          | ''            | ''        
 '2K'         | '1%'      | '1/16W'  | '0402LF'  | 'EMPTY'  | 'TMP_QCS22002FB19'(!)   = 'End of Design' | 'Comp-Approve'     | 'CS22002FB19'           | 'R0402'             | '(R0402-0201)'                 | '2K'      | '1%'    | '1/16W'  | 'IO'       | 'RES CHIP 2K 1/16W +-1%(0402)'                     | 'CHIP0402'     | ''          | ''            | ''        
 '2.2'        | '5%'      | '1/16W'  | '0402LF'  | 'CHIP'   | 'TMP_QCS-2202JB25'(!)   = 'End of Design' | 'Comp-Approve'     | 'CS-2202JB25'           | 'R0402'             | '(R0402-0201)'                 | '2.2'     | '5%'    | '1/16W'  | 'DISCRETE' | 'RES CHIP 2.2 1/16W +-5%  (0402)'                  | 'CHIP0402'     | ''          | ''            | ''        
 '2.2'        | '5%'      | '1/16W'  | '0402LF'  | 'EMPTY'  | 'TMP_QCS-2202JB25'(!)   = 'End of Design' | 'Comp-Approve'     | 'CS-2202JB25'           | 'R0402'             | '(R0402-0201)'                 | '2.2'     | '5%'    | '1/16W'  | 'IO'       | 'RES CHIP 2.2 1/16W +-5%  (0402)'                  | 'CHIP0402'     | ''          | ''            | ''        
 '2.2K'       | '1%'      | '1/16W'  | '0402LF'  | 'CHIP'   | 'TMP_QCS22202FB08'(!)   = 'End of Design' | 'Comp-Approve'     | 'CS22202FB08'           | 'R0402'             | '(R0402-0201)'                 | '2.2K'    | '1%'    | '1/16W'  | 'DISCRETE' | 'RES CHIP 2.2K 1/16W +-1%(0402)'                   | 'CHIP0402'     | ''          | ''            | ''        
 '2.2K'       | '1%'      | '1/16W'  | '0402LF'  | 'EMPTY'  | 'TMP_QCS22202FB08'(!)   = 'End of Design' | 'Comp-Approve'     | 'CS22202FB08'           | 'R0402'             | '(R0402-0201)'                 | '2.2K'    | '1%'    | '1/16W'  | 'IO'       | 'RES CHIP 2.2K 1/16W +-1%(0402)'                   | 'CHIP0402'     | ''          | ''            | ''        
 '2.26K'      | '1%'      | '1/16W'  | '0402LF'  | 'CHIP'   | 'TMP_QCS22262FB05'(!)   = 'End of Design' | 'Comp-Approve'     | 'CS22262FB05'           | 'R0402'             | '(R0402-0201)'                 | '2.26K'   | '1%'    | '1/16W'  | 'DISCRETE' | 'RES CHIP 2.26K 1/16W +-1%(0402)'                  | 'CHIP0402'     | ''          | ''            | ''        
 '2.26K'      | '1%'      | '1/16W'  | '0402LF'  | 'EMPTY'  | 'TMP_QCS22262FB05'(!)   = 'End of Design' | 'Comp-Approve'     | 'CS22262FB05'           | 'R0402'             | '(R0402-0201)'                 | '2.26K'   | '1%'    | '1/16W'  | 'IO'       | 'RES CHIP 2.26K 1/16W +-1%(0402)'                  | 'CHIP0402'     | ''          | ''            | ''        
 '2.8K'       | '1%'      | '1/16W'  | '0402LF'  | 'CHIP'   | 'TMP_QCS22802FB00'(!)   = ''              | ''                 | 'CS22802FB00'           | 'R0402'             | '(R0402-0201)'                 | '2.8K'    | '1%'    | '1/16W'  | 'DISCRETE' | 'RES CHIP 2.8K 1/16W +-1%(0402)'                   | 'CHIP0402'     | ''          | ''            | ''        
 '2.8K'       | '1%'      | '1/16W'  | '0402LF'  | 'EMPTY'  | 'TMP_QCS22802FB00'(!)   = ''              | ''                 | 'CS22802FB00'           | 'R0402'             | '(R0402-0201)'                 | '2.8K'    | '1%'    | '1/16W'  | 'IO'       | 'RES CHIP 2.8K 1/16W +-1%(0402)'                   | 'CHIP0402'     | ''          | ''            | ''        
 '3.3K'       | '1%'      | '1/16W'  | '0402LF'  | 'CHIP'   | 'TMP_QCS23302FB12'(!)   = 'End of Design' | 'Comp-Approve'     | 'CS23302FB12'           | 'R0402'             | '(R0402-0201)'                 | '3.3K'    | '1%'    | '1/16W'  | 'DISCRETE' | 'RES CHIP 3.3K 1/16W +-1%(0402)'                   | 'CHIP0402'     | ''          | ''            | ''        
 '3.3K'       | '1%'      | '1/16W'  | '0402LF'  | 'EMPTY'  | 'TMP_QCS23302FB12'(!)   = 'End of Design' | 'Comp-Approve'     | 'CS23302FB12'           | 'R0402'             | '(R0402-0201)'                 | '3.3K'    | '1%'    | '1/16W'  | 'IO'       | 'RES CHIP 3.3K 1/16W +-1%(0402)'                   | 'CHIP0402'     | ''          | ''            | ''        
 '5.1K'       | '1%'      | '1/16W'  | '0402LF'  | 'CHIP'   | 'TMP_QCS25102FB02'(!)   = 'End of Design' | 'Comp-Approve'     | 'CS25102FB02'           | 'R0402'             | '(R0402-0201)'                 | '5.1K'    | '1%'    | '1/16W'  | 'DISCRETE' | 'RES CHIP 5.1K 1/16W +-1%(0402)'                   | 'CHIP0402'     | ''          | ''            | ''        
 '5.1K'       | '1%'      | '1/16W'  | '0402LF'  | 'EMPTY'  | 'TMP_QCS25102FB02'(!)   = 'End of Design' | 'Comp-Approve'     | 'CS25102FB02'           | 'R0402'             | '(R0402-0201)'                 | '5.1K'    | '1%'    | '1/16W'  | 'IO'       | 'RES CHIP 5.1K 1/16W +-1%(0402)'                   | 'CHIP0402'     | ''          | ''            | ''        
 '5.11K'      | '1%'      | '1/16W'  | '0402LF'  | 'CHIP'   | 'TMP_QCS25112FB15'(!)   = 'End of Design' | 'Comp-Approve'     | 'CS25112FB15'           | 'R0402'             | '(R0402-0201)'                 | '5.11K'   | '1%'    | '1/16W'  | 'DISCRETE' | 'RES CHIP 5.11K 1/16W +-1%(0402)'                  | 'CHIP0402'     | ''          | ''            | ''        
 '5.11K'      | '1%'      | '1/16W'  | '0402LF'  | 'EMPTY'  | 'TMP_QCS25112FB15'(!)   = 'End of Design' | 'Comp-Approve'     | 'CS25112FB15'           | 'R0402'             | '(R0402-0201)'                 | '5.11K'   | '1%'    | '1/16W'  | 'IO'       | 'RES CHIP 5.11K 1/16W +-1%(0402)'                  | 'CHIP0402'     | ''          | ''            | ''        
 '7.15K'      | '1%'      | '1/16W'  | '0402LF'  | 'CHIP'   | 'TMP_QCS27152FB19'(!)   = ''              | ''                 | 'CS27152FB19'           | 'R0402'             | '(R0402-0201)'                 | '7.15K'   | '1%'    | '1/16W'  | 'DISCRETE' | 'RES CHIP 7.15K 1/16W +-1% (0402)'                 | 'CHIP0402'     | ''          | ''            | ''        
 '7.15K'      | '1%'      | '1/16W'  | '0402LF'  | 'EMPTY'  | 'TMP_QCS27152FB19'(!)   = ''              | ''                 | 'CS27152FB19'           | 'R0402'             | '(R0402-0201)'                 | '7.15K'   | '1%'    | '1/16W'  | 'IO'       | 'RES CHIP 7.15K 1/16W +-1% (0402)'                 | 'CHIP0402'     | ''          | ''            | ''        
 '11.3K'      | '1%'      | '1/16W'  | '0402LF'  | 'CHIP'   | 'TMP_QCS31132FB07'(!)   = 'End of Design' | 'Comp-Approve'     | 'CS31132FB07'           | 'R0402'             | '(R0402-0201)'                 | '11.3K'   | '1%'    | '1/16W'  | 'DISCRETE' | 'RES CHIP 11.3K 1/16W +-1%(0402)'                  | 'CHIP0402'     | ''          | ''            | ''        
 '11.3K'      | '1%'      | '1/16W'  | '0402LF'  | 'EMPTY'  | 'TMP_QCS31132FB07'(!)   = 'End of Design' | 'Comp-Approve'     | 'CS31132FB07'           | 'R0402'             | '(R0402-0201)'                 | '11.3K'   | '1%'    | '1/16W'  | 'IO'       | 'RES CHIP 11.3K 1/16W +-1%(0402)'                  | 'CHIP0402'     | ''          | ''            | ''        
 '13K'        | '1%'      | '1/16W'  | '0402LF'  | 'CHIP'   | 'TMP_QCS31302FB19'(!)   = 'End of Design' | 'Comp-Approve'     | 'CS31302FB19'           | 'R0402'             | '(R0402-0201)'                 | '13K'     | '1%'    | '1/16W'  | 'DISCRETE' | 'RES CHIP 13K 1/16W +-1%( 0402)'                   | 'CHIP0402'     | ''          | ''            | ''        
 '13K'        | '1%'      | '1/16W'  | '0402LF'  | 'EMPTY'  | 'TMP_QCS31302FB19'(!)   = 'End of Design' | 'Comp-Approve'     | 'CS31302FB19'           | 'R0402'             | '(R0402-0201)'                 | '13K'     | '1%'    | '1/16W'  | 'IO'       | 'RES CHIP 13K 1/16W +-1%( 0402)'                   | 'CHIP0402'     | ''          | ''            | ''        
 '18.2K'      | '1%'      | '1/16W'  | '0402LF'  | 'CHIP'   | 'TMP_QCS31822FB16'(!)   = 'End of Design' | 'Comp-Approve'     | 'CS31822FB16'           | 'R0402'             | '(R0402-0201)'                 | '18.2K'   | '1%'    | '1/16W'  | 'DISCRETE' | 'RES CHIP 18.2K 1/16W +-1%( 0402)'                 | 'CHIP0402'     | ''          | ''            | ''        
 '18.2K'      | '1%'      | '1/16W'  | '0402LF'  | 'EMPTY'  | 'TMP_QCS31822FB16'(!)   = 'End of Design' | 'Comp-Approve'     | 'CS31822FB16'           | 'R0402'             | '(R0402-0201)'                 | '18.2K'   | '1%'    | '1/16W'  | 'IO'       | 'RES CHIP 18.2K 1/16W +-1%( 0402)'                 | 'CHIP0402'     | ''          | ''            | ''        
 '20K'        | '5%'      | '1/16W'  | '0402LF'  | 'CHIP'   | 'TMP_QCS32002JB12'(!)   = 'End of Design' | 'Comp-Approve'     | 'CS32002JB12'           | 'R0402'             | '(R0402-0201)'                 | '20K'     | '5%'    | '1/16W'  | 'DISCRETE' | 'RES CHIP 20K 1/16W +-5% (0402)'                   | 'CHIP0402'     | ''          | ''            | ''        
 '20K'        | '5%'      | '1/16W'  | '0402LF'  | 'EMPTY'  | 'TMP_QCS32002JB12'(!)   = 'End of Design' | 'Comp-Approve'     | 'CS32002JB12'           | 'R0402'             | '(R0402-0201)'                 | '20K'     | '5%'    | '1/16W'  | 'IO'       | 'RES CHIP 20K 1/16W +-5% (0402)'                   | 'CHIP0402'     | ''          | ''            | ''        
 '61.9K'      | '1%'      | '1/16W'  | '0402LF'  | 'CHIP'   | 'TMP_QCS36192FB16'(!)   = 'End of Design' | 'Comp-Approve'     | 'CS36192FB16'           | 'R0402'             | '(R0402-0201)'                 | '61.9K'   | '1%'    | '1/16W'  | 'DISCRETE' | 'RES CHIP 61.9K 1/16W +-1%(0402)'                  | 'CHIP0402'     | ''          | ''            | ''        
 '61.9K'      | '1%'      | '1/16W'  | '0402LF'  | 'EMPTY'  | 'TMP_QCS36192FB16'(!)   = 'End of Design' | 'Comp-Approve'     | 'CS36192FB16'           | 'R0402'             | '(R0402-0201)'                 | '61.9K'   | '1%'    | '1/16W'  | 'IO'       | 'RES CHIP 61.9K 1/16W +-1%(0402)'                  | 'CHIP0402'     | ''          | ''            | ''        
 '68.1K'      | '1%'      | '1/16W'  | '0402LF'  | 'CHIP'   | 'TMP_QCS36812FB15'(!)   = 'End of Design' | 'Comp-Approve'     | 'CS36812FB15'           | 'R0402'             | '(R0402-0201)'                 | '68.1K'   | '1%'    | '1/16W'  | 'DISCRETE' | 'RES CHIP 68.1K 1/16W +-1%(0402)'                  | 'CHIP0402'     | ''          | ''            | ''        
 '68.1K'      | '1%'      | '1/16W'  | '0402LF'  | 'EMPTY'  | 'TMP_QCS36812FB15'(!)   = 'End of Design' | 'Comp-Approve'     | 'CS36812FB15'           | 'R0402'             | '(R0402-0201)'                 | '68.1K'   | '1%'    | '1/16W'  | 'IO'       | 'RES CHIP 68.1K 1/16W +-1%(0402)'                  | 'CHIP0402'     | ''          | ''            | ''        
 '150K'       | '1%'      | '1/16W'  | '0402LF'  | 'CHIP'   | 'TMP_QCS41502FB18'(!)   = 'End of Design' | 'Comp-Approve'     | 'CS41502FB18'           | 'R0402'             | '(R0402-0201)'                 | '150K'    | '1%'    | '1/16W'  | 'DISCRETE' | 'RES CHIP 150K 1/16W +-1%(0402)'                   | 'CHIP0402'     | ''          | ''            | ''        
 '150K'       | '1%'      | '1/16W'  | '0402LF'  | 'EMPTY'  | 'TMP_QCS41502FB18'(!)   = 'End of Design' | 'Comp-Approve'     | 'CS41502FB18'           | 'R0402'             | '(R0402-0201)'                 | '150K'    | '1%'    | '1/16W'  | 'IO'       | 'RES CHIP 150K 1/16W +-1%(0402)'                   | 'CHIP0402'     | ''          | ''            | ''        
 '147K'       | '0.1%'    | '1/16W'  | '0402LF'  | 'CHIP'   | 'TMP_QCS41472BB00'(!)   = ''              | ''                 | 'CS41472BB00'           | 'R0402'             | '(R0402-0201)'                 | '147K'    | '0.1%'  | '1/16W'  | 'DISCRETE' | 'RES CHIP 147K 1/16W +-0.1% (0402)'                | 'CHIP0402'     | ''          | ''            | ''        
 '147K'       | '0.1%'    | '1/16W'  | '0402LF'  | 'EMPTY'  | 'TMP_QCS41472BB00'(!)   = ''              | ''                 | 'CS41472BB00'           | 'R0402'             | '(R0402-0201)'                 | '147K'    | '0.1%'  | '1/16W'  | 'IO'       | 'RES CHIP 147K 1/16W +-0.1% (0402)'                | 'CHIP0402'     | ''          | ''            | ''        
 '7.15K'      | '0.1%'    | '1/16W'  | '0402LF'  | 'CHIP'   | 'TMP_QCS27152BB00'(!)   = ''              | ''                 | 'CS27152BB00'           | 'R0402'             | '(R0402-0201)'                 | '7.15K'   | '0.1%'  | '1/16W'  | 'DISCRETE' | 'RES CHIP 7.15K 1/16W +-0.1% (0402)'               | 'CHIP0402'     | ''          | ''            | ''        
 '7.15K'      | '0.1%'    | '1/16W'  | '0402LF'  | 'EMPTY'  | 'TMP_QCS27152BB00'(!)   = ''              | ''                 | 'CS27152BB00'           | 'R0402'             | '(R0402-0201)'                 | '7.15K'   | '0.1%'  | '1/16W'  | 'IO'       | 'RES CHIP 7.15K 1/16W +-0.1% (0402)'               | 'CHIP0402'     | ''          | ''            | ''        
 '140K'       | '0.1%'    | '1/16W'  | '0402LF'  | 'CHIP'   | 'TMP_QCS41402BB00'(!)   = ''              | ''                 | 'CS41402BB00'           | 'R0402'             | '(R0402-0201)'                 | '140K'    | '0.1%'  | '1/16W'  | 'DISCRETE' | 'RES CHIP 140K 1/16W +-0.1% (0402)'                | 'CHIP0402'     | ''          | ''            | ''        
 '140K'       | '0.1%'    | '1/16W'  | '0402LF'  | 'EMPTY'  | 'TMP_QCS41402BB00'(!)   = ''              | ''                 | 'CS41402BB00'           | 'R0402'             | '(R0402-0201)'                 | '140K'    | '0.1%'  | '1/16W'  | 'IO'       | 'RES CHIP 140K 1/16W +-0.1% (0402)'                | 'CHIP0402'     | ''          | ''            | ''        
 '330'        | '1%'      | '1/16W'  | '0402LF'  | 'CHIP'   | 'TMP_QCS13302FB11'(!)   = 'End of Design' | 'Comp-Approve'     | 'CS13302FB11'           | 'R0402'             | '(R0402-0201)'                 | '330'     | '1%'    | '1/16W'  | 'DISCRETE' | 'RES CHIP 330 1/16W +-1%(0402)'                    | 'CHIP0402'     | ''          | ''            | ''        
 '330'        | '1%'      | '1/16W'  | '0402LF'  | 'EMPTY'  | 'TMP_QCS13302FB11'(!)   = 'End of Design' | 'Comp-Approve'     | 'CS13302FB11'           | 'R0402'             | '(R0402-0201)'                 | '330'     | '1%'    | '1/16W'  | 'IO'       | 'RES CHIP 330 1/16W +-1%(0402)'                    | 'CHIP0402'     | ''          | ''            | ''        
 '220'        | '1%'      | '1/16W'  | '0402LF'  | 'CHIP'   | 'TMP_QCS12202FB14'(!)   = 'End of Design' | 'Comp-Approve'     | 'CS12202FB14'           | 'R0402'             | '(R0402-0201)'                 | '220'     | '1%'    | '1/16W'  | 'DISCRETE' | 'RES CHIP 220 1/16W +-1%(0402)'                    | 'CHIP0402'     | ''          | ''            | ''        
 '220'        | '1%'      | '1/16W'  | '0402LF'  | 'EMPTY'  | 'TMP_QCS12202FB14'(!)   = 'End of Design' | 'Comp-Approve'     | 'CS12202FB14'           | 'R0402'             | '(R0402-0201)'                 | '220'     | '1%'    | '1/16W'  | 'IO'       | 'RES CHIP 220 1/16W +-1%(0402)'                    | 'CHIP0402'     | ''          | ''            | ''        
 '5.76K'      | '1%'      | '1/16W'  | '0402LF'  | 'CHIP'   | 'TMP_QCS25762FB01'(!)   = 'End of Design' | 'Comp-Approve'     | 'CS25762FB01'           | 'R0402'             | '(R0402-0201)'                 | '5.76K'   | '1%'    | '1/16W'  | 'DISCRETE' | 'RES CHIP 5.76K 1/16W +-1%(0402)'                  | 'CHIP0402'     | ''          | ''            | ''        
 '5.76K'      | '1%'      | '1/16W'  | '0402LF'  | 'EMPTY'  | 'TMP_QCS25762FB01'(!)   = 'End of Design' | 'Comp-Approve'     | 'CS25762FB01'           | 'R0402'             | '(R0402-0201)'                 | '5.76K'   | '1%'    | '1/16W'  | 'IO'       | 'RES CHIP 5.76K 1/16W +-1%(0402)'                  | 'CHIP0402'     | ''          | ''            | ''        
 '3.74K'      | '1%'      | '1/16W'  | '0402LF'  | 'CHIP'   | 'TMP_QCS23742FB00'(!)   = 'End of Design' | 'Comp-Approve'     | 'CS23742FB00'           | 'R0402'             | '(R0402-0201)'                 | '3.74K'   | '1%'    | '1/16W'  | 'DISCRETE' | 'RES CHIP 3.74K 1/16W +-1%(0402)'                  | 'CHIP0402'     | ''          | ''            | ''        
 '3.74K'      | '1%'      | '1/16W'  | '0402LF'  | 'EMPTY'  | 'TMP_QCS23742FB00'(!)   = 'End of Design' | 'Comp-Approve'     | 'CS23742FB00'           | 'R0402'             | '(R0402-0201)'                 | '3.74K'   | '1%'    | '1/16W'  | 'IO'       | 'RES CHIP 3.74K 1/16W +-1%(0402)'                  | 'CHIP0402'     | ''          | ''            | ''        
 '12.7K'      | '1%'      | '1/16W'  | '0402LF'  | 'CHIP'   | 'TMP_QCS31272FB17'(!)   = 'End of Design' | 'Comp-Approve'     | 'CS31272FB17'           | 'R0402'             | '(R0402-0201)'                 | '12.7K'   | '1%'    | '1/16W'  | 'DISCRETE' | 'RES CHIP 12.7K 1/16W +-1% (0402)'                 | 'CHIP0402'     | ''          | ''            | ''        
 '12.7K'      | '1%'      | '1/16W'  | '0402LF'  | 'EMPTY'  | 'TMP_QCS31272FB17'(!)   = 'End of Design' | 'Comp-Approve'     | 'CS31272FB17'           | 'R0402'             | '(R0402-0201)'                 | '12.7K'   | '1%'    | '1/16W'  | 'IO'       | 'RES CHIP 12.7K 1/16W +-1% (0402)'                 | 'CHIP0402'     | ''          | ''            | ''        
 '31.6K'      | '1%'      | '1/16W'  | '0402LF'  | 'CHIP'   | 'TMP_QCS33162FB14'(!)   = 'End of Design' | 'Comp-Approve'     | 'CS33162FB14'           | 'R0402'             | '(R0402-0201)'                 | '31.6K'   | '1%'    | '1/16W'  | 'DISCRETE' | 'RES CHIP 31.6K 1/16W +-1%(0402)'                  | 'CHIP0402'     | ''          | ''            | ''        
 '31.6K'      | '1%'      | '1/16W'  | '0402LF'  | 'EMPTY'  | 'TMP_QCS33162FB14'(!)   = 'End of Design' | 'Comp-Approve'     | 'CS33162FB14'           | 'R0402'             | '(R0402-0201)'                 | '31.6K'   | '1%'    | '1/16W'  | 'IO'       | 'RES CHIP 31.6K 1/16W +-1%(0402)'                  | 'CHIP0402'     | ''          | ''            | ''        
 '54.9K'      | '1%'      | '1/16W'  | '0402LF'  | 'CHIP'   | 'TMP_QCS35492FB14'(!)   = 'End of Design' | 'Comp-Approve'     | 'CS35492FB14'           | 'R0402'             | '(R0402-0201)'                 | '54.9K'   | '1%'    | '1/16W'  | 'DISCRETE' | 'RES CHIP 54.9K 1/16W +-1%(0402)'                  | 'CHIP0402'     | ''          | ''            | ''        
 '54.9K'      | '1%'      | '1/16W'  | '0402LF'  | 'EMPTY'  | 'TMP_QCS35492FB14'(!)   = 'End of Design' | 'Comp-Approve'     | 'CS35492FB14'           | 'R0402'             | '(R0402-0201)'                 | '54.9K'   | '1%'    | '1/16W'  | 'IO'       | 'RES CHIP 54.9K 1/16W +-1%(0402)'                  | 'CHIP0402'     | ''          | ''            | ''        
 '8.87K'      | '1%'      | '1/16W'  | '0402LF'  | 'CHIP'   | 'TMP_QCS28872FB08'(!)   = 'End of Design' | 'Comp-Approve'     | 'CS28872FB08'           | 'R0402'             | '(R0402-0201)'                 | '8.87K'   | '1%'    | '1/16W'  | 'DISCRETE' | 'RES CHIP 8.87K 1/16W +-1%(0402)'                  | 'CHIP0402'     | ''          | ''            | ''        
 '8.87K'      | '1%'      | '1/16W'  | '0402LF'  | 'EMPTY'  | 'TMP_QCS28872FB08'(!)   = 'End of Design' | 'Comp-Approve'     | 'CS28872FB08'           | 'R0402'             | '(R0402-0201)'                 | '8.87K'   | '1%'    | '1/16W'  | 'IO'       | 'RES CHIP 8.87K 1/16W +-1%(0402)'                  | 'CHIP0402'     | ''          | ''            | ''        
 '2.67K'      | '1%'      | '1/16W'  | '0402LF'  | 'CHIP'   | 'TMP_QCS22672FB12'(!)   = 'End of Design' | 'Comp-Approve'     | 'CS22672FB12'           | 'R0402'             | '(R0402-0201)'                 | '2.67K'   | '1%'    | '1/16W'  | 'DISCRETE' | 'RES CHIP 2.67K 1/16W +-1%(0402) '                 | 'CHIP0402'     | ''          | ''            | ''        
 '2.67K'      | '1%'      | '1/16W'  | '0402LF'  | 'EMPTY'  | 'TMP_QCS22672FB12'(!)   = 'End of Design' | 'Comp-Approve'     | 'CS22672FB12'           | 'R0402'             | '(R0402-0201)'                 | '2.67K'   | '1%'    | '1/16W'  | 'IO'       | 'RES CHIP 2.67K 1/16W +-1%(0402) '                 | 'CHIP0402'     | ''          | ''            | ''        
 '5.36K'      | '1%'      | '1/16W'  | '0402LF'  | 'CHIP'   | 'TMP_QCS25362FB15'(!)   = 'End of Design' | 'Comp-Approve'     | 'CS25362FB15'           | 'R0402'             | '(R0402-0201)'                 | '5.36K'   | '1%'    | '1/16W'  | 'DISCRETE' | 'RES CHIP 5.36K 1/16W +-1%(0402) '                 | 'CHIP0402'     | ''          | ''            | ''        
 '5.36K'      | '1%'      | '1/16W'  | '0402LF'  | 'EMPTY'  | 'TMP_QCS25362FB15'(!)   = 'End of Design' | 'Comp-Approve'     | 'CS25362FB15'           | 'R0402'             | '(R0402-0201)'                 | '5.36K'   | '1%'    | '1/16W'  | 'IO'       | 'RES CHIP 5.36K 1/16W +-1%(0402) '                 | 'CHIP0402'     | ''          | ''            | ''        
 '390K'       | '1%'      | '1/16W'  | '0402LF'  | 'CHIP'   | 'TMP_QCS43902FB00'(!)   = 'End of Design' | 'Comp-Approve'     | 'CS43902FB00'           | 'R0402'             | '(R0402-0201)'                 | '390K'    | '1%'    | '1/16W'  | 'DISCRETE' | 'RES CHIP 390K 1/16W +-1%(0402)'                   | 'CHIP0402'     | ''          | ''            | ''        
 '390K'       | '1%'      | '1/16W'  | '0402LF'  | 'EMPTY'  | 'TMP_QCS43902FB00'(!)   = 'End of Design' | 'Comp-Approve'     | 'CS43902FB00'           | 'R0402'             | '(R0402-0201)'                 | '390K'    | '1%'    | '1/16W'  | 'IO'       | 'RES CHIP 390K 1/16W +-1%(0402)'                   | 'CHIP0402'     | ''          | ''            | ''        
 '100K'       | '1%'      | '1/16W'  | '0402LF'  | 'CHIP'   | 'TMP_QCS41002FB28'(!)   = 'End of Design' | 'Comp-Approve'     | 'CS41002FB28'           | 'R0402'             | '(R0402-0201)'                 | '100K'    | '1%'    | '1/16W'  | 'DISCRETE' | 'RES CHIP 100K 1/16W +-1% (0402)'                  | 'CHIP0402'     | ''          | ''            | ''        
 '100K'       | '1%'      | '1/16W'  | '0402LF'  | 'EMPTY'  | 'TMP_QCS41002FB28'(!)   = 'End of Design' | 'Comp-Approve'     | 'CS41002FB28'           | 'R0402'             | '(R0402-0201)'                 | '100K'    | '1%'    | '1/16W'  | 'IO'       | 'RES CHIP 100K 1/16W +-1% (0402)'                  | 'CHIP0402'     | ''          | ''            | ''        
 '110K'       | '1%'      | '1/16W'  | '0402LF'  | 'CHIP'   | 'TMP_QCS41102FB13'(!)   = 'End of Design' | 'Comp-Approve'     | 'CS41102FB13'           | 'R0402'             | '(R0402-0201)'                 | '110K'    | '1%'    | '1/16W'  | 'DISCRETE' | 'RES CHIP 110K 1/16W +-1%(0402)'                   | 'CHIP0402'     | ''          | ''            | ''        
 '110K'       | '1%'      | '1/16W'  | '0402LF'  | 'EMPTY'  | 'TMP_QCS41102FB13'(!)   = 'End of Design' | 'Comp-Approve'     | 'CS41102FB13'           | 'R0402'             | '(R0402-0201)'                 | '110K'    | '1%'    | '1/16W'  | 'IO'       | 'RES CHIP 110K 1/16W +-1%(0402)'                   | 'CHIP0402'     | ''          | ''            | ''        
 '10'         | '5%'      | '1/16W'  | '0402LF'  | 'CHIP'   | 'TMP_QCS01002JB22'(!)   = 'End of Design' | 'Comp-Approve'     | 'CS01002JB22'           | 'R0402'             | '(R0402-0201)'                 | '10'      | '5%'    | '1/16W'  | 'DISCRETE' | 'RES CHIP 10 1/16W +-5%(0402)'                     | 'CHIP0402'     | ''          | ''            | ''        
 '10'         | '5%'      | '1/16W'  | '0402LF'  | 'EMPTY'  | 'TMP_QCS01002JB22'(!)   = 'End of Design' | 'Comp-Approve'     | 'CS01002JB22'           | 'R0402'             | '(R0402-0201)'                 | '10'      | '5%'    | '1/16W'  | 'IO'       | 'RES CHIP 10 1/16W +-5%(0402)'                     | 'CHIP0402'     | ''          | ''            | ''        
 '20K'        | '5%'      | '1/16W'  | '0402LF'  | 'CHIP'   | 'TMP_QCS32002JB04'(!)   = ''              | ''                 | 'CS32002JB04'           | 'R0402'             | '(R0402-0201)'                 | '20K'     | '5%'    | '1/16W'  | 'DISCRETE' | 'RES CHIP 20K 1/16W +-5% (0402)'                   | 'CHIP0402'     | ''          | ''            | ''        
 '20K'        | '5%'      | '1/16W'  | '0402LF'  | 'EMPTY'  | 'TMP_QCS32002JB04'(!)   = ''              | ''                 | 'CS32002JB04'           | 'R0402'             | '(R0402-0201)'                 | '20K'     | '5%'    | '1/16W'  | 'IO'       | 'RES CHIP 20K 1/16W +-5% (0402)'                   | 'CHIP0402'     | ''          | ''            | ''        
 '56'         | '5%'      | '1/16W'  | '0402LF'  | 'CHIP'   | 'TMP_QCS05602JB17'(!)   = 'End of Design' | 'Comp-Approve'     | 'CS05602JB17'           | 'R0402'             | '(R0402-0201)'                 | '56'      | '5%'    | '1/16W'  | 'DISCRETE' | 'RES CHIP 56 1/16W +-5% (0402)'                    | 'CHIP0402'     | ''          | ''            | '20100527'
 '56'         | '5%'      | '1/16W'  | '0402LF'  | 'EMPTY'  | 'TMP_QCS05602JB17'(!)   = 'End of Design' | 'Comp-Approve'     | 'CS05602JB17'           | 'R0402'             | '(R0402-0201)'                 | '56'      | '5%'    | '1/16W'  | 'IO'       | 'RES CHIP 56 1/16W +-5% (0402)'                    | 'CHIP0402'     | ''          | ''            | '20100527'
 '20'         | '1%'      | '1/16W'  | '0402LF'  | 'CHIP'   | 'TMP_QCS02002FB23'(!)   = 'End of Design' | 'Comp-Approve'     | 'CS02002FB23'           | 'R0402'             | '(R0402-0201)'                 | '20'      | '1%'    | '1/16W'  | 'DISCRETE' | 'RES CHIP 20 1/16W +-1% (0402)'                    | 'CHIP0402'     | ''          | ''            | '20100601'
 '20'         | '1%'      | '1/16W'  | '0402LF'  | 'EMPTY'  | 'TMP_QCS02002FB23'(!)   = 'End of Design' | 'Comp-Approve'     | 'CS02002FB23'           | 'R0402'             | '(R0402-0201)'                 | '20'      | '1%'    | '1/16W'  | 'IO'       | 'RES CHIP 20 1/16W +-1% (0402)'                    | 'CHIP0402'     | ''          | ''            | '20100601'
 '4.02K'      | '1%'      | '1/16W'  | '0402LF'  | 'CHIP'   | 'TMP_QCS24022FB05'(!)   = ''              | ''                 | 'CS24022FB05'           | 'R0402'             | '(R0402-0201)'                 | '4.02K'   | '1%'    | '1/16W'  | 'DISCRETE' | 'RES CHIP 4.02K 1/16W +-1%(0402)'                  | 'CHIP0402'     | ''          | ''            | '20100601'
 '4.02K'      | '1%'      | '1/16W'  | '0402LF'  | 'EMPTY'  | 'TMP_QCS24022FB05'(!)   = ''              | ''                 | 'CS24022FB05'           | 'R0402'             | '(R0402-0201)'                 | '4.02K'   | '1%'    | '1/16W'  | 'IO'       | 'RES CHIP 4.02K 1/16W +-1%(0402)'                  | 'CHIP0402'     | ''          | ''            | '20100601'
 '21.5K'      | '1%'      | '1/16W'  | '0402LF'  | 'CHIP'   | 'TMP_QCS32152FB17'(!)   = 'End of Design' | 'Comp-Approve'     | 'CS32152FB17'           | 'R0402'             | '(R0402-0201)'                 | '21.5K'   | '1%'    | '1/16W'  | 'DISCRETE' | 'RES CHIP 21.5K 1/16W +-1%(0402)'                  | 'CHIP0402'     | ''          | ''            | '20100601'
 '21.5K'      | '1%'      | '1/16W'  | '0402LF'  | 'EMPTY'  | 'TMP_QCS32152FB17'(!)   = 'End of Design' | 'Comp-Approve'     | 'CS32152FB17'           | 'R0402'             | '(R0402-0201)'                 | '21.5K'   | '1%'    | '1/16W'  | 'IO'       | 'RES CHIP 21.5K 1/16W +-1%(0402)'                  | 'CHIP0402'     | ''          | ''            | '20100601'
 '1'          | '1%'      | '1/4W'   | '1206LF'  | 'CHIP'   | 'TMP_QCS-1006F209'(!)   = 'End of Design' | 'Comp-Approve'     | 'CS-1006F209'           | 'R1206'             | '(SMR1206AW)'                  | '1'       | '1%'    | '1/4W'   | 'DISCRETE' | 'RES CHIP 1 1/4W +-1%(1206)'                       | 'CHIP1206'     | ''          | ''            | '20100603'
 '1'          | '1%'      | '1/4W'   | '1206LF'  | 'EMPTY'  | 'TMP_QCS-1006F209'(!)   = 'End of Design' | 'Comp-Approve'     | 'CS-1006F209'           | 'R1206'             | '(SMR1206AW)'                  | '1'       | '1%'    | '1/4W'   | 'IO'       | 'RES CHIP 1 1/4W +-1%(1206)'                       | 'CHIP1206'     | ''          | ''            | '20100603'
 '2K'         | '5%'      | '1/16W'  | '0402LF'  | 'CHIP'   | 'TMP_QCS22002JB29'(!)   = 'End of Design' | 'Comp-Approve'     | 'CS22002JB29'           | 'R0402'             | '(R0402-0201)'                 | '2K'      | '5%'    | '1/16W'  | 'DISCRETE' | 'RES CHIP 2K(1/16W +-5% 0402)'                     | 'CHIP0402'     | ''          | ''            | '20100603'
 '2K'         | '5%'      | '1/16W'  | '0402LF'  | 'EMPTY'  | 'TMP_QCS22002JB29'(!)   = 'End of Design' | 'Comp-Approve'     | 'CS22002JB29'           | 'R0402'             | '(R0402-0201)'                 | '2K'      | '5%'    | '1/16W'  | 'IO'       | 'RES CHIP 2K(1/16W +-5% 0402)'                     | 'CHIP0402'     | ''          | ''            | '20100603'
 '430'        | '1%'      | '1/16W'  | '0402LF'  | 'CHIP'   | 'CS14302FB05'(!)        = 'End of Design' | 'Comp-Approve'     | 'CS14302FB05'           | 'R0402'             | '(R0402-0201)'                 | '430'     | '1%'    | '1/16W'  | 'DISCRETE' | 'RES CHIP 430 1/16W +-1%(0402)'                    | 'CHIP0402'     | ''          | ''            | '20100609'
 '430'        | '1%'      | '1/16W'  | '0402LF'  | 'EMPTY'  | 'CS14302FB05'(!)        = 'End of Design' | 'Comp-Approve'     | 'CS14302FB05'           | 'R0402'             | '(R0402-0201)'                 | '430'     | '1%'    | '1/16W'  | 'IO'       | 'RES CHIP 430 1/16W +-1%(0402)'                    | 'CHIP0402'     | ''          | ''            | '20100609'
 '422'        | '1%'      | '1/16W'  | '0402LF'  | 'CHIP'   | 'CS14222FB19'(!)        = 'End of Design' | 'Comp-Approve'     | 'CS14222FB19'           | 'R0402'             | '(R0402-0201)'                 | '422'     | '1%'    | '1/16W'  | 'DISCRETE' | 'RES CHIP 422 1/16W +-1% (0402)'                   | 'CHIP0402'     | ''          | ''            | '20100609'
 '422'        | '1%'      | '1/16W'  | '0402LF'  | 'EMPTY'  | 'CS14222FB19'(!)        = 'End of Design' | 'Comp-Approve'     | 'CS14222FB19'           | 'R0402'             | '(R0402-0201)'                 | '422'     | '1%'    | '1/16W'  | 'IO'       | 'RES CHIP 422 1/16W +-1% (0402)'                   | 'CHIP0402'     | ''          | ''            | '20100609'
 '120'        | '1%'      | '1/16W'  | '0402LF'  | 'CHIP'   | 'CS11202FB11'(!)        = 'End of Design' | 'Comp-Approve'     | 'CS11202FB11'           | 'R0402'             | '(R0402-0201)'                 | '120'     | '1%'    | '1/16W'  | 'DISCRETE' | 'RES CHIP 120 1/16W +-1%(0402)'                    | 'CHIP0402'     | ''          | ''            | '20100609'
 '120'        | '1%'      | '1/16W'  | '0402LF'  | 'EMPTY'  | 'CS11202FB11'(!)        = 'End of Design' | 'Comp-Approve'     | 'CS11202FB11'           | 'R0402'             | '(R0402-0201)'                 | '120'     | '1%'    | '1/16W'  | 'IO'       | 'RES CHIP 120 1/16W +-1%(0402)'                    | 'CHIP0402'     | ''          | ''            | '20100609'
 '866'        | '1%'      | '1/10W'  | '0603LF ' | 'CHIP'   | 'CS18663F919'(!)        = ''              | ''                 | 'CS18663F919'           | 'R0603'             | '(SMR0603AW)'                  | '866'     | '1%'    | '1/10W ' | 'DISCRETE' | 'RESISTER CHIP 866 1/10W +-1%(0603)'               | 'CHIP0603'     | ''          | ''            | '20100609'
 '866'        | '1%'      | '1/10W'  | '0603LF ' | 'EMPTY'  | 'CS18663F919'(!)        = ''              | ''                 | 'CS18663F919'           | 'R0603'             | '(SMR0603AW)'                  | '866'     | '1%'    | '1/10W ' | 'IO'       | 'RESISTER CHIP 866 1/10W +-1%(0603)'               | 'CHIP0603'     | ''          | ''            | '20100609'
 '1.74K'      | '1%'      | '1/16W'  | '0402LF'  | 'CHIP'   | 'CS21742FB00'(!)        = 'End of Design' | 'Comp-Approve'     | 'CS21742FB00'           | 'R0402'             | '(R0402-0201)'                 | '1.74K'   | '1%'    | '1/16W'  | 'DISCRETE' | 'RES CHIP 1.74K 1/16W +-1%(0402)'                  | 'CHIP0402'     | ''          | ''            | '20100610'
 '1.74K'      | '1%'      | '1/16W'  | '0402LF'  | 'EMPTY'  | 'CS21742FB00'(!)        = 'End of Design' | 'Comp-Approve'     | 'CS21742FB00'           | 'R0402'             | '(R0402-0201)'                 | '1.74K'   | '1%'    | '1/16W'  | 'IO'       | 'RES CHIP 1.74K 1/16W +-1%(0402)'                  | 'CHIP0402'     | ''          | ''            | '20100610'
 '3.48K'      | '1%'      | '1/16W'  | '0402LF'  | 'CHIP'   | 'CS23482FB12'(!)        = 'End of Design' | 'Comp-Approve'     | 'CS23482FB12'           | 'R0402'             | '(R0402-0201)'                 | '3.48K'   | '1%'    | '1/16W'  | 'DISCRETE' | 'RES CHIP 3.48K 1/16W +-1%( 0402)'                 | 'CHIP0402'     | ''          | ''            | '20100611'
 '3.48K'      | '1%'      | '1/16W'  | '0402LF'  | 'EMPTY'  | 'CS23482FB12'(!)        = 'End of Design' | 'Comp-Approve'     | 'CS23482FB12'           | 'R0402'             | '(R0402-0201)'                 | '3.48K'   | '1%'    | '1/16W'  | 'IO'       | 'RES CHIP 3.48K 1/16W +-1%( 0402)'                 | 'CHIP0402'     | ''          | ''            | '20100611'
 '154'        | '1%'      | '1/16W'  | '0402LF'  | 'CHIP'   | 'CS11542FB00'(!)        = 'End of Design' | 'Comp-Approve'     | 'CS11542FB00'           | 'R0402'             | '(R0402-0201)'                 | '154'     | '1%'    | '1/16W'  | 'DISCRETE' | 'RES CHIP 154 1/16W +-1%(0402)'                    | 'CHIP0402'     | ''          | ''            | '20100614'
 '154'        | '1%'      | '1/16W'  | '0402LF'  | 'EMPTY'  | 'CS11542FB00'(!)        = 'End of Design' | 'Comp-Approve'     | 'CS11542FB00'           | 'R0402'             | '(R0402-0201)'                 | '154'     | '1%'    | '1/16W'  | 'IO'       | 'RES CHIP 154 1/16W +-1%(0402)'                    | 'CHIP0402'     | ''          | ''            | '20100614'
 '402'        | '1%'      | '1/16W'  | '0402LF'  | 'CHIP'   | 'CS14022FB03'(!)        = ''              | ''                 | 'CS14022FB03'           | 'R0402'             | '(R0402-0201)'                 | '402'     | '1%'    | '1/16W'  | 'DISCRETE' | 'RES CHIP 402 1/16W +-1%(0402)'                    | 'CHIP0402'     | ''          | ''            | '20100614'
 '402'        | '1%'      | '1/16W'  | '0402LF'  | 'EMPTY'  | 'CS14022FB03'(!)        = ''              | ''                 | 'CS14022FB03'           | 'R0402'             | '(R0402-0201)'                 | '402'     | '1%'    | '1/16W'  | 'IO'       | 'RES CHIP 402 1/16W +-1%(0402)'                    | 'CHIP0402'     | ''          | ''            | '20100614'
 '2.15K'      | '1%'      | '1/16W'  | '0402LF'  | 'CHIP'   | 'CS22152FB07'(!)        = 'End of Design' | 'Comp-Approve'     | 'CS22152FB07'           | 'R0402'             | '(R0402-0201)'                 | '2.15K'   | '1%'    | '1/16W'  | 'DISCRETE' | 'RES CHIP 2.15K 1/16W +-1%(0402)'                  | 'CHIP0402'     | ''          | ''            | '20100614'
 '2.15K'      | '1%'      | '1/16W'  | '0402LF'  | 'EMPTY'  | 'CS22152FB07'(!)        = 'End of Design' | 'Comp-Approve'     | 'CS22152FB07'           | 'R0402'             | '(R0402-0201)'                 | '2.15K'   | '1%'    | '1/16W'  | 'IO'       | 'RES CHIP 2.15K 1/16W +-1%(0402)'                  | 'CHIP0402'     | ''          | ''            | '20100614'
 '3.57K'      | '1%'      | '1/16W'  | '0402LF'  | 'CHIP'   | 'CS23572FB11'(!)        = 'End of Design' | 'Comp-Approve'     | 'CS23572FB11'           | 'R0402'             | '(R0402-0201)'                 | '3.57K'   | '1%'    | '1/16W'  | 'DISCRETE' | 'RES CHIP 3.57K 1/16W +-1%(0402)'                  | 'CHIP0402'     | ''          | ''            | '20100614'
 '3.57K'      | '1%'      | '1/16W'  | '0402LF'  | 'EMPTY'  | 'CS23572FB11'(!)        = 'End of Design' | 'Comp-Approve'     | 'CS23572FB11'           | 'R0402'             | '(R0402-0201)'                 | '3.57K'   | '1%'    | '1/16W'  | 'IO'       | 'RES CHIP 3.57K 1/16W +-1%(0402)'                  | 'CHIP0402'     | ''          | ''            | '20100614'
 '3.92K'      | '1%'      | '1/16W'  | '0402LF'  | 'CHIP'   | 'CS23922FB13'(!)        = 'End of Design' | 'Comp-Approve'     | 'CS23922FB13'           | 'R0402'             | '(R0402-0201)'                 | '3.92K'   | '1%'    | '1/16W'  | 'DISCRETE' | 'RES CHIP 3.92K 1/16W +-1% (0402)'                 | 'CHIP0402'     | ''          | ''            | '20100614'
 '3.92K'      | '1%'      | '1/16W'  | '0402LF'  | 'EMPTY'  | 'CS23922FB13'(!)        = 'End of Design' | 'Comp-Approve'     | 'CS23922FB13'           | 'R0402'             | '(R0402-0201)'                 | '3.92K'   | '1%'    | '1/16W'  | 'IO'       | 'RES CHIP 3.92K 1/16W +-1% (0402)'                 | 'CHIP0402'     | ''          | ''            | '20100614'
 '1.5K'       | '1%'      | '1/16W'  | '0402LF'  | 'CHIP'   | 'CS21502FB14'(!)        = 'End of Design' | 'Comp-Release Qty' | 'CS21502FB14'           | 'R0402'             | '(R0402-0201)'                 | '1.5K'    | '1%'    | '1/16W'  | 'DISCRETE' | 'RES CHIP 1.5K 1/16W +-1% (0402)'                  | 'CHIP0402'     | ''          | ''            | '20100614'
 '1.5K'       | '1%'      | '1/16W'  | '0402LF'  | 'EMPTY'  | 'CS21502FB14'(!)        = 'End of Design' | 'Comp-Release Qty' | 'CS21502FB14'           | 'R0402'             | '(R0402-0201)'                 | '1.5K'    | '1%'    | '1/16W'  | 'IO'       | 'RES CHIP 1.5K 1/16W +-1% (0402)'                  | 'CHIP0402'     | ''          | ''            | '20100614'
 '261'        | '1%'      | '1/16W'  | '0402LF'  | 'CHIP'   | 'CS12612FB05'(!)        = ''              | ''                 | 'CS12612FB05'           | 'R0402'             | '(R0402-0201)'                 | '261'     | '1%'    | '1/16W'  | 'DISCRETE' | 'RES CHIP 261 1/16W +-1%(0402)'                    | 'CHIP0402'     | ''          | ''            | '20100614'
 '261'        | '1%'      | '1/16W'  | '0402LF'  | 'EMPTY'  | 'CS12612FB05'(!)        = ''              | ''                 | 'CS12612FB05'           | 'R0402'             | '(R0402-0201)'                 | '261'     | '1%'    | '1/16W'  | 'IO'       | 'RES CHIP 261 1/16W +-1%(0402)'                    | 'CHIP0402'     | ''          | ''            | '20100614'
 '20.5K'      | '1%'      | '1/16W'  | '0402LF'  | 'CHIP'   | 'CS32052FB21'(!)        = 'End of Design' | 'Comp-Approve'     | 'CS32052FB21'           | 'R0402'             | '(R0402-0201)'                 | '20.5K'   | '1%'    | '1/16W'  | 'DISCRETE' | 'RES CHIP 20.5K 1/16W +-1%(0402)'                  | 'CHIP0402'     | ''          | ''            | '20100615'
 '20.5K'      | '1%'      | '1/16W'  | '0402LF'  | 'EMPTY'  | 'CS32052FB21'(!)        = 'End of Design' | 'Comp-Approve'     | 'CS32052FB21'           | 'R0402'             | '(R0402-0201)'                 | '20.5K'   | '1%'    | '1/16W'  | 'IO'       | 'RES CHIP 20.5K 1/16W +-1%(0402)'                  | 'CHIP0402'     | ''          | ''            | '20100615'
 '34K'        | '1%'      | '1/16W'  | '0402LF'  | 'CHIP'   | 'CS33402FB18'(!)        = 'End of Design' | 'Comp-Approve'     | 'CS33402FB18'           | 'R0402'             | '(R0402-0201)'                 | '34K'     | '1%'    | '1/16W'  | 'DISCRETE' | 'RES CHIP 34K 1/16W +-1% (0402)'                   | 'CHIP0402'     | ''          | ''            | '20100615'
 '34K'        | '1%'      | '1/16W'  | '0402LF'  | 'EMPTY'  | 'CS33402FB18'(!)        = 'End of Design' | 'Comp-Approve'     | 'CS33402FB18'           | 'R0402'             | '(R0402-0201)'                 | '34K'     | '1%'    | '1/16W'  | 'IO'       | 'RES CHIP 34K 1/16W +-1% (0402)'                   | 'CHIP0402'     | ''          | ''            | '20100615'
 '8.66K'      | '1%'      | '1/16W'  | '0402LF'  | 'CHIP'   | 'CS28662FB14'(!)        = 'End of Design' | 'Comp-Approve'     | 'CS28662FB14'           | 'R0402'             | '(R0402-0201)'                 | '8.66K'   | '1%'    | '1/16W'  | 'DISCRETE' | 'RES CHIP 8.66K 1/16W +-1%(0402)'                  | 'CHIP0402'     | ''          | ''            | '20100615'
 '8.66K'      | '1%'      | '1/16W'  | '0402LF'  | 'EMPTY'  | 'CS28662FB14'(!)        = 'End of Design' | 'Comp-Approve'     | 'CS28662FB14'           | 'R0402'             | '(R0402-0201)'                 | '8.66K'   | '1%'    | '1/16W'  | 'IO'       | 'RES CHIP 8.66K 1/16W +-1%(0402)'                  | 'CHIP0402'     | ''          | ''            | '20100615'
 '54.9'       | '1%'      | '1/16W'  | '0402LF'  | 'CHIP'   | 'CS05492FB19'(!)        = 'End of Design' | 'Comp-Approve'     | 'CS05492FB19'           | 'R0402'             | '(R0402-0201)'                 | '54.9'    | '1%'    | '1/16W'  | 'DISCRETE' | 'RES CHIP 54.9 1/16W +-1%(0402)'                   | 'CHIP0402'     | ''          | ''            | '20100617'
 '54.9'       | '1%'      | '1/16W'  | '0402LF'  | 'EMPTY'  | 'CS05492FB19'(!)        = 'End of Design' | 'Comp-Approve'     | 'CS05492FB19'           | 'R0402'             | '(R0402-0201)'                 | '54.9'    | '1%'    | '1/16W'  | 'IO'       | 'RES CHIP 54.9 1/16W +-1%(0402)'                   | 'CHIP0402'     | ''          | ''            | '20100617'
 '4.02K'      | '1%'      | '1/16W'  | '0402LF'  | 'CHIP'   | 'CS24022FB05'(!)        = ''              | ''                 | 'CS24022FB05'           | 'R0402'             | '(R0402-0201)'                 | '4.02K'   | '1%'    | '1/16W'  | 'DISCRETE' | 'RES CHIP 4.02K 1/16W +-1%(0402)'                  | 'CHIP0402'     | ''          | ''            | '20100617'
 '4.02K'      | '1%'      | '1/16W'  | '0402LF'  | 'EMPTY'  | 'CS24022FB05'(!)        = ''              | ''                 | 'CS24022FB05'           | 'R0402'             | '(R0402-0201)'                 | '4.02K'   | '1%'    | '1/16W'  | 'IO'       | 'RES CHIP 4.02K 1/16W +-1%(0402)'                  | 'CHIP0402'     | ''          | ''            | '20100617'
 '3.4K'       | '1%'      | '1/16W'  | '0402LF'  | 'CHIP'   | 'CS23402FB08'(!)        = 'End of Design' | 'Comp-Approve'     | 'CS23402FB08'           | 'R0402'             | '(R0402-0201)'                 | '3.4K'    | '1%'    | '1/16W'  | 'DISCRETE' | 'RES CHIP 3.4K 1/16W +-1%(0402)'                   | 'CHIP0402'     | ''          | ''            | '20100617'
 '3.4K'       | '1%'      | '1/16W'  | '0402LF'  | 'EMPTY'  | 'CS23402FB08'(!)        = 'End of Design' | 'Comp-Approve'     | 'CS23402FB08'           | 'R0402'             | '(R0402-0201)'                 | '3.4K'    | '1%'    | '1/16W'  | 'IO'       | 'RES CHIP 3.4K 1/16W +-1%(0402)'                   | 'CHIP0402'     | ''          | ''            | '20100617'
 '187K'       | '1%'      | '1/16W'  | '0402LF'  | 'CHIP'   | 'CS41872FB10'(!)        = 'End of Design' | 'Comp-Approve'     | 'CS41872FB10'           | 'R0402'             | '(R0402-0201)'                 | '187K'    | '1%'    | '1/16W'  | 'DISCRETE' | 'RES CHIP 187K 1/16W +-1%(0402)'                   | 'CHIP0402'     | ''          | ''            | '20100617'
 '187K'       | '1%'      | '1/16W'  | '0402LF'  | 'EMPTY'  | 'CS41872FB10'(!)        = 'End of Design' | 'Comp-Approve'     | 'CS41872FB10'           | 'R0402'             | '(R0402-0201)'                 | '187K'    | '1%'    | '1/16W'  | 'IO'       | 'RES CHIP 187K 1/16W +-1%(0402)'                   | 'CHIP0402'     | ''          | ''            | '20100617'
 '1M'         | '1%'      | '1/16W'  | '0402LF'  | 'CHIP'   | 'CS51002FB11'(!)        = 'End of Design' | 'Comp-Approve'     | 'CS51002FB11'           | 'R0402'             | '(R0402-0201)'                 | '1M'      | '1%'    | '1/16W'  | 'DISCRETE' | 'RES CHIP 1M 1/16W +-1% (0402)'                    | 'CHIP0402'     | ''          | ''            | '20100617'
 '1M'         | '1%'      | '1/16W'  | '0402LF'  | 'EMPTY'  | 'CS51002FB11'(!)        = 'End of Design' | 'Comp-Approve'     | 'CS51002FB11'           | 'R0402'             | '(R0402-0201)'                 | '1M'      | '1%'    | '1/16W'  | 'IO'       | 'RES CHIP 1M 1/16W +-1% (0402)'                    | 'CHIP0402'     | ''          | ''            | '20100617'
 '562'        | '1%'      | '1/16W'  | '0402LF'  | 'CHIP'   | 'CS15622FB08'(!)        = ''              | ''                 | 'CS15622FB08'           | 'R0402'             | '(R0402-0201)'                 | '562'     | '1%'    | '1/16W'  | 'DISCRETE' | 'RES CIHP 562 1/16W +-1% (0402)'                   | 'CHIP0402'     | ''          | ''            | '20100617'
 '562'        | '1%'      | '1/16W'  | '0402LF'  | 'EMPTY'  | 'CS15622FB08'(!)        = ''              | ''                 | 'CS15622FB08'           | 'R0402'             | '(R0402-0201)'                 | '562'     | '1%'    | '1/16W'  | 'IO'       | 'RES CIHP 562 1/16W +-1% (0402)'                   | 'CHIP0402'     | ''          | ''            | '20100617'
 '0'          | '5%'      | '1/16W'  | '0402LF'  | 'CHIP'   | 'CS00002JB38'(!)        = 'End of Design' | 'Comp-Approve'     | 'CS00002JB38'           | 'R0402'             | '(R0402-0201)'                 | '0'       | '5%'    | '1/16W'  | 'DISCRETE' | 'RESISTOR CHIP 0 1/16W +-5%(0402)'                 | 'CHIP0402'     | ''          | ''            | '20100618'
 '0'          | '5%'      | '1/16W'  | '0402LF'  | 'EMPTY'  | 'CS00002JB38'(!)        = 'End of Design' | 'Comp-Approve'     | 'CS00002JB38'           | 'R0402'             | '(R0402-0201)'                 | '0'       | '5%'    | '1/16W'  | 'IO'       | 'RESISTOR CHIP 0 1/16W +-5%(0402)'                 | 'CHIP0402'     | ''          | ''            | '20100618'
 '4.99K'      | '0.5%'    | '1/16W'  | '0402LF'  | 'CHIP'   | 'CS24992DB00'(!)        = ''              | ''                 | 'CS24992DB00'           | 'R0402'             | '(R0402-0201)'                 | '4.99K'   | '0.5%'  | '1/16W'  | 'DISCRETE' | 'RES CHIP 4.99K 1/16W +-0.5%(0402)'                | 'CHIP0402'     | ''          | ''            | '20100618'
 '4.99K'      | '0.5%'    | '1/16W'  | '0402LF'  | 'EMPTY'  | 'CS24992DB00'(!)        = ''              | ''                 | 'CS24992DB00'           | 'R0402'             | '(R0402-0201)'                 | '4.99K'   | '0.5%'  | '1/16W'  | 'IO'       | 'RES CHIP 4.99K 1/16W +-0.5%(0402)'                | 'CHIP0402'     | ''          | ''            | '20100618'
 '210K'       | '1%'      | '1/16W'  | '0402LF'  | 'CHIP'   | 'CS42102FB00'(!)        = 'End of Design' | 'Comp-Approve'     | 'CS42102FB00'           | 'R0402'             | '(R0402-0201)'                 | '210K'    | '1%'    | '1/16W'  | 'DISCRETE' | 'RES CHIP 210K 1/16W +-1%(0402)'                   | 'CHIP0402'     | ''          | ''            | '20100618'
 '210K'       | '1%'      | '1/16W'  | '0402LF'  | 'EMPTY'  | 'CS42102FB00'(!)        = 'End of Design' | 'Comp-Approve'     | 'CS42102FB00'           | 'R0402'             | '(R0402-0201)'                 | '210K'    | '1%'    | '1/16W'  | 'IO'       | 'RES CHIP 210K 1/16W +-1%(0402)'                   | 'CHIP0402'     | ''          | ''            | '20100618'
 '84.5K'      | '1%'      | '1/16W'  | '0402LF'  | 'CHIP'   | 'CS38452FB14'(!)        = 'End of Design' | 'Comp-Approve'     | 'CS38452FB14'           | 'R0402'             | '(R0402-0201)'                 | '84.5K'   | '1%'    | '1/16W'  | 'DISCRETE' | 'RES CHIP 84.5K 1/16W +-1%(0402)'                  | 'CHIP0402'     | ''          | ''            | '20100618'
 '84.5K'      | '1%'      | '1/16W'  | '0402LF'  | 'EMPTY'  | 'CS38452FB14'(!)        = 'End of Design' | 'Comp-Approve'     | 'CS38452FB14'           | 'R0402'             | '(R0402-0201)'                 | '84.5K'   | '1%'    | '1/16W'  | 'IO'       | 'RES CHIP 84.5K 1/16W +-1%(0402)'                  | 'CHIP0402'     | ''          | ''            | '20100618'
 '133K'       | '1%'      | '1/16W'  | '0402LF'  | 'CHIP'   | 'CS41332FB06'(!)        = 'End of Design' | 'Comp-Approve'     | 'CS41332FB06'           | 'R0402'             | '(R0402-0201)'                 | '133K'    | '1%'    | '1/16W'  | 'DISCRETE' | 'RES CHIP 133K 1/16W +-1%(0402)'                   | 'CHIP0402'     | ''          | ''            | '20100618'
 '133K'       | '1%'      | '1/16W'  | '0402LF'  | 'EMPTY'  | 'CS41332FB06'(!)        = 'End of Design' | 'Comp-Approve'     | 'CS41332FB06'           | 'R0402'             | '(R0402-0201)'                 | '133K'    | '1%'    | '1/16W'  | 'IO'       | 'RES CHIP 133K 1/16W +-1%(0402)'                   | 'CHIP0402'     | ''          | ''            | '20100618'
 '205K'       | '1%'      | '1/16W'  | '0402LF'  | 'CHIP'   | 'CS42052FB10'(!)        = 'End of Design' | 'Comp-Approve'     | 'CS42052FB10'           | 'R0402'             | '(R0402-0201)'                 | '205K'    | '1%'    | '1/16W'  | 'DISCRETE' | 'RES CHIP 205K 1/16W +-1%(0402)'                   | 'CHIP0402'     | ''          | ''            | '20100618'
 '205K'       | '1%'      | '1/16W'  | '0402LF'  | 'EMPTY'  | 'CS42052FB10'(!)        = 'End of Design' | 'Comp-Approve'     | 'CS42052FB10'           | 'R0402'             | '(R0402-0201)'                 | '205K'    | '1%'    | '1/16W'  | 'IO'       | 'RES CHIP 205K 1/16W +-1%(0402)'                   | 'CHIP0402'     | ''          | ''            | '20100618'
 '6.34K'      | '0.5%'    | '1/10W'  | '0603LF'  | 'CHIP'   | 'CS26343D900'(!)        = 'End of Design' | 'Comp-Approve'     | 'CS26343D900'           | 'R0603'             | '(SMR0603AW)'                  | '6.34K'   | '0.5%'  | '1/10W'  | 'DISCRETE' | 'RES CHIP 6.34K 1/10W +-0.5%(0603)'                | 'CHIP0603'     | ''          | ''            | '20100618'
 '6.34K'      | '0.5%'    | '1/10W'  | '0603LF'  | 'EMPTY'  | 'CS26343D900'(!)        = 'End of Design' | 'Comp-Approve'     | 'CS26343D900'           | 'R0603'             | '(SMR0603AW)'                  | '6.34K'   | '0.5%'  | '1/10W'  | 'IO'       | 'RES CHIP 6.34K 1/10W +-0.5%(0603)'                | 'CHIP0603'     | ''          | ''            | '20100618'
 '10K'        | '0.5%'    | '1/10W'  | '0603LF'  | 'CHIP'   | 'CS31003D911'(!)        = ''              | ''                 | 'CS31003D911'           | 'R0603'             | '(SMR0603AW)'                  | '10K'     | '0.5%'  | '1/10W ' | 'DISCRETE' | 'RESISTOR CHIP 10K 1/10W+-0.5%(0603)'              | 'CHIP0603'     | ''          | ''            | '20100618'
 '10K'        | '0.5%'    | '1/10W'  | '0603LF'  | 'EMPTY'  | 'CS31003D911'(!)        = ''              | ''                 | 'CS31003D911'           | 'R0603'             | '(SMR0603AW)'                  | '10K'     | '0.5%'  | '1/10W ' | 'IO'       | 'RESISTOR CHIP 10K 1/10W+-0.5%(0603)'              | 'CHIP0603'     | ''          | ''            | '20100618'
 '3.6K'       | '0.5%'    | '1/10W'  | '0603LF'  | 'CHIP'   | 'CS23603D900'(!)        = 'End of Design' | 'Comp-Approve'     | 'CS23603D900'           | 'R0603'             | '(SMR0603AW)'                  | '3.6K'    | '0.5%'  | '1/10W ' | 'DISCRETE' | 'RES CHIP 3.6K 1/10W +-0.5%(0603)'                 | 'CHIP0603'     | ''          | ''            | '20100621'
 '3.6K'       | '0.5%'    | '1/10W'  | '0603LF'  | 'EMPTY'  | 'CS23603D900'(!)        = 'End of Design' | 'Comp-Approve'     | 'CS23603D900'           | 'R0603'             | '(SMR0603AW)'                  | '3.6K'    | '0.5%'  | '1/10W ' | 'IO'       | 'RES CHIP 3.6K 1/10W +-0.5%(0603)'                 | 'CHIP0603'     | ''          | ''            | '20100621'
 '24.9K'      | '1%'      | '1/16W'  | '0402LF'  | 'CHIP'   | 'CS32492FB16'(!)        = 'End of Design' | 'Comp-Approve'     | 'CS32492FB16'           | 'R0402'             | '(R0402-0201)'                 | '24.9K'   | '1%'    | '1/16W'  | 'DISCRETE' | 'RES CHIP 24.9K 1/16W +-1%(0402)'                  | 'CHIP0402'     | ''          | ''            | '20100621'
 '24.9K'      | '1%'      | '1/16W'  | '0402LF'  | 'EMPTY'  | 'CS32492FB16'(!)        = 'End of Design' | 'Comp-Approve'     | 'CS32492FB16'           | 'R0402'             | '(R0402-0201)'                 | '24.9K'   | '1%'    | '1/16W'  | 'IO'       | 'RES CHIP 24.9K 1/16W +-1%(0402)'                  | 'CHIP0402'     | ''          | ''            | '20100621'
 '330'        | '1%'      | '1/10W'  | '0603LF'  | 'CHIP'   | 'CS13303F917'(!)        = ''              | ''                 | 'CS13303F917'           | 'R0603'             | '(SMR0603AW)'                  | '330'     | '1%'    | '1/10W'  | 'DISCRETE' | 'RES CHIP 330 1/10W +-1%(0603)'                    | 'CHIP0603'     | ''          | ''            | '20100621'
 '330'        | '1%'      | '1/10W'  | '0603LF'  | 'EMPTY'  | 'CS13303F917'(!)        = ''              | ''                 | 'CS13303F917'           | 'R0603'             | '(SMR0603AW)'                  | '330'     | '1%'    | '1/10W'  | 'IO'       | 'RES CHIP 330 1/10W +-1%(0603)'                    | 'CHIP0603'     | ''          | ''            | '20100621'
 '47.5K'      | '1%'      | '1/10W'  | '0603LF'  | 'CHIP'   | 'CS34753F911'(!)        = ''              | ''                 | 'CS34753F911'           | 'R0603'             | '(SMR0603AW)'                  | '47.5K'   | '1%'    | '1/10W ' | 'DISCRETE' | 'RES CHIP 47.5K 1/10W +-1%(0603)'                  | 'CHIP0603'     | ''          | ''            | '20100621'
 '47.5K'      | '1%'      | '1/10W'  | '0603LF'  | 'EMPTY'  | 'CS34753F911'(!)        = ''              | ''                 | 'CS34753F911'           | 'R0603'             | '(SMR0603AW)'                  | '47.5K'   | '1%'    | '1/10W ' | 'IO'       | 'RES CHIP 47.5K 1/10W +-1%(0603)'                  | 'CHIP0603'     | ''          | ''            | '20100621'
 '47.5K'      | '1%'      | '1/16W'  | '0402LF'  | 'CHIP'   | 'CS34752FB14'(!)        = 'End of Design' | 'Comp-Approve'     | 'CS34752FB14'           | 'R0402'             | '(R0402-0201)'                 | '47.5K'   | '1%'    | '1/16W'  | 'DISCRETE' | 'RES CHIP 47.5K 1/16W +-1% (0402)'                 | 'CHIP0402'     | ''          | ''            | '20100621'
 '47.5K'      | '1%'      | '1/16W'  | '0402LF'  | 'EMPTY'  | 'CS34752FB14'(!)        = 'End of Design' | 'Comp-Approve'     | 'CS34752FB14'           | 'R0402'             | '(R0402-0201)'                 | '47.5K'   | '1%'    | '1/16W'  | 'IO'       | 'RES CHIP 47.5K 1/16W +-1% (0402)'                 | 'CHIP0402'     | ''          | ''            | '20100621'
 '130'        | '1%'      | '1/16W'  | '0402LF'  | 'CHIP'   | 'CS11302FB15'(!)        = 'End of Design' | 'Comp-Approve'     | 'CS11302FB15'           | 'R0402'             | '(R0402-0201)'                 | '130'     | '1%'    | '1/16W'  | 'DISCRETE' | 'RES CHIP 130 1/16W +-1%(0402)'                    | 'CHIP0402'     | ''          | ''            | '20100621'
 '130'        | '1%'      | '1/16W'  | '0402LF'  | 'EMPTY'  | 'CS11302FB15'(!)        = 'End of Design' | 'Comp-Approve'     | 'CS11302FB15'           | 'R0402'             | '(R0402-0201)'                 | '130'     | '1%'    | '1/16W'  | 'IO'       | 'RES CHIP 130 1/16W +-1%(0402)'                    | 'CHIP0402'     | ''          | ''            | '20100621'
 '23.7K'      | '1%'      | '1/16W'  | '0402LF'  | 'CHIP'   | 'CS32372FB05'(!)        = 'End of Design' | 'Comp-Approve'     | 'CS32372FB05'           | 'R0402'             | '(R0402-0201)'                 | '23.7K'   | '1%'    | '1/16W'  | 'DISCRETE' | 'RES CHIP 23.7K 1/16W +-1%(0402)'                  | 'CHIP0402'     | ''          | ''            | '20100621'
 '23.7K'      | '1%'      | '1/16W'  | '0402LF'  | 'EMPTY'  | 'CS32372FB05'(!)        = 'End of Design' | 'Comp-Approve'     | 'CS32372FB05'           | 'R0402'             | '(R0402-0201)'                 | '23.7K'   | '1%'    | '1/16W'  | 'IO'       | 'RES CHIP 23.7K 1/16W +-1%(0402)'                  | 'CHIP0402'     | ''          | ''            | '20100621'
 '6.98K'      | '1%'      | '1/16W'  | '0402LF'  | 'CHIP'   | 'CS26982FB01'(!)        = 'End of Design' | 'Comp-Approve'     | 'CS26982FB01'           | 'R0402'             | '(R0402-0201)'                 | '6.98K'   | '1%'    | '1/16W'  | 'DISCRETE' | 'RES CHIP 6.98K 1/16W +-1% (0402)'                 | 'CHIP0402'     | ''          | ''            | '20100622'
 '6.98K'      | '1%'      | '1/16W'  | '0402LF'  | 'EMPTY'  | 'CS26982FB01'(!)        = 'End of Design' | 'Comp-Approve'     | 'CS26982FB01'           | 'R0402'             | '(R0402-0201)'                 | '6.98K'   | '1%'    | '1/16W'  | 'IO'       | 'RES CHIP 6.98K 1/16W +-1% (0402)'                 | 'CHIP0402'     | ''          | ''            | '20100622'
 '845'        | '1%'      | '1/16W'  | '0402LF'  | 'CHIP'   | 'CS18452FB11'(!)        = 'End of Design' | 'Comp-Approve'     | 'CS18452FB11'           | 'R0402'             | '(R0402-0201)'                 | '845'     | '1%'    | '1/16W'  | 'DISCRETE' | 'RES CHIP 845 1/16W +-1%(0402) '                   | 'CHIP0402'     | ''          | ''            | '20100622'
 '845'        | '1%'      | '1/16W'  | '0402LF'  | 'EMPTY'  | 'CS18452FB11'(!)        = 'End of Design' | 'Comp-Approve'     | 'CS18452FB11'           | 'R0402'             | '(R0402-0201)'                 | '845'     | '1%'    | '1/16W'  | 'IO'       | 'RES CHIP 845 1/16W +-1%(0402) '                   | 'CHIP0402'     | ''          | ''            | '20100622'
 '1.05K'      | '1%'      | '1/16W'  | '0402LF'  | 'CHIP'   | 'CS21052FB00'(!)        = 'End of Design' | 'Comp-Approve'     | 'CS21052FB00'           | 'R0402'             | '(R0402-0201)'                 | '1.05K'   | '1%'    | '1/16W'  | 'DISCRETE' | 'RES CHIP 1.05K 1/16W +-1%(0402)'                  | 'CHIP0402'     | ''          | ''            | '20100723'
 '1.05K'      | '1%'      | '1/16W'  | '0402LF'  | 'EMPTY'  | 'CS21052FB00'(!)        = 'End of Design' | 'Comp-Approve'     | 'CS21052FB00'           | 'R0402'             | '(R0402-0201)'                 | '1.05K'   | '1%'    | '1/16W'  | 'IO'       | 'RES CHIP 1.05K 1/16W +-1%(0402)'                  | 'CHIP0402'     | ''          | ''            | '20100723'
 '1.02K'      | '1%'      | '1/16W'  | '0402LF'  | 'CHIP'   | 'CS21022FB15'(!)        = 'End of Design' | 'Comp-Approve'     | 'CS21022FB15'           | 'R0402'             | '(R0402-0201)'                 | '1.02K'   | '1%'    | '1/16W'  | 'DISCRETE' | 'RES CHIP 1.02K 1/16W +-1%(0402)'                  | 'CHIP0402'     | ''          | ''            | '20100622'
 '1.02K'      | '1%'      | '1/16W'  | '0402LF'  | 'EMPTY'  | 'CS21022FB15'(!)        = 'End of Design' | 'Comp-Approve'     | 'CS21022FB15'           | 'R0402'             | '(R0402-0201)'                 | '1.02K'   | '1%'    | '1/16W'  | 'IO'       | 'RES CHIP 1.02K 1/16W +-1%(0402)'                  | 'CHIP0402'     | ''          | ''            | '20100622'
 '115K'       | '1%'      | '1/16W'  | '0402LF'  | 'CHIP'   | 'CS41152FB08'(!)        = 'End of Design' | 'Comp-Approve'     | 'CS41152FB08'           | 'R0402'             | '(R0402-0201)'                 | '115K'    | '1%'    | '1/16W'  | 'DISCRETE' | 'RES CHIP 115K 1/16W +-1%(0402)'                   | 'CHIP0402'     | ''          | ''            | '20100623'
 '115K'       | '1%'      | '1/16W'  | '0402LF'  | 'EMPTY'  | 'CS41152FB08'(!)        = 'End of Design' | 'Comp-Approve'     | 'CS41152FB08'           | 'R0402'             | '(R0402-0201)'                 | '115K'    | '1%'    | '1/16W'  | 'IO'       | 'RES CHIP 115K 1/16W +-1%(0402)'                   | 'CHIP0402'     | ''          | ''            | '20100623'
 '28.7K'      | '1%'      | '1/16W'  | '0402LF'  | 'CHIP'   | 'CS32872FB11'(!)        = 'End of Design' | 'Comp-Approve'     | 'CS32872FB11'           | 'R0402'             | '(R0402-0201)'                 | '28.7K'   | '1%'    | '1/16W'  | 'DISCRETE' | 'RES CHIP 28.7K 1/16W +-1%(0402)'                  | 'CHIP0402'     | ''          | ''            | '20100623'
 '28.7K'      | '1%'      | '1/16W'  | '0402LF'  | 'EMPTY'  | 'CS32872FB11'(!)        = 'End of Design' | 'Comp-Approve'     | 'CS32872FB11'           | 'R0402'             | '(R0402-0201)'                 | '28.7K'   | '1%'    | '1/16W'  | 'IO'       | 'RES CHIP 28.7K 1/16W +-1%(0402)'                  | 'CHIP0402'     | ''          | ''            | '20100623'
 '6.04K'      | '1%'      | '1/16W'  | '0402LF'  | 'CHIP'   | 'CS26042FB00'(!)        = 'End of Design' | 'Comp-Approve'     | 'CS26042FB00'           | 'R0402'             | '(R0402-0201)'                 | '6.04K'   | '1%'    | '1/16W'  | 'DISCRETE' | 'RES CHIP 6.04K 1/16W +-1%(0402)'                  | 'CHIP0402'     | ''          | ''            | '20100630'
 '6.04K'      | '1%'      | '1/16W'  | '0402LF'  | 'EMPTY'  | 'CS26042FB00'(!)        = 'End of Design' | 'Comp-Approve'     | 'CS26042FB00'           | 'R0402'             | '(R0402-0201)'                 | '6.04K'   | '1%'    | '1/16W'  | 'IO'       | 'RES CHIP 6.04K 1/16W +-1%(0402)'                  | 'CHIP0402'     | ''          | ''            | '20100630'
 '45'         | '1%'      | '1/16W'  | '0402LF'  | 'CHIP'   | 'CS04502FB01'(!)        = ''              | ''                 | 'CS04502FB01'           | 'R0402'             | '(R0402-0201)'                 | '45'      | '1%'    | '1/16W'  | 'DISCRETE' | 'RES CHIP 45 1/16W +-1%(0402)'                     | 'CHIP0402'     | ''          | ''            | '20100630'
 '45'         | '1%'      | '1/16W'  | '0402LF'  | 'EMPTY'  | 'CS04502FB01'(!)        = ''              | ''                 | 'CS04502FB01'           | 'R0402'             | '(R0402-0201)'                 | '45'      | '1%'    | '1/16W'  | 'IO'       | 'RES CHIP 45 1/16W +-1%(0402)'                     | 'CHIP0402'     | ''          | ''            | '20100630'
 '196K'       | '1%'      | '1/16W'  | '0402LF'  | 'CHIP'   | 'CS41962FB01'(!)        = 'End of Design' | 'Comp-Approve'     | 'CS41962FB01'           | 'R0402'             | '(R0402-0201)'                 | '196K'    | '1%'    | '1/16W'  | 'DISCRETE' | 'RES CHIP 196K 1/16W +-1% (0402)'                  | 'CHIP0402'     | ''          | ''            | '20100702'
 '196K'       | '1%'      | '1/16W'  | '0402LF'  | 'EMPTY'  | 'CS41962FB01'(!)        = 'End of Design' | 'Comp-Approve'     | 'CS41962FB01'           | 'R0402'             | '(R0402-0201)'                 | '196K'    | '1%'    | '1/16W'  | 'IO'       | 'RES CHIP 196K 1/16W +-1% (0402)'                  | 'CHIP0402'     | ''          | ''            | '20100702'
 '158K'       | '1%'      | '1/16W'  | '0402LF'  | 'CHIP'   | 'CS41582FB06'(!)        = ''              | ''                 | 'CS41582FB06'           | 'R0402'             | '(R0402-0201)'                 | '158K'    | '1%'    | '1/16W'  | 'DISCRETE' | 'RES CHIP 158K 1/16W +-1% (0402)'                  | 'CHIP0402'     | ''          | ''            | '20100702'
 '158K'       | '1%'      | '1/16W'  | '0402LF'  | 'EMPTY'  | 'CS41582FB06'(!)        = ''              | ''                 | 'CS41582FB06'           | 'R0402'             | '(R0402-0201)'                 | '158K'    | '1%'    | '1/16W'  | 'IO'       | 'RES CHIP 158K 1/16W +-1% (0402)'                  | 'CHIP0402'     | ''          | ''            | '20100702'
 '300'        | '1%'      | '1/8W'   | '0805LF'  | 'CHIP'   | 'CS13004FA00'(!)        = ''              | ''                 | 'CS13004FA00'           | 'R0805'             | '(SMR0805AW)'                  | '300'     | '1%'    | '1/8W'   | 'DISCRETE' | 'RES CHIP 300 1/8W +-1%(0805)'                     | 'CHIP0805'     | ''          | ''            | '20100706'
 '300'        | '1%'      | '1/8W'   | '0805LF'  | 'EMPTY'  | 'CS13004FA00'(!)        = ''              | ''                 | 'CS13004FA00'           | 'R0805'             | '(SMR0805AW)'                  | '300'     | '1%'    | '1/8W'   | 'IO'       | 'RES CHIP 300 1/8W +-1%(0805)'                     | 'CHIP0805'     | ''          | ''            | '20100706'
 '0.5'        | '5%'      | '1/2W'   | '1210LF'  | 'CHIP'   | 'CS+5007J300'(!)        = ''              | ''                 | 'CS+5007J300'           | 'R1210'             | '(SMR1210AW)'                  | '0.5'     | '5%'    | '1/2W'   | 'DISCRETE' | 'RES CHIP 0.5 1/2W +-5% (1210)'                    | 'CHIP1210'     | ''          | ''            | '20100706'
 '0.5'        | '5%'      | '1/2W'   | '1210LF'  | 'EMPTY'  | 'CS+5007J300'(!)        = ''              | ''                 | 'CS+5007J300'           | 'R1210'             | '(SMR1210AW)'                  | '0.5'     | '5%'    | '1/2W'   | 'IO'       | 'RES CHIP 0.5 1/2W +-5% (1210)'                    | 'CHIP1210'     | ''          | ''            | '20100706'
 '499K'       | '1%'      | '1/10W'  | '0603LF'  | 'CHIP'   | 'CS44993F918'(!)        = ''              | ''                 | 'CS44993F918'           | 'R0603'             | '(SMR0603AW)'                  | '499K'    | '1%'    | '1/10W ' | 'DISCRETE' | 'RES CHIP 499K 1/10W +-1%(0603)'                   | 'CHIP0603'     | ''          | ''            | '20100708'
 '499K'       | '1%'      | '1/10W'  | '0603LF'  | 'EMPTY'  | 'CS44993F918'(!)        = ''              | ''                 | 'CS44993F918'           | 'R0603'             | '(SMR0603AW)'                  | '499K'    | '1%'    | '1/10W ' | 'IO'       | 'RES CHIP 499K 1/10W +-1%(0603)'                   | 'CHIP0603'     | ''          | ''            | '20100708'
 '33'         | '5%'      | '1/16W'  | '0402LF'  | 'CHIP'   | 'CS03302JB29'(!)        = 'End of Design' | 'Comp-Approve'     | 'CS03302JB29'           | 'R0402'             | '(R0402-0201)'                 | '33'      | '5%'    | '1/16W'  | 'DISCRETE' | 'RES CHIP 33 1/16W +-5% (0402)'                    | 'CHIP0402'     | ''          | ''            | '20100708'
 '33'         | '5%'      | '1/16W'  | '0402LF'  | 'EMPTY'  | 'CS03302JB29'(!)        = 'End of Design' | 'Comp-Approve'     | 'CS03302JB29'           | 'R0402'             | '(R0402-0201)'                 | '33'      | '5%'    | '1/16W'  | 'IO'       | 'RES CHIP 33 1/16W +-5% (0402)'                    | 'CHIP0402'     | ''          | ''            | '20100708'
 '330'        | '5%'      | '1/10W'  | '0603LF'  | 'CHIP'   | 'CS13303J943'(!)        = ''              | ''                 | 'CS13303J943'           | 'R0603'             | '(SMR0603AW)'                  | '330'     | '5%'    | '1/10W ' | 'DISCRETE' | 'RES CHIP 330 1/10W +-5%(0603)'                    | 'CHIP0603'     | ''          | ''            | '20100708'
 '330'        | '5%'      | '1/10W'  | '0603LF'  | 'EMPTY'  | 'CS13303J943'(!)        = ''              | ''                 | 'CS13303J943'           | 'R0603'             | '(SMR0603AW)'                  | '330'     | '5%'    | '1/10W ' | 'IO'       | 'RES CHIP 330 1/10W +-5%(0603)'                    | 'CHIP0603'     | ''          | ''            | '20100708'
 '4.7K'       | '5%'      | '1/10W'  | '0603LF'  | 'CHIP'   | 'CS24703J942'(!)        = ''              | ''                 | 'CS24703J942'           | 'R0603'             | '(SMR0603AW)'                  | '4.7K'    | '5%'    | '1/10W ' | 'DISCRETE' | 'RES CHIP 4.7K 1/10W +-5%(0603)'                   | 'CHIP0603'     | ''          | ''            | '20100708'
 '4.7K'       | '5%'      | '1/10W'  | '0603LF'  | 'EMPTY'  | 'CS24703J942'(!)        = ''              | ''                 | 'CS24703J942'           | 'R0603'             | '(SMR0603AW)'                  | '4.7K'    | '5%'    | '1/10W ' | 'IO'       | 'RES CHIP 4.7K 1/10W +-5%(0603)'                   | 'CHIP0603'     | ''          | ''            | '20100708'
 '100'        | '1%'      | '1/10W'  | '0603LF'  | 'CHIP'   | 'CS11003F953'(!)        = ''              | ''                 | 'CS11003F953'           | 'R0603'             | '(SMR0603AW)'                  | '100'     | '1%'    | '1/10W ' | 'DISCRETE' | 'RESISTOR CHIP 100 1/10W+-1%(0603)'                | 'CHIP0603'     | ''          | ''            | '20100708'
 '100'        | '1%'      | '1/10W'  | '0603LF'  | 'EMPTY'  | 'CS11003F953'(!)        = ''              | ''                 | 'CS11003F953'           | 'R0603'             | '(SMR0603AW)'                  | '100'     | '1%'    | '1/10W ' | 'IO'       | 'RESISTOR CHIP 100 1/10W+-1%(0603)'                | 'CHIP0603'     | ''          | ''            | '20100708'
 '1K'         | '1%'      | '1/10W'  | '0603LF'  | 'CHIP'   | 'CS21003F947'(!)        = ''              | ''                 | 'CS21003F947'           | 'R0603'             | '(SMR0603AW)'                  | '1K'      | '1%'    | '1/10W ' | 'DISCRETE' | 'RESISTOR CHIP 1K,1/10W,+-1%(0603)'                | 'CHIP0603'     | ''          | ''            | '20100708'
 '1K'         | '1%'      | '1/10W'  | '0603LF'  | 'EMPTY'  | 'CS21003F947'(!)        = ''              | ''                 | 'CS21003F947'           | 'R0603'             | '(SMR0603AW)'                  | '1K'      | '1%'    | '1/10W ' | 'IO'       | 'RESISTOR CHIP 1K,1/10W,+-1%(0603)'                | 'CHIP0603'     | ''          | ''            | '20100708'
 '20K'        | '1%'      | '1/16W'  | '0402LF'  | 'CHIP'   | 'CS32002FB29'(!)        = 'End of Design' | 'Comp-Approve'     | 'CS32002FB29'           | 'R0402'             | '(R0402-0201)'                 | '20K'     | '1%'    | '1/16W'  | 'DISCRETE' | 'RES CHIP 20K 1/16W +-1%(0402)'                    | 'CHIP0402'     | ''          | ''            | '20100708'
 '20K'        | '1%'      | '1/16W'  | '0402LF'  | 'EMPTY'  | 'CS32002FB29'(!)        = 'End of Design' | 'Comp-Approve'     | 'CS32002FB29'           | 'R0402'             | '(R0402-0201)'                 | '20K'     | '1%'    | '1/16W'  | 'IO'       | 'RES CHIP 20K 1/16W +-1%(0402)'                    | 'CHIP0402'     | ''          | ''            | '20100708'
 '130'        | '5%'      | '1/16W'  | '0402LF'  | 'CHIP'   | 'CS11302JB17'(!)        = 'End of Design' | 'Comp-Approve'     | 'CS11302JB17'           | 'R0402'             | '(R0402-0201)'                 | '130'     | '5%'    | '1/16W'  | 'DISCRETE' | 'RES CHIP 130(1/16W,+-5%,0402)'                    | 'CHIP0402'     | ''          | ''            | '20100708'
 '130'        | '5%'      | '1/16W'  | '0402LF'  | 'EMPTY'  | 'CS11302JB17'(!)        = 'End of Design' | 'Comp-Approve'     | 'CS11302JB17'           | 'R0402'             | '(R0402-0201)'                 | '130'     | '5%'    | '1/16W'  | 'IO'       | 'RES CHIP 130(1/16W,+-5%,0402)'                    | 'CHIP0402'     | ''          | ''            | '20100708'
 '4.7K'       | '1%'      | '1/16W'  | '0402LF'  | 'CHIP'   | 'CS24702FB10'(!)        = 'End of Design' | 'Comp-Approve'     | 'CS24702FB10'           | 'R0402'             | '(R0402-0201)'                 | '4.7K'    | '1%'    | '1/16W'  | 'DISCRETE' | 'RES CHIP 4.7K 1/16W +-1%(0402)'                   | 'CHIP0402'     | ''          | ''            | '20100708'
 '4.7K'       | '1%'      | '1/16W'  | '0402LF'  | 'EMPTY'  | 'CS24702FB10'(!)        = 'End of Design' | 'Comp-Approve'     | 'CS24702FB10'           | 'R0402'             | '(R0402-0201)'                 | '4.7K'    | '1%'    | '1/16W'  | 'IO'       | 'RES CHIP 4.7K 1/16W +-1%(0402)'                   | 'CHIP0402'     | ''          | ''            | '20100708'
 '100K'       | '5%'      | '1/16W'  | '0402LF'  | 'CHIP'   | 'CS41002JB20'(!)        = 'End of Design' | 'Comp-Approve'     | 'CS41002JB20'           | 'R0402'             | '(R0402-0201)'                 | '100K'    | '5%'    | '1/16W'  | 'DISCRETE' | 'RES CHIP 100K 1/16W 5%(0402)'                     | 'CHIP0402'     | ''          | ''            | '20100708'
 '100K'       | '5%'      | '1/16W'  | '0402LF'  | 'EMPTY'  | 'CS41002JB20'(!)        = 'End of Design' | 'Comp-Approve'     | 'CS41002JB20'           | 'R0402'             | '(R0402-0201)'                 | '100K'    | '5%'    | '1/16W'  | 'IO'       | 'RES CHIP 100K 1/16W 5%(0402)'                     | 'CHIP0402'     | ''          | ''            | '20100708'
 '220'        | '5%'      | '1/16W'  | '0402LF'  | 'CHIP'   | 'CS12202JB24'(!)        = 'End of Design' | 'Comp-Approve'     | 'CS12202JB24'           | 'R0402'             | '(R0402-0201)'                 | '220'     | '5%'    | '1/16W'  | 'DISCRETE' | 'RES CHIP 220 1/16W +-5%(0402)'                    | 'CHIP0402'     | ''          | ''            | '20100708'
 '220'        | '5%'      | '1/16W'  | '0402LF'  | 'EMPTY'  | 'CS12202JB24'(!)        = 'End of Design' | 'Comp-Approve'     | 'CS12202JB24'           | 'R0402'             | '(R0402-0201)'                 | '220'     | '5%'    | '1/16W'  | 'IO'       | 'RES CHIP 220 1/16W +-5%(0402)'                    | 'CHIP0402'     | ''          | ''            | '20100708'
 '487'        | '1%'      | '1/16W'  | '0402LF'  | 'CHIP'   | 'CS14872FB05'(!)        = 'End of Design' | 'Comp-Approve'     | 'CS14872FB05'           | 'R0402'             | '(R0402-0201)'                 | '487'     | '1%'    | '1/16W'  | 'DISCRETE' | 'RES CHIP 487 1/16W +-1%(0402)'                    | 'CHIP0402'     | ''          | ''            | '20100712'
 '487'        | '1%'      | '1/16W'  | '0402LF'  | 'EMPTY'  | 'CS14872FB05'(!)        = 'End of Design' | 'Comp-Approve'     | 'CS14872FB05'           | 'R0402'             | '(R0402-0201)'                 | '487'     | '1%'    | '1/16W'  | 'IO'       | 'RES CHIP 487 1/16W +-1%(0402)'                    | 'CHIP0402'     | ''          | ''            | '20100712'
 '1.1K'       | '1%'      | '1/16W'  | '0402LF'  | 'CHIP'   | 'CS21102FB10'(!)        = 'End of Design' | 'Comp-Approve'     | 'CS21102FB10'           | 'R0402'             | '(R0402-0201)'                 | '1.1K'    | '1%'    | '1/16W'  | 'DISCRETE' | 'RES CHIP 1.1K 1/16W +-1% (0402)'                  | 'CHIP0402'     | ''          | ''            | '20100712'
 '1.1K'       | '1%'      | '1/16W'  | '0402LF'  | 'EMPTY'  | 'CS21102FB10'(!)        = 'End of Design' | 'Comp-Approve'     | 'CS21102FB10'           | 'R0402'             | '(R0402-0201)'                 | '1.1K'    | '1%'    | '1/16W'  | 'IO'       | 'RES CHIP 1.1K 1/16W +-1% (0402)'                  | 'CHIP0402'     | ''          | ''            | '20100712'
 '68'         | '1%'      | '1/16W'  | '0402LF'  | 'CHIP'   | 'CS06802FB07'(!)        = 'End of Design' | 'Comp-Approve'     | 'CS06802FB07'           | 'R0402'             | '(R0402-0201)'                 | '68'      | '1%'    | '1/16W'  | 'DISCRETE' | 'RES CHIP 68 1/16W +-1%(0402)'                     | 'CHIP0402'     | ''          | ''            | '20100712'
 '68'         | '1%'      | '1/16W'  | '0402LF'  | 'EMPTY'  | 'CS06802FB07'(!)        = 'End of Design' | 'Comp-Approve'     | 'CS06802FB07'           | 'R0402'             | '(R0402-0201)'                 | '68'      | '1%'    | '1/16W'  | 'IO'       | 'RES CHIP 68 1/16W +-1%(0402)'                     | 'CHIP0402'     | ''          | ''            | '20100712'
 '21K'        | '1%'      | '1/16W'  | '0402LF'  | 'CHIP'   | 'CS32102FB14'(!)        = 'End of Design' | 'Comp-Approve'     | 'CS32102FB14'           | 'R0402'             | '(R0402-0201)'                 | '21K '    | '1%'    | '1/16W'  | 'DISCRETE' | 'RES CHIP 21K 1/16W +-1%(0402)'                    | 'CHIP0402'     | ''          | ''            | '20100712'
 '21K'        | '1%'      | '1/16W'  | '0402LF'  | 'EMPTY'  | 'CS32102FB14'(!)        = 'End of Design' | 'Comp-Approve'     | 'CS32102FB14'           | 'R0402'             | '(R0402-0201)'                 | '21K '    | '1%'    | '1/16W'  | 'IO'       | 'RES CHIP 21K 1/16W +-1%(0402)'                    | 'CHIP0402'     | ''          | ''            | '20100712'
 '453'        | '1%'      | '1/16W'  | '0402LF'  | 'CHIP'   | 'CS14532FB14'(!)        = 'End of Design' | 'Comp-Approve'     | 'CS14532FB14'           | 'R0402'             | '(R0402-0201)'                 | '453'     | '1%'    | '1/16W'  | 'DISCRETE' | 'RES CHIP 453 1/16W +-1% (0402) '                  | 'CHIP0402'     | ''          | ''            | '20100712'
 '453'        | '1%'      | '1/16W'  | '0402LF'  | 'EMPTY'  | 'CS14532FB14'(!)        = 'End of Design' | 'Comp-Approve'     | 'CS14532FB14'           | 'R0402'             | '(R0402-0201)'                 | '453'     | '1%'    | '1/16W'  | 'IO'       | 'RES CHIP 453 1/16W +-1% (0402) '                  | 'CHIP0402'     | ''          | ''            | '20100712'
 '0'          | '5%'      | '1/8W'   | '0805LF'  | 'CHIP'   | 'CS00004JA40'(!)        = ''              | ''                 | 'CS00004JA40'           | 'R0805'             | '(SMR0805AW)'                  | '0'       | '5%'    | '1/8W'   | 'DISCRETE' | 'RESISTOR CHIP 0 1/8W +-5%(0805)'                  | 'CHIP0805'     | ''          | ''            | '20100713'
 '0'          | '5%'      | '1/8W'   | '0805LF'  | 'EMPTY'  | 'CS00004JA40'(!)        = ''              | ''                 | 'CS00004JA40'           | 'R0805'             | '(SMR0805AW)'                  | '0'       | '5%'    | '1/8W'   | 'IO'       | 'RESISTOR CHIP 0 1/8W +-5%(0805)'                  | 'CHIP0805'     | ''          | ''            | '20100713'
 '2.21K'      | '1%'      | '1/16W'  | '0402LF'  | 'CHIP'   | 'CS22212FB02'(!)        = ''              | 'End of Life'      | 'CS22212FB02'           | 'R0402_EOL'         | '(R0402-0201)'                 | '2.21K'   | '1%'    | '1/16W'  | 'DISCRETE' | 'RES CHIP 2.21K 1/16W +-1% (0402)'                 | 'CHIP0402'     | ''          | ''            | '20100713'
 '2.21K'      | '1%'      | '1/16W'  | '0402LF'  | 'EMPTY'  | 'CS22212FB02'(!)        = ''              | 'End of Life'      | 'CS22212FB02'           | 'R0402_EOL'         | '(R0402-0201)'                 | '2.21K'   | '1%'    | '1/16W'  | 'IO'       | 'RES CHIP 2.21K 1/16W +-1% (0402)'                 | 'CHIP0402'     | ''          | ''            | '20100713'
 '8.25K'      | '1%'      | '1/16W'  | '0402LF'  | 'CHIP'   | 'CS28252FB07'(!)        = 'End of Design' | 'Comp-Approve'     | 'CS28252FB07'           | 'R0402'             | '(R0402-0201)'                 | '8.25K'   | '1%'    | '1/16W'  | 'DISCRETE' | 'RES CHIP 8.25K 1/16W +-1% (0402)'                 | 'CHIP0402'     | ''          | ''            | '20100715'
 '8.25K'      | '1%'      | '1/16W'  | '0402LF'  | 'EMPTY'  | 'CS28252FB07'(!)        = 'End of Design' | 'Comp-Approve'     | 'CS28252FB07'           | 'R0402'             | '(R0402-0201)'                 | '8.25K'   | '1%'    | '1/16W'  | 'IO'       | 'RES CHIP 8.25K 1/16W +-1% (0402)'                 | 'CHIP0402'     | ''          | ''            | '20100715'
 '680  '      | '1%'      | '1/16W'  | '0402LF'  | 'CHIP'   | 'CS16802FB09'(!)        = 'End of Design' | 'Comp-Approve'     | 'CS16802FB09'           | 'R0402'             | '(R0402-0201)'                 | '680'     | '1%'    | '1/16W'  | 'DISCRETE' | 'RES CHIP 680 1/16W +-1%(0402)'                    | 'CHIP0402'     | ''          | ''            | '20100715'
 '680  '      | '1%'      | '1/16W'  | '0402LF'  | 'EMPTY'  | 'CS16802FB09'(!)        = 'End of Design' | 'Comp-Approve'     | 'CS16802FB09'           | 'R0402'             | '(R0402-0201)'                 | '680'     | '1%'    | '1/16W'  | 'IO'       | 'RES CHIP 680 1/16W +-1%(0402)'                    | 'CHIP0402'     | ''          | ''            | '20100715'
 '750'        | '1%'      | '1/16W'  | '0402LF'  | 'CHIP'   | 'CS17502FB19'(!)        = 'End of Design' | 'Comp-Approve'     | 'CS17502FB19'           | 'R0402'             | '(R0402-0201)'                 | '750'     | '1%'    | '1/16W'  | 'DISCRETE' | 'RES CHIP 750 1/16W +-1%(0402)'                    | 'CHIP0402'     | ''          | ''            | '20100715'
 '750'        | '1%'      | '1/16W'  | '0402LF'  | 'EMPTY'  | 'CS17502FB19'(!)        = 'End of Design' | 'Comp-Approve'     | 'CS17502FB19'           | 'R0402'             | '(R0402-0201)'                 | '750'     | '1%'    | '1/16W'  | 'IO'       | 'RES CHIP 750 1/16W +-1%(0402)'                    | 'CHIP0402'     | ''          | ''            | '20100715'
 '15   '      | '1%'      | '1/16W'  | '0402LF'  | 'CHIP'   | 'CS01502FB11'(!)        = 'End of Design' | 'Comp-Approve'     | 'CS01502FB11'           | 'R0402'             | '(R0402-0201)'                 | '15'      | '1%'    | '1/16W'  | 'DISCRETE' | 'RES CHIP 15 1/16W +-1%(0402)'                     | 'CHIP0402'     | ''          | ''            | '20100715'
 '15   '      | '1%'      | '1/16W'  | '0402LF'  | 'EMPTY'  | 'CS01502FB11'(!)        = 'End of Design' | 'Comp-Approve'     | 'CS01502FB11'           | 'R0402'             | '(R0402-0201)'                 | '15'      | '1%'    | '1/16W'  | 'IO'       | 'RES CHIP 15 1/16W +-1%(0402)'                     | 'CHIP0402'     | ''          | ''            | '20100715'
 '1M'         | '5%'      | '1/16W'  | '0402LF'  | 'CHIP'   | 'CS51002JB21'(!)        = 'End of Design' | 'Comp-Approve'     | 'CS51002JB21'           | 'R0402'             | '(R0402-0201)'                 | '1M'      | '5%'    | '1/16W'  | 'DISCRETE' | 'RES CHIP 1M 1/16W +-5% (0402)'                    | 'CHIP0402'     | ''          | ''            | '20100715'
 '1M'         | '5%'      | '1/16W'  | '0402LF'  | 'EMPTY'  | 'CS51002JB21'(!)        = 'End of Design' | 'Comp-Approve'     | 'CS51002JB21'           | 'R0402'             | '(R0402-0201)'                 | '1M'      | '5%'    | '1/16W'  | 'IO'       | 'RES CHIP 1M 1/16W +-5% (0402)'                    | 'CHIP0402'     | ''          | ''            | '20100715'
 '47   '      | '5%'      | '1/16W'  | '0402LF'  | 'CHIP'   | 'CS04702JB18'(!)        = 'End of Design' | 'Comp-Approve'     | 'CS04702JB18'           | 'R0402'             | '(R0402-0201)'                 | '47'      | '5%'    | '1/16W'  | 'DISCRETE' | 'RES CHIP 47 1/16W +-5%(0402)'                     | 'CHIP0402'     | ''          | ''            | '20100715'
 '47   '      | '5%'      | '1/16W'  | '0402LF'  | 'EMPTY'  | 'CS04702JB18'(!)        = 'End of Design' | 'Comp-Approve'     | 'CS04702JB18'           | 'R0402'             | '(R0402-0201)'                 | '47'      | '5%'    | '1/16W'  | 'IO'       | 'RES CHIP 47 1/16W +-5%(0402)'                     | 'CHIP0402'     | ''          | ''            | '20100715'
 '330  '      | '5%'      | '1/16W'  | '0402LF'  | 'CHIP'   | 'CS13302JB21'(!)        = 'End of Design' | 'Comp-Approve'     | 'CS13302JB21'           | 'R0402'             | '(R0402-0201)'                 | '330'     | '5%'    | '1/16W'  | 'DISCRETE' | 'RES CHIP 330(1/16W +-5% 0402)'                    | 'CHIP0402'     | ''          | ''            | '20100715'
 '330  '      | '5%'      | '1/16W'  | '0402LF'  | 'EMPTY'  | 'CS13302JB21'(!)        = 'End of Design' | 'Comp-Approve'     | 'CS13302JB21'           | 'R0402'             | '(R0402-0201)'                 | '330'     | '5%'    | '1/16W'  | 'IO'       | 'RES CHIP 330(1/16W +-5% 0402)'                    | 'CHIP0402'     | ''          | ''            | '20100715'
 '470  '      | '5%'      | '1/16W'  | '0402LF'  | 'CHIP'   | 'CS14702JB28'(!)        = 'End of Design' | 'Comp-Approve'     | 'CS14702JB28'           | 'R0402'             | '(R0402-0201)'                 | '470'     | '5%'    | '1/16W'  | 'DISCRETE' | 'RES CHIP 470 1/16W +-5% (0402)'                   | 'CHIP0402'     | ''          | ''            | '20100715'
 '470  '      | '5%'      | '1/16W'  | '0402LF'  | 'EMPTY'  | 'CS14702JB28'(!)        = 'End of Design' | 'Comp-Approve'     | 'CS14702JB28'           | 'R0402'             | '(R0402-0201)'                 | '470'     | '5%'    | '1/16W'  | 'IO'       | 'RES CHIP 470 1/16W +-5% (0402)'                   | 'CHIP0402'     | ''          | ''            | '20100715'
 '2.2K'       | '5%'      | '1/16W'  | '0402LF'  | 'CHIP'   | 'CS22202JB18'(!)        = 'End of Design' | 'Comp-Approve'     | 'CS22202JB18'           | 'R0402'             | '(R0402-0201)'                 | '2.2K'    | '5%'    | '1/16W'  | 'DISCRETE' | 'RES CHIP 2.2K 1/16W +-5%(0402)'                   | 'CHIP0402'     | ''          | ''            | '20100715'
 '2.2K'       | '5%'      | '1/16W'  | '0402LF'  | 'EMPTY'  | 'CS22202JB18'(!)        = 'End of Design' | 'Comp-Approve'     | 'CS22202JB18'           | 'R0402'             | '(R0402-0201)'                 | '2.2K'    | '5%'    | '1/16W'  | 'IO'       | 'RES CHIP 2.2K 1/16W +-5%(0402)'                   | 'CHIP0402'     | ''          | ''            | '20100715'
 '4.7K '      | '5%'      | '1/16W'  | '0402LF'  | 'CHIP'   | 'CS24702JB03'(!)        = 'End of Design' | 'Comp-Approve'     | 'CS24702JB03'           | 'R0402'             | '(R0402-0201)'                 | '4.7K'    | '5%'    | '1/16W'  | 'DISCRETE' | 'RES CHIP 4.7K 1/16W +-5% (0402)'                  | 'CHIP0402'     | ''          | ''            | '20100715'
 '4.7K '      | '5%'      | '1/16W'  | '0402LF'  | 'EMPTY'  | 'CS24702JB03'(!)        = 'End of Design' | 'Comp-Approve'     | 'CS24702JB03'           | 'R0402'             | '(R0402-0201)'                 | '4.7K'    | '5%'    | '1/16W'  | 'IO'       | 'RES CHIP 4.7K 1/16W +-5% (0402)'                  | 'CHIP0402'     | ''          | ''            | '20100715'
 '4.7K '      | '5%'      | '1/16W'  | '0402LF'  | 'CHIP'   | 'CS24702JB11'(!)        = ''              | ''                 | 'CS24702JB11'           | 'R0402'             | '(R0402-0201)'                 | '4.7K'    | '5%'    | '1/16W'  | 'DISCRETE' | 'RES CHIP 4.7K 1/16W +-5% (0402)ES-PAL'            | 'CHIP0402'     | ''          | ''            | '20100715'
 '4.7K '      | '5%'      | '1/16W'  | '0402LF'  | 'EMPTY'  | 'CS24702JB11'(!)        = ''              | ''                 | 'CS24702JB11'           | 'R0402'             | '(R0402-0201)'                 | '4.7K'    | '5%'    | '1/16W'  | 'IO'       | 'RES CHIP 4.7K 1/16W +-5% (0402)ES-PAL'            | 'CHIP0402'     | ''          | ''            | '20100715'
 '220K '      | '5%'      | '1/10W'  | '0603LF'  | 'CHIP'   | 'CS42203J900'(!)        = 'End of Design' | 'Comp-Approve'     | 'CS42203J900'           | 'R0603'             | '(SMR0603AW)'                  | '220K'    | '5%'    | '1/10W ' | 'DISCRETE' | 'RESISTOR CHIP 220K 1/10W +-5%(1608)'              | 'CHIP0603'     | ''          | ''            | '20100715'
 '220K '      | '5%'      | '1/10W'  | '0603LF'  | 'EMPTY'  | 'CS42203J900'(!)        = 'End of Design' | 'Comp-Approve'     | 'CS42203J900'           | 'R0603'             | '(SMR0603AW)'                  | '220K'    | '5%'    | '1/10W ' | 'IO'       | 'RESISTOR CHIP 220K 1/10W +-5%(1608)'              | 'CHIP0603'     | ''          | ''            | '20100715'
 '0    '      | '1%'      | '1/10W'  | '0603LF'  | 'CHIP'   | 'CS00003F916'(!)        = 'End of Design' | 'Comp-Approve'     | 'CS00003F916'           | 'R0603'             | '(SMR0603AW)'                  | '0'       | '1%'    | '1/10W ' | 'DISCRETE' | 'RES CHIP 0 1/10W +-1% (0603)'                     | 'CHIP0603'     | ''          | ''            | '20100715'
 '0    '      | '1%'      | '1/10W'  | '0603LF'  | 'EMPTY'  | 'CS00003F916'(!)        = 'End of Design' | 'Comp-Approve'     | 'CS00003F916'           | 'R0603'             | '(SMR0603AW)'                  | '0'       | '1%'    | '1/10W ' | 'IO'       | 'RES CHIP 0 1/10W +-1% (0603)'                     | 'CHIP0603'     | ''          | ''            | '20100715'
 '0'          | '5%'      | '1/10W'  | '0603LF'  | 'CHIP'   | 'CS00003J900'(!)        = 'End of Design' | 'Comp-Approve'     | 'CS00003J900'           | 'R0603'             | '(SMR0603AW)'                  | '0'       | '5%'    | '1/10W ' | 'DISCRETE' | 'RESISTOR CHIP 0 1/10W+-5%(0603)'                  | 'CHIP0603'     | ''          | ''            | '20100715'
 '0'          | '5%'      | '1/10W'  | '0603LF'  | 'EMPTY'  | 'CS00003J900'(!)        = 'End of Design' | 'Comp-Approve'     | 'CS00003J900'           | 'R0603'             | '(SMR0603AW)'                  | '0'       | '5%'    | '1/10W ' | 'IO'       | 'RESISTOR CHIP 0 1/10W+-5%(0603)'                  | 'CHIP0603'     | ''          | ''            | '20100715'
 '0.001'      | '1%'      | '2W   '  | '2512LF'  | 'CHIP'   | 'CS+001AF104'(!)        = ''              | 'End of Life'      | 'CS+001AF104'           | 'R2512A_EOL'        | '(SMR2512AW)'                  | '0.001'   | '1%'    | '2W    ' | 'DISCRETE' | 'RES CHIP 0.001 2W(+-1%,2512) L-F'                 | 'CHIP2512'     | ''          | ''            | '20100715'
 '0.001'      | '1%'      | '2W   '  | '2512LF'  | 'EMPTY'  | 'CS+001AF104'(!)        = ''              | 'End of Life'      | 'CS+001AF104'           | 'R2512A_EOL'        | '(SMR2512AW)'                  | '0.001'   | '1%'    | '2W    ' | 'IO'       | 'RES CHIP 0.001 2W(+-1%,2512) L-F'                 | 'CHIP2512'     | ''          | ''            | '20100715'
 '49.9'       | '1%'      | '1/16W'  | '0402LF'  | 'CHIP'   | 'CS04992FB31'(!)        = 'End of Design' | 'Comp-Approve'     | 'CS04992FB31'           | 'R0402'             | '(R0402_OCTAGONXA,R0402-0201)' | '49.9'    | '1%'    | '1/16W ' | 'DISCRETE' | 'RES CHIP 49.9 1/16W +-1% (0402)'                  | 'CHIP0402'     | ''          | ''            | '20100716'
 '49.9'       | '1%'      | '1/16W'  | '0402LF'  | 'EMPTY'  | 'CS04992FB31'(!)        = 'End of Design' | 'Comp-Approve'     | 'CS04992FB31'           | 'R0402'             | '(R0402_OCTAGONXA,R0402-0201)' | '49.9'    | '1%'    | '1/16W ' | 'IO'       | 'RES CHIP 49.9 1/16W +-1% (0402)'                  | 'CHIP0402'     | ''          | ''            | '20100716'
 '226      '  | '0.1%'    | '1/16W'  | '0402LF'  | 'CHIP'   | 'CS12262BB00'(!)        = ''              | ''                 | 'CS12262BB00'           | 'R0402'             | '(R0402-0201)'                 | '226'     | '0.1%'  | '1/16W ' | 'DISCRETE' | 'RES CHIP 226 1/16W 0.1% (0402)'                   | 'CHIP0402'     | ''          | ''            | '20100716'
 '226      '  | '0.1%'    | '1/16W'  | '0402LF'  | 'EMPTY'  | 'CS12262BB00'(!)        = ''              | ''                 | 'CS12262BB00'           | 'R0402'             | '(R0402-0201)'                 | '226'     | '0.1%'  | '1/16W ' | 'IO'       | 'RES CHIP 226 1/16W 0.1% (0402)'                   | 'CHIP0402'     | ''          | ''            | '20100716'
 '2.21K    '  | '1%  '    | '1/16W'  | '0402LF'  | 'CHIP'   | 'CS22212FB11'(!)        = 'End of Design' | 'Comp-Approve'     | 'CS22212FB11'           | 'R0402'             | '(R0402-0201)'                 | '2.21K'   | '1%  '  | '1/16W ' | 'DISCRETE' | 'RES CHIP 2.21K 1/16W +-1% (0402)'                 | 'CHIP0402'     | ''          | ''            | '20100716'
 '2.21K    '  | '1%  '    | '1/16W'  | '0402LF'  | 'EMPTY'  | 'CS22212FB11'(!)        = 'End of Design' | 'Comp-Approve'     | 'CS22212FB11'           | 'R0402'             | '(R0402-0201)'                 | '2.21K'   | '1%  '  | '1/16W ' | 'IO'       | 'RES CHIP 2.21K 1/16W +-1% (0402)'                 | 'CHIP0402'     | ''          | ''            | '20100716'
 '3K       '  | '1%  '    | '1/16W'  | '0402LF'  | 'CHIP'   | 'CS23002FB11'(!)        = 'End of Design' | 'Comp-Approve'     | 'CS23002FB11'           | 'R0402'             | '(R0402-0201)'                 | '3K'      | '1%  '  | '1/16W ' | 'DISCRETE' | 'RES CHIP 3K 1/16W +-1%(0402)'                     | 'CHIP0402'     | ''          | ''            | '20100716'
 '3K       '  | '1%  '    | '1/16W'  | '0402LF'  | 'EMPTY'  | 'CS23002FB11'(!)        = 'End of Design' | 'Comp-Approve'     | 'CS23002FB11'           | 'R0402'             | '(R0402-0201)'                 | '3K'      | '1%  '  | '1/16W ' | 'IO'       | 'RES CHIP 3K 1/16W +-1%(0402)'                     | 'CHIP0402'     | ''          | ''            | '20100716'
 '6.2K'       | '1%'      | '1/16W'  | '0402LF'  | 'CHIP'   | 'CS26202FB17'(!)        = 'End of Design' | 'Comp-Approve'     | 'CS26202FB17'           | 'R0402'             | '(R0402-0201)'                 | '6.2K'    | '1%'    | '1/16W'  | 'DISCRETE' | 'RES CHIP 6.2K 1/16W +-1%(0402)'                   | 'CHIP0402'     | ''          | ''            | '20100716'
 '6.2K'       | '1%'      | '1/16W'  | '0402LF'  | 'EMPTY'  | 'CS26202FB17'(!)        = 'End of Design' | 'Comp-Approve'     | 'CS26202FB17'           | 'R0402'             | '(R0402-0201)'                 | '6.2K'    | '1%'    | '1/16W'  | 'IO'       | 'RES CHIP 6.2K 1/16W +-1%(0402)'                   | 'CHIP0402'     | ''          | ''            | '20100716'
 '10K      '  | '0.1%'    | '1/16W'  | '0402LF'  | 'CHIP'   | 'CS31002BB02'(!)        = ''              | ''                 | 'CS31002BB02'           | 'R0402'             | '(R0402-0201)'                 | '10K'     | '0.1%'  | '1/16W'  | 'DISCRETE' | 'RES CHIP 10K 1/16W+-0.1%(0402)JET ASSIGN'         | 'CHIP0402'     | ''          | ''            | '20100716'
 '10K      '  | '0.1%'    | '1/16W'  | '0402LF'  | 'EMPTY'  | 'CS31002BB02'(!)        = ''              | ''                 | 'CS31002BB02'           | 'R0402'             | '(R0402-0201)'                 | '10K'     | '0.1%'  | '1/16W'  | 'IO'       | 'RES CHIP 10K 1/16W+-0.1%(0402)JET ASSIGN'         | 'CHIP0402'     | ''          | ''            | '20100716'
 '22K      '  | '5%  '    | '1/16W'  | '0402LF'  | 'CHIP'   | 'CS32202JB28'(!)        = 'End of Design' | 'Comp-Approve'     | 'CS32202JB28'           | 'R0402'             | '(R0402-0201)'                 | '22K'     | '5%'    | '1/16W'  | 'DISCRETE' | 'RES CHIP 22K 1/16W +-5% (0402)'                   | 'CHIP0402'     | ''          | ''            | '20100716'
 '22K      '  | '5%  '    | '1/16W'  | '0402LF'  | 'EMPTY'  | 'CS32202JB28'(!)        = 'End of Design' | 'Comp-Approve'     | 'CS32202JB28'           | 'R0402'             | '(R0402-0201)'                 | '22K'     | '5%'    | '1/16W'  | 'IO'       | 'RES CHIP 22K 1/16W +-5% (0402)'                   | 'CHIP0402'     | ''          | ''            | '20100716'
 '30.1K    '  | '1%  '    | '1/16W'  | '0402LF'  | 'CHIP'   | 'CS33012FB18'(!)        = 'End of Design' | 'Comp-Approve'     | 'CS33012FB18'           | 'R0402'             | '(R0402-0201)'                 | '30.1K'   | '1%  '  | '1/16W'  | 'DISCRETE' | 'RES CHIP 30.1K 1/16W +-1%(0402)'                  | 'CHIP0402'     | ''          | ''            | '20100716'
 '30.1K    '  | '1%  '    | '1/16W'  | '0402LF'  | 'EMPTY'  | 'CS33012FB18'(!)        = 'End of Design' | 'Comp-Approve'     | 'CS33012FB18'           | 'R0402'             | '(R0402-0201)'                 | '30.1K'   | '1%  '  | '1/16W'  | 'IO'       | 'RES CHIP 30.1K 1/16W +-1%(0402)'                  | 'CHIP0402'     | ''          | ''            | '20100716'
 '33K'        | '0.1%'    | '1/16W'  | '0402LF'  | 'CHIP'   | 'CS33302BB00'(!)        = ''              | ''                 | 'CS33302BB00'           | 'R0402'             | '(R0402-0201)'                 | '33K'     | '0.1%'  | '1/16W'  | 'DISCRETE' | 'RES CHIP 33K 1/16W 0.1% (0402)'                   | 'CHIP0402'     | ''          | ''            | '20100716'
 '33K'        | '0.1%'    | '1/16W'  | '0402LF'  | 'EMPTY'  | 'CS33302BB00'(!)        = ''              | ''                 | 'CS33302BB00'           | 'R0402'             | '(R0402-0201)'                 | '33K'     | '0.1%'  | '1/16W'  | 'IO'       | 'RES CHIP 33K 1/16W 0.1% (0402)'                   | 'CHIP0402'     | ''          | ''            | '20100716'
 '100      '  | '5%  '    | '1/10W'  | '0603LF'  | 'CHIP'   | 'CS11003J947'(!)        = ''              | ''                 | 'CS11003J947'           | 'R0603'             | '(SMR0603AW)'                  | '100'     | '5%'    | '1/10W'  | 'DISCRETE' | 'RESISTOR CHIP 100 1/10W +-5%(0603)EP'             | 'CHIP0603'     | ''          | ''            | '20100716'
 '100      '  | '5%  '    | '1/10W'  | '0603LF'  | 'EMPTY'  | 'CS11003J947'(!)        = ''              | ''                 | 'CS11003J947'           | 'R0603'             | '(SMR0603AW)'                  | '100'     | '5%'    | '1/10W'  | 'IO'       | 'RESISTOR CHIP 100 1/10W +-5%(0603)EP'             | 'CHIP0603'     | ''          | ''            | '20100716'
 '180      '  | '1%  '    | '1/10W'  | '0603LF'  | 'CHIP'   | 'CS11803F910'(!)        = 'End of Design' | 'Comp-Approve'     | 'CS11803F910'           | 'R0603'             | '(SMR0603AW)'                  | '180'     | '1%'    | '1/10W'  | 'DISCRETE' | 'RES CHIP 180 1/10W +-1%(0603)EP'                  | 'CHIP0603'     | ''          | ''            | '20100716'
 '180      '  | '1%  '    | '1/10W'  | '0603LF'  | 'EMPTY'  | 'CS11803F910'(!)        = 'End of Design' | 'Comp-Approve'     | 'CS11803F910'           | 'R0603'             | '(SMR0603AW)'                  | '180'     | '1%'    | '1/10W'  | 'IO'       | 'RES CHIP 180 1/10W +-1%(0603)EP'                  | 'CHIP0603'     | ''          | ''            | '20100716'
 '200      '  | '1%  '    | '1/10W'  | '0603LF'  | 'CHIP'   | 'CS12003F930'(!)        = ''              | ''                 | 'CS12003F930'           | 'R0603'             | '(SMR0603AW)'                  | '200'     | '1%'    | '1/10W'  | 'DISCRETE' | 'RES CHIP 200 1/10W 1% (0603)EP'                   | 'CHIP0603'     | ''          | ''            | '20100716'
 '200      '  | '1%  '    | '1/10W'  | '0603LF'  | 'EMPTY'  | 'CS12003F930'(!)        = ''              | ''                 | 'CS12003F930'           | 'R0603'             | '(SMR0603AW)'                  | '200'     | '1%'    | '1/10W'  | 'IO'       | 'RES CHIP 200 1/10W 1% (0603)EP'                   | 'CHIP0603'     | ''          | ''            | '20100716'
 '1K       '  | '5%  '    | '1/10W'  | '0603LF'  | 'CHIP'   | 'CS21003J949'(!)        = ''              | ''                 | 'CS21003J949'           | 'R0603'             | '(SMR0603AW)'                  | '1K'      | '5%'    | '1/10W'  | 'DISCRETE' | 'RES CHIP 1K 1/10W +-5%(0603)'                     | 'CHIP0603'     | ''          | ''            | '20100716'
 '1K       '  | '5%  '    | '1/10W'  | '0603LF'  | 'EMPTY'  | 'CS21003J949'(!)        = ''              | ''                 | 'CS21003J949'           | 'R0603'             | '(SMR0603AW)'                  | '1K'      | '5%'    | '1/10W'  | 'IO'       | 'RES CHIP 1K 1/10W +-5%(0603)'                     | 'CHIP0603'     | ''          | ''            | '20100716'
 '54.9      ' | '1%  '    | '1/10W'  | '0603LF'  | 'CHIP'   | 'CS05493F931'(!)        = ''              | ''                 | 'CS05493F931'           | 'R0603'             | '(SMR0603AW)'                  | '54.9'    | '1%'    | '1/10W'  | 'DISCRETE' | 'RES CHIP 54.9 1/10W +-1%(0603)'                   | 'CHIP0603'     | ''          | ''            | '20100718'
 '54.9      ' | '1%  '    | '1/10W'  | '0603LF'  | 'EMPTY'  | 'CS05493F931'(!)        = ''              | ''                 | 'CS05493F931'           | 'R0603'             | '(SMR0603AW)'                  | '54.9'    | '1%'    | '1/10W'  | 'IO'       | 'RES CHIP 54.9 1/10W +-1%(0603)'                   | 'CHIP0603'     | ''          | ''            | '20100718'
 '2.15K     ' | '1%  '    | '1/10W'  | '0603LF'  | 'CHIP'   | 'CS22153F920'(!)        = ''              | ''                 | 'CS22153F920'           | 'R0603'             | '(SMR0603AW)'                  | '2.15K'   | '1%'    | '1/10W'  | 'DISCRETE' | 'RES CHIP 2.15K 1/10W +-1%(0603)'                  | 'CHIP0603'     | ''          | ''            | '20100718'
 '2.15K     ' | '1%  '    | '1/10W'  | '0603LF'  | 'EMPTY'  | 'CS22153F920'(!)        = ''              | ''                 | 'CS22153F920'           | 'R0603'             | '(SMR0603AW)'                  | '2.15K'   | '1%'    | '1/10W'  | 'IO'       | 'RES CHIP 2.15K 1/10W +-1%(0603)'                  | 'CHIP0603'     | ''          | ''            | '20100718'
 '3.4K      ' | '1%  '    | '1/10W'  | '0603LF'  | 'CHIP'   | 'CS23403F912'(!)        = ''              | ''                 | 'CS23403F912'           | 'R0603'             | '(SMR0603AW)'                  | '3.4K'    | '1%'    | '1/10W'  | 'DISCRETE' | 'RESISTOR CHIP 3.4K 1/10W+-1%(0603)'               | 'CHIP0603'     | ''          | ''            | '20100718'
 '3.4K      ' | '1%  '    | '1/10W'  | '0603LF'  | 'EMPTY'  | 'CS23403F912'(!)        = ''              | ''                 | 'CS23403F912'           | 'R0603'             | '(SMR0603AW)'                  | '3.4K'    | '1%'    | '1/10W'  | 'IO'       | 'RESISTOR CHIP 3.4K 1/10W+-1%(0603)'               | 'CHIP0603'     | ''          | ''            | '20100718'
 '10K       ' | '1%  '    | '1/10W'  | '0603LF'  | 'CHIP'   | 'CS31003F949'(!)        = ''              | ''                 | 'CS31003F949'           | 'R0603'             | '(SMR0603AW)'                  | '10K'     | '1%'    | '1/10W'  | 'DISCRETE' | 'RESISTOR CHIP 10K 1/10W+-1%(0603)'                | 'CHIP0603'     | ''          | ''            | '20100718'
 '10K       ' | '1%  '    | '1/10W'  | '0603LF'  | 'EMPTY'  | 'CS31003F949'(!)        = ''              | ''                 | 'CS31003F949'           | 'R0603'             | '(SMR0603AW)'                  | '10K'     | '1%'    | '1/10W'  | 'IO'       | 'RESISTOR CHIP 10K 1/10W+-1%(0603)'                | 'CHIP0603'     | ''          | ''            | '20100718'
 '511      '  | '1%  '    | '1/16W'  | '0402LF'  | 'CHIP'   | 'CS15112FB13'(!)        = 'End of Design' | 'Comp-Approve'     | 'CS15112FB13'           | 'R0402'             | '(R0402-0201)'                 | '511'     | '1%'    | '1/16W'  | 'DISCRETE' | 'RES CHIP 511 1/16W +-1%(0402)'                    | 'CHIP0402'     | ''          | ''            | '20100720'
 '511      '  | '1%  '    | '1/16W'  | '0402LF'  | 'EMPTY'  | 'CS15112FB13'(!)        = 'End of Design' | 'Comp-Approve'     | 'CS15112FB13'           | 'R0402'             | '(R0402-0201)'                 | '511'     | '1%'    | '1/16W'  | 'IO'       | 'RES CHIP 511 1/16W +-1%(0402)'                    | 'CHIP0402'     | ''          | ''            | '20100720'
 '604      '  | '1%  '    | '1/16W'  | '0402LF'  | 'CHIP'   | 'CS16042FB24'(!)        = 'End of Design' | 'Comp-Approve'     | 'CS16042FB24'           | 'R0402'             | '(R0402-0201)'                 | '604'     | '1%'    | '1/16W'  | 'DISCRETE' | 'RES CHIP 604 1/16W +-1%(0402)'                    | 'CHIP0402'     | ''          | ''            | '20100720'
 '604      '  | '1%  '    | '1/16W'  | '0402LF'  | 'EMPTY'  | 'CS16042FB24'(!)        = 'End of Design' | 'Comp-Approve'     | 'CS16042FB24'           | 'R0402'             | '(R0402-0201)'                 | '604'     | '1%'    | '1/16W'  | 'IO'       | 'RES CHIP 604 1/16W +-1%(0402)'                    | 'CHIP0402'     | ''          | ''            | '20100720'
 '13.7K    '  | '1%  '    | '1/16W'  | '0402LF'  | 'CHIP'   | 'CS31372FB11'(!)        = 'End of Design' | 'Comp-Approve'     | 'CS31372FB11'           | 'R0402'             | '(R0402-0201)'                 | '13.7K'   | '1%'    | '1/16W'  | 'DISCRETE' | 'RES CHIP 13.7K 1/16W +-1%(0402)'                  | 'CHIP0402'     | ''          | ''            | '20100720'
 '13.7K    '  | '1%  '    | '1/16W'  | '0402LF'  | 'EMPTY'  | 'CS31372FB11'(!)        = 'End of Design' | 'Comp-Approve'     | 'CS31372FB11'           | 'R0402'             | '(R0402-0201)'                 | '13.7K'   | '1%'    | '1/16W'  | 'IO'       | 'RES CHIP 13.7K 1/16W +-1%(0402)'                  | 'CHIP0402'     | ''          | ''            | '20100720'
 '18.7K    '  | '1%  '    | '1/16W'  | '0402LF'  | 'CHIP'   | 'CS31872FB19'(!)        = 'End of Design' | 'Comp-Approve'     | 'CS31872FB19'           | 'R0402'             | '(R0402-0201)'                 | '18.7k'   | '1%'    | '1/16W'  | 'DISCRETE' | 'RES CHIP 18.7K 1/16W +-1%(0402)'                  | 'CHIP0402'     | ''          | ''            | '20100720'
 '18.7K    '  | '1%  '    | '1/16W'  | '0402LF'  | 'EMPTY'  | 'CS31872FB19'(!)        = 'End of Design' | 'Comp-Approve'     | 'CS31872FB19'           | 'R0402'             | '(R0402-0201)'                 | '18.7k'   | '1%'    | '1/16W'  | 'IO'       | 'RES CHIP 18.7K 1/16W +-1%(0402)'                  | 'CHIP0402'     | ''          | ''            | '20100720'
 '2.21K    '  | '0.5%  '  | '1/10W'  | '0603LF'  | 'CHIP'   | 'CS22213D906'(!)        = ''              | ''                 | 'CS22213D906'           | 'R0603'             | '(SMR0603AW)'                  | '2.21K'   | '0.5%'  | '1/10W'  | 'DISCRETE' | 'RESISTOR CHIP 2.21K 1/10W+-0.5%(0603)L-F'         | 'CHIP0603'     | ''          | ''            | '20100727'
 '2.21K    '  | '0.5%  '  | '1/10W'  | '0603LF'  | 'EMPTY'  | 'CS22213D906'(!)        = ''              | ''                 | 'CS22213D906'           | 'R0603'             | '(SMR0603AW)'                  | '2.21K'   | '0.5%'  | '1/10W'  | 'IO'       | 'RESISTOR CHIP 2.21K 1/10W+-0.5%(0603)L-F'         | 'CHIP0603'     | ''          | ''            | '20100727'
 '33K    '    | '1%  '    | '1/16W'  | '0402LF'  | 'CHIP'   | 'CS33302FB14'(!)        = 'End of Design' | 'Comp-Approve'     | 'CS33302FB14'           | 'R0402'             | '(R0402-0201)'                 | '33K'     | '1%'    | '1/16W'  | 'DISCRETE' | 'RES CHIP 33K 1/16W +-1%(0402)'                    | 'CHIP0402'     | ''          | ''            | '20100802'
 '33K    '    | '1%  '    | '1/16W'  | '0402LF'  | 'EMPTY'  | 'CS33302FB14'(!)        = 'End of Design' | 'Comp-Approve'     | 'CS33302FB14'           | 'R0402'             | '(R0402-0201)'                 | '33K'     | '1%'    | '1/16W'  | 'IO'       | 'RES CHIP 33K 1/16W +-1%(0402)'                    | 'CHIP0402'     | ''          | ''            | '20100802'
 '22'         | '5%'      | '1/16W'  | '0402LF'  | 'CHIP'   | 'CS02202JB22'(!)        = 'End of Design' | 'Comp-Approve'     | 'CS02202JB22'           | 'R0402'             | '(R0402-0201)'                 | '22'      | '5%'    | '1/16W'  | 'DISCRETE' | 'RES CHIP 22 1/16W 5%(0402)'                       | 'CHIP0402'     | ''          | ''            | '20100811'
 '22'         | '5%'      | '1/16W'  | '0402LF'  | 'EMPTY'  | 'CS02202JB22'(!)        = 'End of Design' | 'Comp-Approve'     | 'CS02202JB22'           | 'R0402'             | '(R0402-0201)'                 | '22'      | '5%'    | '1/16W'  | 'IO'       | 'RES CHIP 22 1/16W 5%(0402)'                       | 'CHIP0402'     | ''          | ''            | '20100811'
 '22.1     '  | '1%  '    | '1/16W'  | '0402LF'  | 'CHIP'   | 'CS02212FB09'(!)        = 'End of Design' | 'Comp-Approve'     | 'CS02212FB09'           | 'R0402'             | '(R0402-0201)'                 | '22.1'    | '1%'    | '1/16W'  | 'DISCRETE' | 'RES CHIP 22.1 1/16W +-1%(0402) L-F'               | 'CHIP0402'     | ''          | ''            | '20100811'
 '22.1     '  | '1%  '    | '1/16W'  | '0402LF'  | 'EMPTY'  | 'CS02212FB09'(!)        = 'End of Design' | 'Comp-Approve'     | 'CS02212FB09'           | 'R0402'             | '(R0402-0201)'                 | '22.1'    | '1%'    | '1/16W'  | 'IO'       | 'RES CHIP 22.1 1/16W +-1%(0402) L-F'               | 'CHIP0402'     | ''          | ''            | '20100811'
 '33'         | '1%'      | '1/16W'  | '0402LF'  | 'CHIP'   | 'CS03302FB19'(!)        = 'End of Design' | 'Comp-Approve'     | 'CS03302FB19'           | 'R0402'             | '(R0402-0201)'                 | '33'      | '1%'    | '1/16W'  | 'DISCRETE' | 'RES CHIP 33 1/16W +-1%(0402)'                     | 'CHIP0402'     | ''          | ''            | '20100811'
 '33'         | '1%'      | '1/16W'  | '0402LF'  | 'EMPTY'  | 'CS03302FB19'(!)        = 'End of Design' | 'Comp-Approve'     | 'CS03302FB19'           | 'R0402'             | '(R0402-0201)'                 | '33'      | '1%'    | '1/16W'  | 'IO'       | 'RES CHIP 33 1/16W +-1%(0402)'                     | 'CHIP0402'     | ''          | ''            | '20100811'
 '75'         | '1%'      | '1/16W'  | '0402LF'  | 'CHIP'   | 'CS07502FB17'(!)        = 'End of Design' | 'Comp-Approve'     | 'CS07502FB17'           | 'R0402'             | '(R0402-0201)'                 | '75'      | '1%'    | '1/16W'  | 'DISCRETE' | 'RES CHIP 75 1/16W +-1% (0402)'                    | 'CHIP0402'     | ''          | ''            | '20100811'
 '75'         | '1%'      | '1/16W'  | '0402LF'  | 'EMPTY'  | 'CS07502FB17'(!)        = 'End of Design' | 'Comp-Approve'     | 'CS07502FB17'           | 'R0402'             | '(R0402-0201)'                 | '75'      | '1%'    | '1/16W'  | 'IO'       | 'RES CHIP 75 1/16W +-1% (0402)'                    | 'CHIP0402'     | ''          | ''            | '20100811'
 '2.7K     '  | '5%  '    | '1/16W'  | '0402LF'  | 'CHIP'   | 'CS22702JB16'(!)        = 'End of Design' | 'Comp-Approve'     | 'CS22702JB16'           | 'R0402'             | '(R0402-0201)'                 | '2.7K'    | '5%'    | '1/16W'  | 'DISCRETE' | 'RES CHIP 2.7K 1/16W +-5%(0402)'                   | 'CHIP0402'     | ''          | ''            | '20100811'
 '2.7K     '  | '5%  '    | '1/16W'  | '0402LF'  | 'EMPTY'  | 'CS22702JB16'(!)        = 'End of Design' | 'Comp-Approve'     | 'CS22702JB16'           | 'R0402'             | '(R0402-0201)'                 | '2.7K'    | '5%'    | '1/16W'  | 'IO'       | 'RES CHIP 2.7K 1/16W +-5%(0402)'                   | 'CHIP0402'     | ''          | ''            | '20100811'
 '8.2K     '  | '5%  '    | '1/16W'  | '0402LF'  | 'CHIP'   | 'CS28202JB14'(!)        = 'End of Design' | 'Comp-Approve'     | 'CS28202JB14'           | 'R0402'             | '(R0402-0201)'                 | '8.2K'    | '5%'    | '1/16W'  | 'DISCRETE' | 'RES CHIP 8.2K 1/16W +-5% (0402)'                  | 'CHIP0402'     | ''          | ''            | '20100811'
 '8.2K     '  | '5%  '    | '1/16W'  | '0402LF'  | 'EMPTY'  | 'CS28202JB14'(!)        = 'End of Design' | 'Comp-Approve'     | 'CS28202JB14'           | 'R0402'             | '(R0402-0201)'                 | '8.2K'    | '5%'    | '1/16W'  | 'IO'       | 'RES CHIP 8.2K 1/16W +-5% (0402)'                  | 'CHIP0402'     | ''          | ''            | '20100811'
 '270K     '  | '5%  '    | '1/16W'  | '0402LF'  | 'CHIP'   | 'CS42702JB10'(!)        = 'End of Design' | 'Comp-Approve'     | 'CS42702JB10'           | 'R0402'             | '(R0402-0201)'                 | '270K'    | '5%'    | '1/16W'  | 'DISCRETE' | 'RES CHIP 270K(1/16W,+-5%,0402)'                   | 'CHIP0402'     | ''          | ''            | '20100811'
 '270K     '  | '5%  '    | '1/16W'  | '0402LF'  | 'EMPTY'  | 'CS42702JB10'(!)        = 'End of Design' | 'Comp-Approve'     | 'CS42702JB10'           | 'R0402'             | '(R0402-0201)'                 | '270K'    | '5%'    | '1/16W'  | 'IO'       | 'RES CHIP 270K(1/16W,+-5%,0402)'                   | 'CHIP0402'     | ''          | ''            | '20100811'
 '1.21K    '  | '1%  '    | '1/10W'  | '0603LF'  | 'CHIP'   | 'CS21213F914'(!)        = 'End of Design' | 'Comp-Approve'     | 'CS21213F914'           | 'R0603'             | '(SMR0603AW)'                  | '1.21K'   | '1%'    | '1/10W'  | 'DISCRETE' | 'RES CHIP 1.21K 1/10W +-1% (0603) EP'              | 'CHIP0603'     | ''          | ''            | '20100811'
 '1.21K    '  | '1%  '    | '1/10W'  | '0603LF'  | 'EMPTY'  | 'CS21213F914'(!)        = 'End of Design' | 'Comp-Approve'     | 'CS21213F914'           | 'R0603'             | '(SMR0603AW)'                  | '1.21K'   | '1%'    | '1/10W'  | 'IO'       | 'RES CHIP 1.21K 1/10W +-1% (0603) EP'              | 'CHIP0603'     | ''          | ''            | '20100811'
 '1.5K'       | '1%'      | '1/10W'  | '0603LF'  | 'CHIP'   | 'CS21503F911'(!)        = ''              | ''                 | 'CS21503F911'           | 'R0603'             | '(SMR0603AW)'                  | '1.5K'    | '1%'    | '1/10W ' | 'DISCRETE' | 'RESISTOR CHIP 1.5K 1/10W +-1%(1608)'              | 'CHIP0603'     | ''          | ''            | '20100811'
 '1.5K'       | '1%'      | '1/10W'  | '0603LF'  | 'EMPTY'  | 'CS21503F911'(!)        = ''              | ''                 | 'CS21503F911'           | 'R0603'             | '(SMR0603AW)'                  | '1.5K'    | '1%'    | '1/10W ' | 'IO'       | 'RESISTOR CHIP 1.5K 1/10W +-1%(1608)'              | 'CHIP0603'     | ''          | ''            | '20100811'
 '2.1K'       | '1%'      | '1/10W'  | '0603LF'  | 'CHIP'   | 'CS22103F901'(!)        = ''              | ''                 | 'CS22103F901'           | 'R0603'             | '(SMR0603AW)'                  | '2.1K'    | '1%'    | '1/10W ' | 'DISCRETE' | 'RES CHIP 2.1K 1/10W +-1% (0603)'                  | 'CHIP0603'     | ''          | ''            | '20100811'
 '2.1K'       | '1%'      | '1/10W'  | '0603LF'  | 'EMPTY'  | 'CS22103F901'(!)        = ''              | ''                 | 'CS22103F901'           | 'R0603'             | '(SMR0603AW)'                  | '2.1K'    | '1%'    | '1/10W ' | 'IO'       | 'RES CHIP 2.1K 1/10W +-1% (0603)'                  | 'CHIP0603'     | ''          | ''            | '20100811'
 '44.2'       | '1%'      | '1/10W'  | '0603LF'  | 'CHIP'   | 'CS04423F911'(!)        = ''              | ''                 | 'CS04423F911'           | 'R0603'             | '(SMR0603AW)'                  | '44.2'    | '1%'    | '1/10W ' | 'DISCRETE' | 'RES CHIP 44.2 1/10W +-1%(0603)L-F'                | 'CHIP0603'     | ''          | ''            | '20100811'
 '44.2'       | '1%'      | '1/10W'  | '0603LF'  | 'EMPTY'  | 'CS04423F911'(!)        = ''              | ''                 | 'CS04423F911'           | 'R0603'             | '(SMR0603AW)'                  | '44.2'    | '1%'    | '1/10W ' | 'IO'       | 'RES CHIP 44.2 1/10W +-1%(0603)L-F'                | 'CHIP0603'     | ''          | ''            | '20100811'
 '1.1K'       | '1%'      | '1/10W'  | '0603LF'  | 'CHIP'   | 'CS21103F916'(!)        = ''              | ''                 | 'CS21103F916'           | 'R0603'             | '(SMR0603AW)'                  | '1.1K'    | '1%'    | '1/10W ' | 'DISCRETE' | 'RES CHIP 1.1K 1/10W +-1%(0603)'                   | 'CHIP0603'     | ''          | ''            | '20100811'
 '1.1K'       | '1%'      | '1/10W'  | '0603LF'  | 'EMPTY'  | 'CS21103F916'(!)        = ''              | ''                 | 'CS21103F916'           | 'R0603'             | '(SMR0603AW)'                  | '1.1K'    | '1%'    | '1/10W ' | 'IO'       | 'RES CHIP 1.1K 1/10W +-1%(0603)'                   | 'CHIP0603'     | ''          | ''            | '20100811'
 '240'        | '5%'      | '1/16W'  | '0402LF'  | 'CHIP'   | 'CS12402JB13'(!)        = 'End of Design' | 'Comp-Approve'     | 'CS12402JB13'           | 'R0402'             | '(R0402-0201)'                 | '240'     | '5%'    | '1/16W'  | 'DISCRETE' | 'RES CHIP 240 1/16W +-5%(0402)'                    | 'CHIP0402'     | ''          | ''            | '20100817'
 '240'        | '5%'      | '1/16W'  | '0402LF'  | 'EMPTY'  | 'CS12402JB13'(!)        = 'End of Design' | 'Comp-Approve'     | 'CS12402JB13'           | 'R0402'             | '(R0402-0201)'                 | '240'     | '5%'    | '1/16W'  | 'IO'       | 'RES CHIP 240 1/16W +-5%(0402)'                    | 'CHIP0402'     | ''          | ''            | '20100817'
 '240'        | '1%'      | '1/16W'  | '0402LF'  | 'CHIP'   | 'CS12402FB03'(!)        = 'End of Design' | 'Comp-Release Qty' | 'CS12402FB03'           | 'R0402'             | '(R0402-0201)'                 | '240'     | '1%'    | '1/16W'  | 'DISCRETE' | 'RES CHIP 240 1/16W +-1%(0402)'                    | 'CHIP0402'     | ''          | ''            | '20100827'
 '240'        | '1%'      | '1/16W'  | '0402LF'  | 'EMPTY'  | 'CS12402FB03'(!)        = 'End of Design' | 'Comp-Release Qty' | 'CS12402FB03'           | 'R0402'             | '(R0402-0201)'                 | '240'     | '1%'    | '1/16W'  | 'IO'       | 'RES CHIP 240 1/16W +-1%(0402)'                    | 'CHIP0402'     | ''          | ''            | '20100827'
 '5.1'        | '5%'      | '1/16W'  | '0402LF'  | 'CHIP'   | 'CS-5102JB03'(!)        = 'End of Design' | 'Comp-Approve'     | 'CS-5102JB03'           | 'R0402'             | '(R0402-0201)'                 | '5.1'     | '5%'    | '1/16W ' | 'DISCRETE' | 'RES CHIP 5.1 1/16W +-5%(0402)'                    | 'CHIP0402'     | ''          | ''            | '20100827'
 '5.1'        | '5%'      | '1/16W'  | '0402LF'  | 'EMPTY'  | 'CS-5102JB03'(!)        = 'End of Design' | 'Comp-Approve'     | 'CS-5102JB03'           | 'R0402'             | '(R0402-0201)'                 | '5.1'     | '5%'    | '1/16W ' | 'IO'       | 'RES CHIP 5.1 1/16W +-5%(0402)'                    | 'CHIP0402'     | ''          | ''            | '20100827'
 '82'         | '5%'      | '1/16W'  | '0402LF'  | 'CHIP'   | 'CS08202JB11'(!)        = 'End of Design' | 'Comp-Approve'     | 'CS08202JB11'           | 'R0402'             | '(R0402-0201)'                 | '82'      | '5%'    | '1/16W'  | 'DISCRETE' | 'RES CHIP 82 1/16W +-5% (0402)'                    | 'CHIP0402'     | ''          | ''            | '20100827'
 '82'         | '5%'      | '1/16W'  | '0402LF'  | 'EMPTY'  | 'CS08202JB11'(!)        = 'End of Design' | 'Comp-Approve'     | 'CS08202JB11'           | 'R0402'             | '(R0402-0201)'                 | '82'      | '5%'    | '1/16W'  | 'IO'       | 'RES CHIP 82 1/16W +-5% (0402)'                    | 'CHIP0402'     | ''          | ''            | '20100827'
 '36'         | '5%'      | '1/16W'  | '0402LF'  | 'CHIP'   | 'CS03602JB01'(!)        = 'End of Design' | 'End of Life'      | 'CS03602JB01'           | 'R0402_EOL'         | '(R0402-0201)'                 | '82'      | '5%'    | '1/16W'  | 'DISCRETE' | 'RES CHIP 36 1/16W +-5%(0402)'                     | 'CHIP0402'     | ''          | ''            | '20100827'
 '36'         | '5%'      | '1/16W'  | '0402LF'  | 'EMPTY'  | 'CS03602JB01'(!)        = 'End of Design' | 'End of Life'      | 'CS03602JB01'           | 'R0402_EOL'         | '(R0402-0201)'                 | '82'      | '5%'    | '1/16W'  | 'IO'       | 'RES CHIP 36 1/16W +-5%(0402)'                     | 'CHIP0402'     | ''          | ''            | '20100827'
 '37.4'       | '1%'      | '1/16W'  | '0402LF'  | 'CHIP'   | 'CS03742FB11'(!)        = 'End of Design' | 'Comp-Approve'     | 'CS03742FB11'           | 'R0402'             | '(R0402-0201)'                 | '37.4'    | '1%  '  | '1/16W'  | 'DISCRETE' | 'RES CHIP 37.4 1/16W +-1%(0402)'                   | 'CHIP0402'     | ''          | ''            | '20100831'
 '37.4'       | '1%'      | '1/16W'  | '0402LF'  | 'EMPTY'  | 'CS03742FB11'(!)        = 'End of Design' | 'Comp-Approve'     | 'CS03742FB11'           | 'R0402'             | '(R0402-0201)'                 | '37.4'    | '1%  '  | '1/16W'  | 'IO'       | 'RES CHIP 37.4 1/16W +-1%(0402)'                   | 'CHIP0402'     | ''          | ''            | '20100831'
 '200'        | '1%'      | '1/16W'  | '0402LF'  | 'CHIP'   | 'CS12002FB25'(!)        = 'End of Design' | 'Comp-Approve'     | 'CS12002FB25'           | 'R0402'             | '(R0402-0201)'                 | '200'     | '1%'    | '1/16W'  | 'DISCRETE' | 'RES CHIP 200 1/16W +-1%(0402)'                    | 'CHIP0402'     | ''          | ''            | '20100831'
 '200'        | '1%'      | '1/16W'  | '0402LF'  | 'EMPTY'  | 'CS12002FB25'(!)        = 'End of Design' | 'Comp-Approve'     | 'CS12002FB25'           | 'R0402'             | '(R0402-0201)'                 | '200'     | '1%'    | '1/16W'  | 'IO'       | 'RES CHIP 200 1/16W +-1%(0402)'                    | 'CHIP0402'     | ''          | ''            | '20100831'
 '26.1 '      | '1%'      | '1/16W'  | '0402LF'  | 'CHIP'   | 'CS02612FB00'(!)        = 'End of Design' | 'Comp-Approve'     | 'CS02612FB00'           | 'R0402'             | '(R0402-0201)'                 | '26.1'    | '1%'    | '1/16W ' | 'DISCRETE' | 'RES CHIP 26.1 1/16W +-1%(0402)'                   | 'CHIP0402'     | ''          | ''            | '20100831'
 '26.1 '      | '1%'      | '1/16W'  | '0402LF'  | 'EMPTY'  | 'CS02612FB00'(!)        = 'End of Design' | 'Comp-Approve'     | 'CS02612FB00'           | 'R0402'             | '(R0402-0201)'                 | '26.1'    | '1%'    | '1/16W ' | 'IO'       | 'RES CHIP 26.1 1/16W +-1%(0402)'                   | 'CHIP0402'     | ''          | ''            | '20100831'
 '20'         | '5%'      | '1/16W'  | '0402LF'  | 'CHIP'   | 'CS02002JB17'(!)        = 'End of Design' | 'Comp-Approve'     | 'CS02002JB17'           | 'R0402'             | '(R0402-0201)'                 | '20'      | '5%'    | '1/16W'  | 'DISCRETE' | 'RES CHIP 20 1/16W +-5% (0402)'                    | 'CHIP0402'     | ''          | ''            | '20100831'
 '20'         | '5%'      | '1/16W'  | '0402LF'  | 'EMPTY'  | 'CS02002JB17'(!)        = 'End of Design' | 'Comp-Approve'     | 'CS02002JB17'           | 'R0402'             | '(R0402-0201)'                 | '20'      | '5%'    | '1/16W'  | 'IO'       | 'RES CHIP 20 1/16W +-5% (0402)'                    | 'CHIP0402'     | ''          | ''            | '20100831'
 '75'         | '5%'      | '1/16W'  | '0402LF'  | 'CHIP'   | 'CS07502JB27'(!)        = 'End of Design' | 'Comp-Approve'     | 'CS07502JB27'           | 'R0402'             | '(R0402-0201)'                 | '75'      | '5%'    | '1/16W'  | 'DISCRETE' | 'RES CHIP 75 1/16W +-5% (0402)'                    | 'CHIP0402'     | ''          | ''            | '20100831'
 '75'         | '5%'      | '1/16W'  | '0402LF'  | 'EMPTY'  | 'CS07502JB27'(!)        = 'End of Design' | 'Comp-Approve'     | 'CS07502JB27'           | 'R0402'             | '(R0402-0201)'                 | '75'      | '5%'    | '1/16W'  | 'IO'       | 'RES CHIP 75 1/16W +-5% (0402)'                    | 'CHIP0402'     | ''          | ''            | '20100831'
 '1.2K '      | '5%'      | '1/16W'  | '0402LF'  | 'CHIP'   | 'CS21202JB15'(!)        = 'End of Design' | 'Comp-Approve'     | 'CS21202JB15'           | 'R0402'             | '(R0402-0201)'                 | '1.2K'    | '5%'    | '1/16W'  | 'DISCRETE' | 'RES CHIP 1.2K 1/16W +-5% (0402)'                  | 'CHIP0402'     | ''          | ''            | '20100831'
 '1.2K '      | '5%'      | '1/16W'  | '0402LF'  | 'EMPTY'  | 'CS21202JB15'(!)        = 'End of Design' | 'Comp-Approve'     | 'CS21202JB15'           | 'R0402'             | '(R0402-0201)'                 | '1.2K'    | '5%'    | '1/16W'  | 'IO'       | 'RES CHIP 1.2K 1/16W +-5% (0402)'                  | 'CHIP0402'     | ''          | ''            | '20100831'
 '1.54K'      | '1%'      | '1/10W'  | '0603LF'  | 'CHIP'   | 'CS21543F927'(!)        = ''              | ''                 | 'CS21543F927'           | 'R0603'             | '(SMR0603AW)'                  | '1.54K'   | '5%'    | '1/10W'  | 'DISCRETE' | 'RESISTOR CHIP 1.54K 1/10W+-1%(0603)'              | 'CHIP0603'     | ''          | ''            | '20100831'
 '1.54K'      | '1%'      | '1/10W'  | '0603LF'  | 'EMPTY'  | 'CS21543F927'(!)        = ''              | ''                 | 'CS21543F927'           | 'R0603'             | '(SMR0603AW)'                  | '1.54K'   | '5%'    | '1/10W'  | 'IO'       | 'RESISTOR CHIP 1.54K 1/10W+-1%(0603)'              | 'CHIP0603'     | ''          | ''            | '20100831'
 '294'        | '1%'      | '1/16W'  | '0402LF'  | 'CHIP'   | 'CS12942FB00'(!)        = 'End of Design' | 'Comp-Approve'     | 'CS12942FB00'           | 'R0402'             | '(R0402-0201)'                 | '294'     | '1%'    | '1/16W'  | 'DISCRETE' | 'RES CHIP 294 1/16W +-1%(0402)'                    | 'CHIP0402'     | ''          | ''            | '20100909'
 '294'        | '1%'      | '1/16W'  | '0402LF'  | 'EMPTY'  | 'CS12942FB00'(!)        = 'End of Design' | 'Comp-Approve'     | 'CS12942FB00'           | 'R0402'             | '(R0402-0201)'                 | '294'     | '1%'    | '1/16W'  | 'IO'       | 'RES CHIP 294 1/16W +-1%(0402)'                    | 'CHIP0402'     | ''          | ''            | '20100909'
 '180'        | '1%'      | '1/16W'  | '0402LF'  | 'CHIP'   | 'CS11802FB05'(!)        = 'End of Design' | 'Comp-Approve'     | 'CS11802FB05'           | 'R0402'             | '(R0402-0201)'                 | '180'     | '1%'    | '1/16W'  | 'DISCRETE' | 'RES CHIP 180 1/16W +-1% (0402)'                   | 'CHIP0402'     | ''          | ''            | '20100913'
 '180'        | '1%'      | '1/16W'  | '0402LF'  | 'EMPTY'  | 'CS11802FB05'(!)        = 'End of Design' | 'Comp-Approve'     | 'CS11802FB05'           | 'R0402'             | '(R0402-0201)'                 | '180'     | '1%'    | '1/16W'  | 'IO'       | 'RES CHIP 180 1/16W +-1% (0402)'                   | 'CHIP0402'     | ''          | ''            | '20100913'
 '2.67K'      | '1%'      | '1/16W'  | '0402LF'  | 'CHIP'   | 'CS22672FB12'(!)        = 'End of Design' | 'Comp-Approve'     | 'CS22672FB12'           | 'R0402'             | '(R0402-0201)'                 | '2.67K'   | '1%'    | '1/16W'  | 'DISCRETE' | 'RES CHIP 2.67K 1/16W +-1%(0402)'                  | 'CHIP0402'     | ''          | ''            | '20100919'
 '2.67K'      | '1%'      | '1/16W'  | '0402LF'  | 'EMPTY'  | 'CS22672FB12'(!)        = 'End of Design' | 'Comp-Approve'     | 'CS22672FB12'           | 'R0402'             | '(R0402-0201)'                 | '2.67K'   | '1%'    | '1/16W'  | 'IO'       | 'RES CHIP 2.67K 1/16W +-1%(0402)'                  | 'CHIP0402'     | ''          | ''            | '20100919'
 '294K'       | '1%'      | '1/16W'  | '0402LF'  | 'CHIP'   | 'CS42942FB13'(!)        = 'End of Design' | 'Comp-Approve'     | 'CS42942FB13'           | 'R0402'             | '(R0402-0201)'                 | '294K'    | '1%'    | '1/16W'  | 'DISCRETE' | 'RES CHIP 294K 1/16W +-1%(0402)'                   | 'CHIP0402'     | ''          | ''            | '20100919'
 '294K'       | '1%'      | '1/16W'  | '0402LF'  | 'EMPTY'  | 'CS42942FB13'(!)        = 'End of Design' | 'Comp-Approve'     | 'CS42942FB13'           | 'R0402'             | '(R0402-0201)'                 | '294K'    | '1%'    | '1/16W'  | 'IO'       | 'RES CHIP 294K 1/16W +-1%(0402)'                   | 'CHIP0402'     | ''          | ''            | '20100919'
 '27.4'       | '1%'      | '1/16W'  | '0402LF'  | 'CHIP'   | 'CS02742FB19'(!)        = 'End of Design' | 'Comp-Release Qty' | 'CS02742FB19'           | 'R0402'             | '(R0402-0201)'                 | '27.4'    | '1%'    | '1/16W'  | 'DISCRETE' | 'RES CHIP 27.4 1/16W +-1%(0402)'                   | 'CHIP0402'     | ''          | ''            | '20100923'
 '27.4'       | '1%'      | '1/16W'  | '0402LF'  | 'EMPTY'  | 'CS02742FB19'(!)        = 'End of Design' | 'Comp-Release Qty' | 'CS02742FB19'           | 'R0402'             | '(R0402-0201)'                 | '27.4'    | '1%'    | '1/16W'  | 'IO'       | 'RES CHIP 27.4 1/16W +-1%(0402)'                   | 'CHIP0402'     | ''          | ''            | '20100923'
 '39'         | '5%'      | '1/16W'  | '0402LF'  | 'CHIP'   | 'CS03902JB21'(!)        = 'End of Design' | 'Comp-Approve'     | 'CS03902JB21'           | 'R0402'             | '(R0402-0201)'                 | '39'      | '5%'    | '1/16W'  | 'DISCRETE' | 'RES CHIP 39 1/16W +-5%(0402)'                     | 'CHIP0402'     | ''          | ''            | '20100923'
 '39'         | '5%'      | '1/16W'  | '0402LF'  | 'EMPTY'  | 'CS03902JB21'(!)        = 'End of Design' | 'Comp-Approve'     | 'CS03902JB21'           | 'R0402'             | '(R0402-0201)'                 | '39'      | '5%'    | '1/16W'  | 'IO'       | 'RES CHIP 39 1/16W +-5%(0402)'                     | 'CHIP0402'     | ''          | ''            | '20100923'
 '42.2'       | '1%'      | '1/16W'  | '0402LF'  | 'CHIP'   | 'CS04222FB01'(!)        = 'End of Design' | 'Comp-Approve'     | 'CS04222FB01'           | 'R0402'             | '(R0402-0201)'                 | '42.2'    | '1%'    | '1/16W'  | 'DISCRETE' | 'RES CHIP 42.2 1/16W +-1%(0402)'                   | 'CHIP0402'     | ''          | ''            | '20100923'
 '42.2'       | '1%'      | '1/16W'  | '0402LF'  | 'EMPTY'  | 'CS04222FB01'(!)        = 'End of Design' | 'Comp-Approve'     | 'CS04222FB01'           | 'R0402'             | '(R0402-0201)'                 | '42.2'    | '1%'    | '1/16W'  | 'IO'       | 'RES CHIP 42.2 1/16W +-1%(0402)'                   | 'CHIP0402'     | ''          | ''            | '20100923'
 '475'        | '1%'      | '1/16W'  | '0402LF'  | 'CHIP'   | 'CS14752FB11'(!)        = 'End of Design' | 'Comp-Approve'     | 'CS14752FB11'           | 'R0402'             | '(R0402-0201)'                 | '475'     | '1%'    | '1/16W'  | 'DISCRETE' | 'RES CHIP 475 1/16W +-1%(0402)'                    | 'CHIP0402'     | ''          | ''            | '20100923'
 '475'        | '1%'      | '1/16W'  | '0402LF'  | 'EMPTY'  | 'CS14752FB11'(!)        = 'End of Design' | 'Comp-Approve'     | 'CS14752FB11'           | 'R0402'             | '(R0402-0201)'                 | '475'     | '1%'    | '1/16W'  | 'IO'       | 'RES CHIP 475 1/16W +-1%(0402)'                    | 'CHIP0402'     | ''          | ''            | '20100923'
 '2.74K'      | '1%'      | '1/16W'  | '0402LF'  | 'CHIP'   | 'CS22742FB00'(!)        = 'End of Design' | 'Comp-Approve'     | 'CS22742FB00'           | 'R0402'             | '(R0402-0201)'                 | '2.74K'   | '1%'    | '1/16W'  | 'DISCRETE' | 'RES CHIP 2.74K 1/16W +-1%(0402)'                  | 'CHIP0402'     | ''          | ''            | '20100923'
 '2.74K'      | '1%'      | '1/16W'  | '0402LF'  | 'EMPTY'  | 'CS22742FB00'(!)        = 'End of Design' | 'Comp-Approve'     | 'CS22742FB00'           | 'R0402'             | '(R0402-0201)'                 | '2.74K'   | '1%'    | '1/16W'  | 'IO'       | 'RES CHIP 2.74K 1/16W +-1%(0402)'                  | 'CHIP0402'     | ''          | ''            | '20100923'
 '2.74K'      | '1%'      | '1/10W'  | '0603LF'  | 'CHIP'   | 'CS22743F935'(!)        = ''              | ''                 | 'CS22743F935'           | 'R0603'             | '(SMR0603AW)'                  | '2.74K'   | '1%'    | '1/10W'  | 'DISCRETE' | 'RES CHIP 2.74K 1/10W +-1%(0603) EP'               | 'CHIP0402'     | ''          | ''            | '20100923'
 '2.74K'      | '1%'      | '1/10W'  | '0603LF'  | 'EMPTY'  | 'CS22743F935'(!)        = ''              | ''                 | 'CS22743F935'           | 'R0603'             | '(SMR0603AW)'                  | '2.74K'   | '1%'    | '1/10W'  | 'IO'       | 'RES CHIP 2.74K 1/10W +-1%(0603) EP'               | 'CHIP0402'     | ''          | ''            | '20100923'
 '0.015'      | '1%'      | '1/2W'   | '2010LF'  | 'CHIP'   | 'CS+0157FJ00'(!)        = 'End of Design' | 'Comp-Release Qty' | 'CS+0157FJ00'           | 'R2010XA'           | '(SMR2010AW)'                  | '0.015'   | '1%'    | '1/2W'   | 'DISCRETE' | 'RES CHIP 0.015 1/2W +-1%(2010)'                   | 'CHIP2010'     | ''          | ''            | '20100927'
 '0.015'      | '1%'      | '1/2W'   | '2010LF'  | 'EMPTY'  | 'CS+0157FJ00'(!)        = 'End of Design' | 'Comp-Release Qty' | 'CS+0157FJ00'           | 'R2010XA'           | '(SMR2010AW)'                  | '0.015'   | '1%'    | '1/2W'   | 'IO'       | 'RES CHIP 0.015 1/2W +-1%(2010)'                   | 'CHIP2010'     | ''          | ''            | '20100927'
 '274'        | '1%'      | '1/10W'  | '0603LF'  | 'CHIP'   | 'CS12743F900'(!)        = 'End of Design' | 'Comp-Approve'     | 'CS12743F900'           | 'R0603'             | '(SMR0603AW)'                  | '274'     | '1%'    | '1/10W'  | 'DISCRETE' | 'RES CHIP 274 1/10W +-1%(0603)'                    | 'CHIP0603'     | ''          | ''            | '20100927'
 '274'        | '1%'      | '1/10W'  | '0603LF'  | 'EMPTY'  | 'CS12743F900'(!)        = 'End of Design' | 'Comp-Approve'     | 'CS12743F900'           | 'R0603'             | '(SMR0603AW)'                  | '274'     | '1%'    | '1/10W'  | 'IO'       | 'RES CHIP 274 1/10W +-1%(0603)'                    | 'CHIP0603'     | ''          | ''            | '20100927'
 '412'        | '1%'      | '1/16W'  | '0402LF'  | 'CHIP'   | 'CS14122FB15'(!)        = 'End of Design' | 'Comp-Approve'     | 'CS14122FB15'           | 'R0402'             | '(R0402-0201)'                 | '412'     | '1%'    | '1/16W'  | 'DISCRETE' | 'RESISTOR CHIP 412 1/16W +-1%(0402)'               | 'CHIP0402'     | ''          | ''            | '20100929'
 '412'        | '1%'      | '1/16W'  | '0402LF'  | 'EMPTY'  | 'CS14122FB15'(!)        = 'End of Design' | 'Comp-Approve'     | 'CS14122FB15'           | 'R0402'             | '(R0402-0201)'                 | '412'     | '1%'    | '1/16W'  | 'IO'       | 'RESISTOR CHIP 412 1/16W +-1%(0402)'               | 'CHIP0402'     | ''          | ''            | '20100929'
 '200K'       | '1%'      | '1/16W'  | '0402LF'  | 'CHIP'   | 'CS42002FB12'(!)        = 'End of Design' | 'Comp-Approve'     | 'CS42002FB12'           | 'R0402'             | '(R0402-0201)'                 | '200K'    | '1%'    | '1/16W'  | 'DISCRETE' | 'RES CHIP 200K 1/16W+-1%(0402)'                    | 'CHIP0402'     | ''          | ''            | '20100929'
 '200K'       | '1%'      | '1/16W'  | '0402LF'  | 'EMPTY'  | 'CS42002FB12'(!)        = 'End of Design' | 'Comp-Approve'     | 'CS42002FB12'           | 'R0402'             | '(R0402-0201)'                 | '200K'    | '1%'    | '1/16W'  | 'IO'       | 'RES CHIP 200K 1/16W+-1%(0402)'                    | 'CHIP0402'     | ''          | ''            | '20100929'
 '9.1K'       | '1%'      | '1/16W'  | '0402LF'  | 'CHIP'   | 'CS29102FB10'(!)        = 'End of Design' | 'Comp-Approve'     | 'CS29102FB10'           | 'R0402'             | '(R0402-0201)'                 | '9.1K'    | '1%'    | '1/16W'  | 'DISCRETE' | 'RES CHIP 9.1K 1/16W +-1%(0402)'                   | 'CHIP0402'     | ''          | ''            | '20101001'
 '9.1K'       | '1%'      | '1/16W'  | '0402LF'  | 'EMPTY'  | 'CS29102FB10'(!)        = 'End of Design' | 'Comp-Approve'     | 'CS29102FB10'           | 'R0402'             | '(R0402-0201)'                 | '9.1K'    | '1%'    | '1/16W'  | 'IO'       | 'RES CHIP 9.1K 1/16W +-1%(0402)'                   | 'CHIP0402'     | ''          | ''            | '20101001'
 '9.31K'      | '1%'      | '1/16W'  | '0402LF'  | 'CHIP'   | 'CS29312FB13'(!)        = 'End of Design' | 'Comp-Approve'     | 'CS29312FB13'           | 'R0402'             | '(R0402-0201)'                 | '9.31K'   | '1%'    | '1/16W'  | 'DISCRETE' | 'RES CHIP 9.31K 1/16W +-1%(0402)'                  | 'CHIP0402'     | ''          | ''            | '20101001'
 '9.31K'      | '1%'      | '1/16W'  | '0402LF'  | 'EMPTY'  | 'CS29312FB13'(!)        = 'End of Design' | 'Comp-Approve'     | 'CS29312FB13'           | 'R0402'             | '(R0402-0201)'                 | '9.31K'   | '1%'    | '1/16W'  | 'IO'       | 'RES CHIP 9.31K 1/16W +-1%(0402)'                  | 'CHIP0402'     | ''          | ''            | '20101001'
 '0.1'        | '1%'      | '1/4W'   | '0805LF'  | 'CHIP'   | 'CS+1006FA18'(!)        = ''              | ''                 | 'CS+1006FA18'           | 'R0805'             | '(SMR0805AW)'                  | '0.1'     | '1%'    | '1/4W'   | 'DISCRETE' | 'RES CHIP 0.1 1/4W +-1%(0805)EU'                   | 'CHIP0805'     | ''          | ''            | '20100930'
 '0.1'        | '1%'      | '1/4W'   | '0805LF'  | 'EMPTY'  | 'CS+1006FA18'(!)        = ''              | ''                 | 'CS+1006FA18'           | 'R0805'             | '(SMR0805AW)'                  | '0.1'     | '1%'    | '1/4W'   | 'IO'       | 'RES CHIP 0.1 1/4W +-1%(0805)EU'                   | 'CHIP0805'     | ''          | ''            | '20100930'
 '22'         | '1%'      | '1/16W'  | '0402LF'  | 'CHIP'   | 'CS02202FB12'(!)        = 'End of Design' | 'Comp-Approve'     | 'CS02202FB12'           | 'R0402'             | '(R0402-0201)'                 | '22'      | '1%'    | '1/16W'  | 'DISCRETE' | 'RES CHIP 22 1/16W +-1%(0402)'                     | 'CHIP0402'     | ''          | ''            | '20100930'
 '22'         | '1%'      | '1/16W'  | '0402LF'  | 'EMPTY'  | 'CS02202FB12'(!)        = 'End of Design' | 'Comp-Approve'     | 'CS02202FB12'           | 'R0402'             | '(R0402-0201)'                 | '22'      | '1%'    | '1/16W'  | 'IO'       | 'RES CHIP 22 1/16W +-1%(0402)'                     | 'CHIP0402'     | ''          | ''            | '20100930'
 '22'         | '5%'      | '1/8W'   | '0805LF'  | 'CHIP'   | 'CS02204JA18'(!)        = ''              | ''                 | 'CS02204JA18'           | 'R0805'             | '(SMR0805AW)'                  | '22'      | '5%'    | '1/8W'   | 'DISCRETE' | 'RES CHIP 22 1/8W +-5%(0805)'                      | 'CHIP0805'     | ''          | ''            | '20100930'
 '22'         | '5%'      | '1/8W'   | '0805LF'  | 'EMPTY'  | 'CS02204JA18'(!)        = ''              | ''                 | 'CS02204JA18'           | 'R0805'             | '(SMR0805AW)'                  | '22'      | '5%'    | '1/8W'   | 'IO'       | 'RES CHIP 22 1/8W +-5%(0805)'                      | 'CHIP0805'     | ''          | ''            | '20100930'
 '24.9'       | '1%'      | '1/16W'  | '0402LF'  | 'CHIP'   | 'CS02492FB29'(!)        = 'End of Design' | 'Comp-Approve'     | 'CS02492FB29'           | 'R0402'             | '(R0402-0201)'                 | '24.9'    | '1%'    | '1/16W'  | 'DISCRETE' | 'RES CHIP 24.9 1/16W +-1%(0402)'                   | 'CHIP0402'     | ''          | ''            | '20100930'
 '24.9'       | '1%'      | '1/16W'  | '0402LF'  | 'EMPTY'  | 'CS02492FB29'(!)        = 'End of Design' | 'Comp-Approve'     | 'CS02492FB29'           | 'R0402'             | '(R0402-0201)'                 | '24.9'    | '1%'    | '1/16W'  | 'IO'       | 'RES CHIP 24.9 1/16W +-1%(0402)'                   | 'CHIP0402'     | ''          | ''            | '20100930'
 '51'         | '5%'      | '1/16W'  | '0402LF'  | 'CHIP'   | 'CS05102JB35'(!)        = 'End of Design' | 'Comp-Approve'     | 'CS05102JB35'           | 'R0402'             | '(R0402-0201)'                 | '51'      | '5%'    | '1/16W'  | 'DISCRETE' | 'RES CHIP 51 1/16W +-5%(0402)'                     | 'CHIP0402'     | ''          | ''            | '20100930'
 '51'         | '5%'      | '1/16W'  | '0402LF'  | 'EMPTY'  | 'CS05102JB35'(!)        = 'End of Design' | 'Comp-Approve'     | 'CS05102JB35'           | 'R0402'             | '(R0402-0201)'                 | '51'      | '5%'    | '1/16W'  | 'IO'       | 'RES CHIP 51 1/16W +-5%(0402)'                     | 'CHIP0402'     | ''          | ''            | '20100930'
 '51.1'       | '1%'      | '1/10W'  | '0603LF'  | 'CHIP'   | 'CS05113F918'(!)        = ''              | ''                 | 'CS05113F918'           | 'R0603'             | '(SMR0603AW)'                  | '51.1'    | '1%'    | '1/10W'  | 'DISCRETE' | 'RES CHIP 51.1 1/10W +-1%(0603)'                   | 'CHIP0603'     | ''          | ''            | '20100930'
 '51.1'       | '1%'      | '1/10W'  | '0603LF'  | 'EMPTY'  | 'CS05113F918'(!)        = ''              | ''                 | 'CS05113F918'           | 'R0603'             | '(SMR0603AW)'                  | '51.1'    | '1%'    | '1/10W'  | 'IO'       | 'RES CHIP 51.1 1/10W +-1%(0603)'                   | 'CHIP0603'     | ''          | ''            | '20100930'
 '169'        | '1%'      | '1/16W'  | '0402LF'  | 'CHIP'   | 'CS11692FB09'(!)        = 'End of Design' | 'Comp-Approve'     | 'CS11692FB09'           | 'R0402'             | '(R0402-0201)'                 | '169'     | '1%'    | '1/16W'  | 'DISCRETE' | 'RES CHIP 169 1/16W +-1%(0402)'                    | 'CHIP0402'     | ''          | ''            | '20100930'
 '169'        | '1%'      | '1/16W'  | '0402LF'  | 'EMPTY'  | 'CS11692FB09'(!)        = 'End of Design' | 'Comp-Approve'     | 'CS11692FB09'           | 'R0402'             | '(R0402-0201)'                 | '169'     | '1%'    | '1/16W'  | 'IO'       | 'RES CHIP 169 1/16W +-1%(0402)'                    | 'CHIP0402'     | ''          | ''            | '20100930'
 '200'        | '5%'      | '1/10W'  | '0603LF'  | 'CHIP'   | 'CS12003J940'(!)        = 'End of Design' | 'Comp-Approve'     | 'CS12003J940'           | 'R0603'             | '(SMR0603AW)'                  | '200'     | '5%'    | '1/10W'  | 'DISCRETE' | 'RESISTOR CHIP 200 1/10W+-5%(0603)'                | 'CHIP0603'     | ''          | ''            | '20100930'
 '200'        | '5%'      | '1/10W'  | '0603LF'  | 'EMPTY'  | 'CS12003J940'(!)        = 'End of Design' | 'Comp-Approve'     | 'CS12003J940'           | 'R0603'             | '(SMR0603AW)'                  | '200'     | '5%'    | '1/10W'  | 'IO'       | 'RESISTOR CHIP 200 1/10W+-5%(0603)'                | 'CHIP0603'     | ''          | ''            | '20100930'
 '392'        | '1%'      | '1/16W'  | '0402LF'  | 'CHIP'   | 'CS13922FB11'(!)        = 'End of Design' | 'Comp-Approve'     | 'CS13922FB11'           | 'R0402'             | '(R0402-0201)'                 | '392'     | '1%'    | '1/16W'  | 'DISCRETE' | 'RES CHIP 392 1/16W +-1%(0402)'                    | 'CHIP0402'     | ''          | ''            | '20100930'
 '392'        | '1%'      | '1/16W'  | '0402LF'  | 'EMPTY'  | 'CS13922FB11'(!)        = 'End of Design' | 'Comp-Approve'     | 'CS13922FB11'           | 'R0402'             | '(R0402-0201)'                 | '392'     | '1%'    | '1/16W'  | 'IO'       | 'RES CHIP 392 1/16W +-1%(0402)'                    | 'CHIP0402'     | ''          | ''            | '20100930'
 '510'        | '5%'      | '1/16W'  | '0402LF'  | 'CHIP'   | 'CS15102JB00'(!)        = 'End of Design' | 'Comp-Approve'     | 'CS15102JB00'           | 'R0402'             | '(R0402-0201)'                 | '510'     | '5%'    | '1/16W'  | 'DISCRETE' | 'RES CHIP 510 1/16W +-5%(0402)'                    | 'CHIP0402'     | ''          | ''            | '20100930'
 '510'        | '5%'      | '1/16W'  | '0402LF'  | 'EMPTY'  | 'CS15102JB00'(!)        = 'End of Design' | 'Comp-Approve'     | 'CS15102JB00'           | 'R0402'             | '(R0402-0201)'                 | '510'     | '5%'    | '1/16W'  | 'IO'       | 'RES CHIP 510 1/16W +-5%(0402)'                    | 'CHIP0402'     | ''          | ''            | '20100930'
 '1.27K'      | '1%'      | '1/16W'  | '0402LF'  | 'CHIP'   | 'CS21272FB15'(!)        = 'End of Design' | 'Comp-Approve'     | 'CS21272FB15'           | 'R0402'             | '(R0402-0201)'                 | '1.27K'   | '1%'    | '1/16W'  | 'DISCRETE' | 'RES CHIP 1.27K 1/16W +-1% (0402)'                 | 'CHIP0402'     | ''          | ''            | '20100930'
 '1.27K'      | '1%'      | '1/16W'  | '0402LF'  | 'EMPTY'  | 'CS21272FB15'(!)        = 'End of Design' | 'Comp-Approve'     | 'CS21272FB15'           | 'R0402'             | '(R0402-0201)'                 | '1.27K'   | '1%'    | '1/16W'  | 'IO'       | 'RES CHIP 1.27K 1/16W +-1% (0402)'                 | 'CHIP0402'     | ''          | ''            | '20100930'
 '2.2'        | '1%'      | '1/8W'   | '0805LF'  | 'CHIP'   | 'CS-2204FA00'(!)        = 'End of Design' | 'Comp-Approve'     | 'CS-2204FA00'           | 'R0805'             | '(SMR0805AW)'                  | '2.2'     | '1%'    | '1/8W'   | 'DISCRETE' | 'RES CHIP 2.2 1/8W +-1%(0805)'                     | 'CHIP0805'     | ''          | ''            | '20100930'
 '2.2'        | '1%'      | '1/8W'   | '0805LF'  | 'EMPTY'  | 'CS-2204FA00'(!)        = 'End of Design' | 'Comp-Approve'     | 'CS-2204FA00'           | 'R0805'             | '(SMR0805AW)'                  | '2.2'     | '1%'    | '1/8W'   | 'IO'       | 'RES CHIP 2.2 1/8W +-1%(0805)'                     | 'CHIP0805'     | ''          | ''            | '20100930'
 '3.01K'      | '1%'      | '1/16W'  | '0402LF'  | 'CHIP'   | 'CS23012FB16'(!)        = 'End of Design' | 'Comp-Approve'     | 'CS23012FB16'           | 'R0402'             | '(R0402-0201)'                 | '3.01K'   | '1%'    | '1/16W'  | 'DISCRETE' | 'RES CHIP 3.01K 1/16W +-1%(0402)'                  | 'CHIP0402'     | ''          | ''            | '20100930'
 '3.01K'      | '1%'      | '1/16W'  | '0402LF'  | 'EMPTY'  | 'CS23012FB16'(!)        = 'End of Design' | 'Comp-Approve'     | 'CS23012FB16'           | 'R0402'             | '(R0402-0201)'                 | '3.01K'   | '1%'    | '1/16W'  | 'IO'       | 'RES CHIP 3.01K 1/16W +-1%(0402)'                  | 'CHIP0402'     | ''          | ''            | '20100930'
 '3.65K'      | '1%'      | '1/16W'  | '0402LF'  | 'CHIP'   | 'CS23652FB08'(!)        = 'End of Design' | 'Comp-Approve'     | 'CS23652FB08'           | 'R0402'             | '(R0402-0201)'                 | '3.65K'   | '1%'    | '1/16W'  | 'DISCRETE' | 'RES CHIP 3.65K 1/16W +-1%(0402)'                  | 'CHIP0402'     | ''          | ''            | '20100930'
 '3.65K'      | '1%'      | '1/16W'  | '0402LF'  | 'EMPTY'  | 'CS23652FB08'(!)        = 'End of Design' | 'Comp-Approve'     | 'CS23652FB08'           | 'R0402'             | '(R0402-0201)'                 | '3.65K'   | '1%'    | '1/16W'  | 'IO'       | 'RES CHIP 3.65K 1/16W +-1%(0402)'                  | 'CHIP0402'     | ''          | ''            | '20100930'
 '4.75K'      | '1%'      | '1/16W'  | '0402LF'  | 'CHIP'   | 'CS24752FB12'(!)        = 'End of Design' | 'Comp-Approve'     | 'CS24752FB12'           | 'R0402'             | '(R0402-0201)'                 | '4.75K'   | '1%'    | '1/16W'  | 'DISCRETE' | 'RES CHIP 4.75K 1/16W +-1%(0402)'                  | 'CHIP0402'     | ''          | ''            | '20100930'
 '4.75K'      | '1%'      | '1/16W'  | '0402LF'  | 'EMPTY'  | 'CS24752FB12'(!)        = 'End of Design' | 'Comp-Approve'     | 'CS24752FB12'           | 'R0402'             | '(R0402-0201)'                 | '4.75K'   | '1%'    | '1/16W'  | 'IO'       | 'RES CHIP 4.75K 1/16W +-1%(0402)'                  | 'CHIP0402'     | ''          | ''            | '20100930'
 '30K'        | '1%'      | '1/16W'  | '0402LF'  | 'CHIP'   | 'CS33002FB13'(!)        = 'End of Design' | 'Comp-Approve'     | 'CS33002FB13'           | 'R0402'             | '(R0402-0201)'                 | '30K'     | '1%'    | '1/16W'  | 'DISCRETE' | 'RES CHIP 30K 1/16W +-1%(0402)'                    | 'CHIP0402'     | ''          | ''            | '20100930'
 '30K'        | '1%'      | '1/16W'  | '0402LF'  | 'EMPTY'  | 'CS33002FB13'(!)        = 'End of Design' | 'Comp-Approve'     | 'CS33002FB13'           | 'R0402'             | '(R0402-0201)'                 | '30K'     | '1%'    | '1/16W'  | 'IO'       | 'RES CHIP 30K 1/16W +-1%(0402)'                    | 'CHIP0402'     | ''          | ''            | '20100930'
 '33K'        | '1%'      | '1/10W'  | '0603LF'  | 'CHIP'   | 'CS33303F911'(!)        = 'End of Design' | 'Comp-Approve'     | 'CS33303F911'           | 'R0603'             | '(SMR0603AW)'                  | '33K'     | '1%'    | '1/10W'  | 'DISCRETE' | 'RES CHIP 33K 1/10W +-1%(0603)'                    | 'CHIP0603'     | ''          | ''            | '20100930'
 '33K'        | '1%'      | '1/10W'  | '0603LF'  | 'EMPTY'  | 'CS33303F911'(!)        = 'End of Design' | 'Comp-Approve'     | 'CS33303F911'           | 'R0603'             | '(SMR0603AW)'                  | '33K'     | '1%'    | '1/10W'  | 'IO'       | 'RES CHIP 33K 1/10W +-1%(0603)'                    | 'CHIP0603'     | ''          | ''            | '20100930'
 '36K'        | '1%'      | '1/16W'  | '0402LF'  | 'CHIP'   | 'CS33602FB15'(!)        = 'End of Design' | 'Comp-Approve'     | 'CS33602FB15'           | 'R0402'             | '(R0402-0201)'                 | '36K'     | '1%'    | '1/16W'  | 'DISCRETE' | 'RES CHIP 36K 1/16W +-1%(0402)'                    | 'CHIP0402'     | ''          | ''            | '20100930'
 '36K'        | '1%'      | '1/16W'  | '0402LF'  | 'EMPTY'  | 'CS33602FB15'(!)        = 'End of Design' | 'Comp-Approve'     | 'CS33602FB15'           | 'R0402'             | '(R0402-0201)'                 | '36K'     | '1%'    | '1/16W'  | 'IO'       | 'RES CHIP 36K 1/16W +-1%(0402)'                    | 'CHIP0402'     | ''          | ''            | '20100930'
 '130K'       | '1%'      | '1/16W'  | '0402LF'  | 'CHIP'   | 'CS41302FB00'(!)        = 'End of Design' | 'Comp-Approve'     | 'CS41302FB00'           | 'R0402'             | '(R0402-0201)'                 | '130K'    | '1%'    | '1/16W'  | 'DISCRETE' | 'RES CHIP 130K 1/16W +-1%(0402)'                   | 'CHIP0402'     | ''          | ''            | '20100930'
 '130K'       | '1%'      | '1/16W'  | '0402LF'  | 'EMPTY'  | 'CS41302FB00'(!)        = 'End of Design' | 'Comp-Approve'     | 'CS41302FB00'           | 'R0402'             | '(R0402-0201)'                 | '130K'    | '1%'    | '1/16W'  | 'IO'       | 'RES CHIP 130K 1/16W +-1%(0402)'                   | 'CHIP0402'     | ''          | ''            | '20100930'
 '330K'       | '5%'      | '1/16W'  | '0402LF'  | 'CHIP'   | 'CS43302JB18'(!)        = 'End of Design' | 'Comp-Approve'     | 'CS43302JB18'           | 'R0402'             | '(R0402-0201)'                 | '330K'    | '5%'    | '1/16W'  | 'DISCRETE' | 'RES CHIP 330K 1/16W +-5% (0402)'                  | 'CHIP0402'     | ''          | ''            | '20100930'
 '330K'       | '5%'      | '1/16W'  | '0402LF'  | 'EMPTY'  | 'CS43302JB18'(!)        = 'End of Design' | 'Comp-Approve'     | 'CS43302JB18'           | 'R0402'             | '(R0402-0201)'                 | '330K'    | '5%'    | '1/16W'  | 'IO'       | 'RES CHIP 330K 1/16W +-5% (0402)'                  | 'CHIP0402'     | ''          | ''            | '20100930'
 '10M'        | '5%'      | '1/10W'  | '0603LF'  | 'CHIP'   | 'CS61003J946'(!)        = ''              | ''                 | 'CS61003J946'           | 'R0603'             | '(SMR0603AW)'                  | '10M'     | '5%'    | '1/10W'  | 'DISCRETE' | 'RES CHIP 10M 1/10W +-5%(0603)EP'                  | 'CHIP0603'     | ''          | ''            | '20100930'
 '10M'        | '5%'      | '1/10W'  | '0603LF'  | 'EMPTY'  | 'CS61003J946'(!)        = ''              | ''                 | 'CS61003J946'           | 'R0603'             | '(SMR0603AW)'                  | '10M'     | '5%'    | '1/10W'  | 'IO'       | 'RES CHIP 10M 1/10W +-5%(0603)EP'                  | 'CHIP0603'     | ''          | ''            | '20100930'
 '499K'       | '1%'      | '1/16W'  | '0402LF'  | 'CHIP'   | 'CS44992FB11'(!)        = 'End of Design' | 'Comp-Approve'     | 'CS44992FB11'           | 'R0402'             | '(R0402-0201)'                 | '499K'    | '1%'    | '1/16W'  | 'DISCRETE' | 'RES CHIP 499K 1/16W +-1% (0402)'                  | 'CHIP0603'     | ''          | ''            | '20101005'
 '499K'       | '1%'      | '1/16W'  | '0402LF'  | 'EMPTY'  | 'CS44992FB11'(!)        = 'End of Design' | 'Comp-Approve'     | 'CS44992FB11'           | 'R0402'             | '(R0402-0201)'                 | '499K'    | '1%'    | '1/16W'  | 'IO'       | 'RES CHIP 499K 1/16W +-1% (0402)'                  | 'CHIP0603'     | ''          | ''            | '20101005'
 '42.2'       | '1%'      | '1/10W'  | '0603LF'  | 'CHIP'   | 'CS04223F900'(!)        = ''              | ''                 | 'CS04223F900'           | 'R0603'             | '(SMR0603AW)'                  | '42.2'    | '1%'    | '1/10W'  | 'DISCRETE' | 'RES CHIP 42.2 1/10W +-1%(0603)'                   | 'CHIP0603'     | ''          | ''            | '20101006'
 '42.2'       | '1%'      | '1/10W'  | '0603LF'  | 'EMPTY'  | 'CS04223F900'(!)        = ''              | ''                 | 'CS04223F900'           | 'R0603'             | '(SMR0603AW)'                  | '42.2'    | '1%'    | '1/10W'  | 'IO'       | 'RES CHIP 42.2 1/10W +-1%(0603)'                   | 'CHIP0603'     | ''          | ''            | '20101006'
 '402'        | '1%'      | '1/16W'  | '0402LF'  | 'CHIP'   | 'CS14022FB11'(!)        = 'End of Design' | 'Comp-Approve'     | 'CS14022FB11'           | 'R0402'             | '(R0402-0201)'                 | '402'     | '1%'    | '1/16W'  | 'DISCRETE' | 'RES CHIP 402 1/16W +-1%( 0402)'                   | 'CHIP0402'     | ''          | ''            | '20101006'
 '402'        | '1%'      | '1/16W'  | '0402LF'  | 'EMPTY'  | 'CS14022FB11'(!)        = 'End of Design' | 'Comp-Approve'     | 'CS14022FB11'           | 'R0402'             | '(R0402-0201)'                 | '402'     | '1%'    | '1/16W'  | 'IO'       | 'RES CHIP 402 1/16W +-1%( 0402)'                   | 'CHIP0402'     | ''          | ''            | '20101006'
 '976'        | '1%'      | '1/16W'  | '0402LF'  | 'CHIP'   | 'CS19762FB19'(!)        = 'End of Design' | 'Comp-Approve'     | 'CS19762FB19'           | 'R0402'             | '(R0402-0201)'                 | '976'     | '1%'    | '1/16W'  | 'DISCRETE' | 'RES CHIP 976 1/16W +-1%(0402)'                    | 'CHIP0402'     | ''          | ''            | '20101006'
 '976'        | '1%'      | '1/16W'  | '0402LF'  | 'EMPTY'  | 'CS19762FB19'(!)        = 'End of Design' | 'Comp-Approve'     | 'CS19762FB19'           | 'R0402'             | '(R0402-0201)'                 | '976'     | '1%'    | '1/16W'  | 'IO'       | 'RES CHIP 976 1/16W +-1%(0402)'                    | 'CHIP0402'     | ''          | ''            | '20101006'
 '1.07K'      | '1%'      | '1/16W'  | '0402LF'  | 'CHIP'   | 'CS21072FB18'(!)        = 'End of Design' | 'Comp-Approve'     | 'CS21072FB18'           | 'R0402'             | '(R0402-0201)'                 | '1.07K'   | '1%'    | '1/16W'  | 'DISCRETE' | 'RES CHIP 1.07K 1/16W,+-1%(0402)'                  | 'CHIP0402'     | ''          | ''            | '20101006'
 '1.07K'      | '1%'      | '1/16W'  | '0402LF'  | 'EMPTY'  | 'CS21072FB18'(!)        = 'End of Design' | 'Comp-Approve'     | 'CS21072FB18'           | 'R0402'             | '(R0402-0201)'                 | '1.07K'   | '1%'    | '1/16W'  | 'IO'       | 'RES CHIP 1.07K 1/16W,+-1%(0402)'                  | 'CHIP0402'     | ''          | ''            | '20101006'
 '220K'       | '5%'      | '1/10W'  | '0603LF'  | 'CHIP'   | 'CS42203J918'(!)        = ''              | ''                 | 'CS42203J918'           | 'R0603'             | '(SMR0603AW)'                  | '220K'    | '5%'    | '1/10W'  | 'DISCRETE' | 'RESISTOR CHIP 220K 1/10W +-5%(1608)'              | 'CHIP0603'     | ''          | ''            | '20101006'
 '220K'       | '5%'      | '1/10W'  | '0603LF'  | 'EMPTY'  | 'CS42203J918'(!)        = ''              | ''                 | 'CS42203J918'           | 'R0603'             | '(SMR0603AW)'                  | '220K'    | '5%'    | '1/10W'  | 'IO'       | 'RESISTOR CHIP 220K 1/10W +-5%(1608)'              | 'CHIP0603'     | ''          | ''            | '20101006'
 '330K'       | '1%'      | '1/10W'  | '0603LF'  | 'CHIP'   | 'CS43303F912'(!)        = 'End of Design' | 'Comp-Approve'     | 'CS43303F912'           | 'R0603'             | '(SMR0603AW)'                  | '330K'    | '1%'    | '1/10W'  | 'DISCRETE' | 'RES CHIP 330K 1/10W +-1%(0603)'                   | 'CHIP0603'     | ''          | ''            | '20101006'
 '330K'       | '1%'      | '1/10W'  | '0603LF'  | 'EMPTY'  | 'CS43303F912'(!)        = 'End of Design' | 'Comp-Approve'     | 'CS43303F912'           | 'R0603'             | '(SMR0603AW)'                  | '330K'    | '1%'    | '1/10W'  | 'IO'       | 'RES CHIP 330K 1/10W +-1%(0603)'                   | 'CHIP0603'     | ''          | ''            | '20101006'
 '2.2'        | '5%'      | '1/10W'  | '0603LF'  | 'CHIP'   | 'CS-2203J913'(!)        = ''              | ''                 | 'CS-2203J913'           | 'R0603'             | '(SMR0603AW)'                  | '2.2'     | '5%'    | '1/10W'  | 'DISCRETE' | 'RESISTER CHIP 2.2 1/10W+-5%(0603)'                | 'CHIP0603'     | ''          | ''            | '20101006'
 '2.2'        | '5%'      | '1/10W'  | '0603LF'  | 'EMPTY'  | 'CS-2203J913'(!)        = ''              | ''                 | 'CS-2203J913'           | 'R0603'             | '(SMR0603AW)'                  | '2.2'     | '5%'    | '1/10W'  | 'IO'       | 'RESISTER CHIP 2.2 1/10W+-5%(0603)'                | 'CHIP0603'     | ''          | ''            | '20101006'
 '150'        | '1%'      | '1/10W'  | '0603LF'  | 'CHIP'   | 'CS11503F943'(!)        = ''              | ''                 | 'CS11503F943'           | 'R0603'             | '(SMR0603AW)'                  | '150'     | '1%'    | '1/10W'  | 'DISCRETE' | 'RESISTOR CHIP 150,1/10W,+-1%(0603)'               | 'CHIP0603'     | ''          | ''            | '20101008'
 '150'        | '1%'      | '1/10W'  | '0603LF'  | 'EMPTY'  | 'CS11503F943'(!)        = ''              | ''                 | 'CS11503F943'           | 'R0603'             | '(SMR0603AW)'                  | '150'     | '1%'    | '1/10W'  | 'IO'       | 'RESISTOR CHIP 150,1/10W,+-1%(0603)'               | 'CHIP0603'     | ''          | ''            | '20101008'
 '75'         | '1%'      | '1/10W'  | '0603LF'  | 'CHIP'   | 'CS07503F930'(!)        = 'End of Design' | 'Comp-Approve'     | 'CS07503F930'           | 'R0603'             | '(SMR0603AW)'                  | '75'      | '1%'    | '1/10W'  | 'DISCRETE' | 'RESISTOR CHIP 75 1/10W +-1%(1608)'                | 'CHIP0603'     | ''          | ''            | '20101008'
 '75'         | '1%'      | '1/10W'  | '0603LF'  | 'EMPTY'  | 'CS07503F930'(!)        = 'End of Design' | 'Comp-Approve'     | 'CS07503F930'           | 'R0603'             | '(SMR0603AW)'                  | '75'      | '1%'    | '1/10W'  | 'IO'       | 'RESISTOR CHIP 75 1/10W +-1%(1608)'                | 'CHIP0603'     | ''          | ''            | '20101008'
 '22.6'       | '1%'      | '1/16W'  | '0402LF'  | 'CHIP'   | 'CS02262FB10'(!)        = 'End of Design' | 'Comp-Approve'     | 'CS02262FB10'           | 'R0402'             | '(R0402-0201)'                 | '22.6'    | '1%'    | '1/16W'  | 'DISCRETE' | 'RES CHIP 22.6 1/16W +-1%(0402)'                   | 'CHIP0402'     | ''          | ''            | '20101008'
 '22.6'       | '1%'      | '1/16W'  | '0402LF'  | 'EMPTY'  | 'CS02262FB10'(!)        = 'End of Design' | 'Comp-Approve'     | 'CS02262FB10'           | 'R0402'             | '(R0402-0201)'                 | '22.6'    | '1%'    | '1/16W'  | 'IO'       | 'RES CHIP 22.6 1/16W +-1%(0402)'                   | 'CHIP0402'     | ''          | ''            | '20101008'
 '2'          | '5%'      | '1/10W'  | '0603LF'  | 'CHIP'   | 'CS-2003J932'(!)        = 'End of Design' | 'Comp-Approve'     | 'CS-2003J932'           | 'R0603'             | '(SMR0603AW)'                  | '2'       | '5%'    | '1/10W'  | 'DISCRETE' | 'RESISTOR CHIP 2 1/10W+-5%(0603)EP'                | 'CHIP0603'     | ''          | ''            | '20101008'
 '2'          | '5%'      | '1/10W'  | '0603LF'  | 'EMPTY'  | 'CS-2003J932'(!)        = 'End of Design' | 'Comp-Approve'     | 'CS-2003J932'           | 'R0603'             | '(SMR0603AW)'                  | '2'       | '5%'    | '1/10W'  | 'IO'       | 'RESISTOR CHIP 2 1/10W+-5%(0603)EP'                | 'CHIP0603'     | ''          | ''            | '20101008'
 '1.24K'      | '1%'      | '1/16W'  | '0402LF'  | 'CHIP'   | 'CS21242FB20'(!)        = 'End of Design' | 'Comp-Approve'     | 'CS21242FB20'           | 'R0402'             | '(R0402-0201)'                 | '1.24K'   | '1%'    | '1/16W'  | 'DISCRETE' | 'RES CHIP 1.24K 1/16W +-1%(0402)'                  | 'CHIP0402'     | ''          | ''            | '20101008'
 '1.24K'      | '1%'      | '1/16W'  | '0402LF'  | 'EMPTY'  | 'CS21242FB20'(!)        = 'End of Design' | 'Comp-Approve'     | 'CS21242FB20'           | 'R0402'             | '(R0402-0201)'                 | '1.24K'   | '1%'    | '1/16W'  | 'IO'       | 'RES CHIP 1.24K 1/16W +-1%(0402)'                  | 'CHIP0402'     | ''          | ''            | '20101008'
 '10M'        | '5%'      | '1/16W'  | '0402LF'  | 'CHIP'   | 'CS61002JB23'(!)        = 'End of Design' | 'Comp-Approve'     | 'CS61002JB23'           | 'R0402'             | '(R0402-0201)'                 | '10M'     | '5%'    | '1/16W'  | 'DISCRETE' | 'RES CHIP 10M 1/16W +-5% (0402)'                   | 'CHIP0402'     | ''          | ''            | '20101013'
 '10M'        | '5%'      | '1/16W'  | '0402LF'  | 'EMPTY'  | 'CS61002JB23'(!)        = 'End of Design' | 'Comp-Approve'     | 'CS61002JB23'           | 'R0402'             | '(R0402-0201)'                 | '10M'     | '5%'    | '1/16W'  | 'IO'       | 'RES CHIP 10M 1/16W +-5% (0402)'                   | 'CHIP0402'     | ''          | ''            | '20101013'
 '806'        | '1%'      | '1/16W'  | '0402LF'  | 'CHIP'   | 'CS18062FB29'(!)        = 'End of Design' | 'Comp-Approve'     | 'CS18062FB29'           | 'R0402'             | '(R0402-0201)'                 | '806'     | '1%'    | '1/16W'  | 'DISCRETE' | 'RES CHIP 806 1/16W +-1%(0402)'                    | 'CHIP0402'     | ''          | ''            | '20101015'
 '806'        | '1%'      | '1/16W'  | '0402LF'  | 'EMPTY'  | 'CS18062FB29'(!)        = 'End of Design' | 'Comp-Approve'     | 'CS18062FB29'           | 'R0402'             | '(R0402-0201)'                 | '806'     | '1%'    | '1/16W'  | 'IO'       | 'RES CHIP 806 1/16W +-1%(0402)'                    | 'CHIP0402'     | ''          | ''            | '20101015'
 '43'         | '5%'      | '1/16W'  | '0402LF'  | 'CHIP'   | 'CS04302JB13'(!)        = 'End of Design' | 'Comp-Approve'     | 'CS04302JB13'           | 'R0402'             | '(R0402-0201)'                 | '43'      | '5%'    | '1/16W'  | 'DISCRETE' | 'RES CHIP 43 1/16W +-5%( 0402 )'                   | 'CHIP0402'     | ''          | ''            | '20101018'
 '43'         | '5%'      | '1/16W'  | '0402LF'  | 'EMPTY'  | 'CS04302JB13'(!)        = 'End of Design' | 'Comp-Approve'     | 'CS04302JB13'           | 'R0402'             | '(R0402-0201)'                 | '43'      | '5%'    | '1/16W'  | 'IO'       | 'RES CHIP 43 1/16W +-5%( 0402 )'                   | 'CHIP0402'     | ''          | ''            | '20101018'
 '0.4'        | '1%'      | '1/10W'  | '0603LF'  | 'CHIP'   | 'CS+4003F900'(!)        = ''              | ''                 | 'CS+4003F900'           | 'R0603'             | '(SMR0603AW)'                  | '0.4'     | '1%'    | '1/10W'  | 'DISCRETE' | 'RESISTOR CHIP 0.4 1/10W +-1%(0603)'               | 'CHIP0603'     | ''          | ''            | '20101018'
 '0.4'        | '1%'      | '1/10W'  | '0603LF'  | 'EMPTY'  | 'CS+4003F900'(!)        = ''              | ''                 | 'CS+4003F900'           | 'R0603'             | '(SMR0603AW)'                  | '0.4'     | '1%'    | '1/10W'  | 'IO'       | 'RESISTOR CHIP 0.4 1/10W +-1%(0603)'               | 'CHIP0603'     | ''          | ''            | '20101018'
 '2.32K'      | '1%'      | '1/16W'  | '0402LF'  | 'CHIP'   | 'CS22322FB01'(!)        = 'End of Design' | 'Comp-Approve'     | 'CS22322FB01'           | 'R0402'             | '(R0402-0201)'                 | '2.32K'   | '1%'    | '1/16W'  | 'DISCRETE' | 'RESISTOR CHIP 2.32K 1/16W +-1%(0402)'             | 'CHIP0402'     | ''          | ''            | '20101028'
 '2.32K'      | '1%'      | '1/16W'  | '0402LF'  | 'EMPTY'  | 'CS22322FB01'(!)        = 'End of Design' | 'Comp-Approve'     | 'CS22322FB01'           | 'R0402'             | '(R0402-0201)'                 | '2.32K'   | '1%'    | '1/16W'  | 'IO'       | 'RESISTOR CHIP 2.32K 1/16W +-1%(0402)'             | 'CHIP0402'     | ''          | ''            | '20101028'
 '36.5K'      | '1%'      | '1/16W'  | '0402LF'  | 'CHIP'   | 'CS33652FB18'(!)        = 'End of Design' | 'Comp-Approve'     | 'CS33652FB18'           | 'R0402'             | '(R0402-0201)'                 | '36.5K'   | '1%'    | '1/16W'  | 'DISCRETE' | 'RES CHIP 36.5K 1/16W +-1%(0402)'                  | 'CHIP0402'     | ''          | ''            | '20101028'
 '36.5K'      | '1%'      | '1/16W'  | '0402LF'  | 'EMPTY'  | 'CS33652FB18'(!)        = 'End of Design' | 'Comp-Approve'     | 'CS33652FB18'           | 'R0402'             | '(R0402-0201)'                 | '36.5K'   | '1%'    | '1/16W'  | 'IO'       | 'RES CHIP 36.5K 1/16W +-1%(0402)'                  | 'CHIP0402'     | ''          | ''            | '20101028'
 '1.8'        | '1%'      | '1/10W'  | '0603LF'  | 'CHIP'   | 'CS-1803F900'(!)        = 'End of Design' | 'P/N Release'      | 'CS-1803F900'           | 'R0603'             | '(SMR0603AW)'                  | '1.8'     | '1%'    | '1/10W'  | 'DISCRETE' | 'RES CHIP 1.8 1/10W +-1%(0603)'                    | 'CHIP0603'     | ''          | ''            | '20101101'
 '1.8'        | '1%'      | '1/10W'  | '0603LF'  | 'EMPTY'  | 'CS-1803F900'(!)        = 'End of Design' | 'P/N Release'      | 'CS-1803F900'           | 'R0603'             | '(SMR0603AW)'                  | '1.8'     | '1%'    | '1/10W'  | 'IO'       | 'RES CHIP 1.8 1/10W +-1%(0603)'                    | 'CHIP0603'     | ''          | ''            | '20101101'
 '1.8'        | '5%'      | '1/10W'  | '0603LF'  | 'CHIP'   | 'CS-1803J900'(!)        = 'End of Design' | 'Comp-Approve'     | 'CS-1803J900'           | 'R0603'             | '(SMR0603AW)'                  | '1.8'     | '5%'    | '1/10W'  | 'DISCRETE' | 'RES CHIP 1.8 1/10W +-5%(0603)'                    | 'CHIP0603'     | ''          | ''            | '20101101'
 '1.8'        | '5%'      | '1/10W'  | '0603LF'  | 'EMPTY'  | 'CS-1803J900'(!)        = 'End of Design' | 'Comp-Approve'     | 'CS-1803J900'           | 'R0603'             | '(SMR0603AW)'                  | '1.8'     | '5%'    | '1/10W'  | 'IO'       | 'RES CHIP 1.8 1/10W +-5%(0603)'                    | 'CHIP0603'     | ''          | ''            | '20101101'
 '0.0005'     | '1%'      | '3W'     | '2512LF'  | 'CHIP'   | 'CS0000DFR00'(!)        = ''              | ''                 | 'CS0000DFR00'           | 'R2512A'            | '(SMR2512AW)'                  | '0.0005'  | '1%'    | '3W'     | 'DISCRETE' | 'RES CHIP 0.0005 3W +-1%(2512)'                    | 'CHIP2512'     | ''          | ''            | '20101105'
 '0.0005'     | '1%'      | '3W'     | '2512LF'  | 'EMPTY'  | 'CS0000DFR00'(!)        = ''              | ''                 | 'CS0000DFR00'           | 'R2512A'            | '(SMR2512AW)'                  | '0.0005'  | '1%'    | '3W'     | 'IO'       | 'RES CHIP 0.0005 3W +-1%(2512)'                    | 'CHIP2512'     | ''          | ''            | '20101105'
 '14.7K'      | '1%'      | '1/16W'  | '0402LF'  | 'CHIP'   | 'CS31472FB14'(!)        = 'End of Design' | 'Comp-Approve'     | 'CS31472FB14'           | 'R0402'             | '(R0402-0201)'                 | '14.7K'   | '1%'    | '1/16W'  | 'DISCRETE' | 'RES CHIP 14.7K 1/16W +-1% (0402)'                 | 'CHIP0402'     | ''          | ''            | '20101213'
 '14.7K'      | '1%'      | '1/16W'  | '0402LF'  | 'EMPTY'  | 'CS31472FB14'(!)        = 'End of Design' | 'Comp-Approve'     | 'CS31472FB14'           | 'R0402'             | '(R0402-0201)'                 | '14.7K'   | '1%'    | '1/16W'  | 'IO'       | 'RES CHIP 14.7K 1/16W +-1% (0402)'                 | 'CHIP0402'     | ''          | ''            | '20101213'
 '64.9K'      | '1%'      | '1/16W'  | '0402LF'  | 'CHIP'   | 'CS36492FB17'(!)        = 'End of Design' | 'Comp-Approve'     | 'CS36492FB17'           | 'R0402'             | '(R0402-0201)'                 | '64.9K'   | '1%'    | '1/16W'  | 'DISCRETE' | 'RES CHIP 64.9K 1/16W +-1%(0402)'                  | 'CHIP0402'     | ''          | ''            | '20101221'
 '64.9K'      | '1%'      | '1/16W'  | '0402LF'  | 'EMPTY'  | 'CS36492FB17'(!)        = 'End of Design' | 'Comp-Approve'     | 'CS36492FB17'           | 'R0402'             | '(R0402-0201)'                 | '64.9K'   | '1%'    | '1/16W'  | 'IO'       | 'RES CHIP 64.9K 1/16W +-1%(0402)'                  | 'CHIP0402'     | ''          | ''            | '20101221'
 '7.5K'       | '1%'      | '1/10W'  | '0603LF'  | 'CHIP'   | 'CS27503F917'(!)        = 'End of Design' | 'Comp-Approve'     | 'CS27503F917'           | 'R0603'             | '(SMR0603AW)'                  | '7.5K'    | '1%'    | '1/10W'  | 'DISCRETE' | 'RES CHIP 7.5K 1/10W +-1%(0603)'                   | 'CHIP0603'     | ''          | ''            | '20101221'
 '7.5K'       | '1%'      | '1/10W'  | '0603LF'  | 'EMPTY'  | 'CS27503F917'(!)        = 'End of Design' | 'Comp-Approve'     | 'CS27503F917'           | 'R0603'             | '(SMR0603AW)'                  | '7.5K'    | '1%'    | '1/10W'  | 'IO'       | 'RES CHIP 7.5K 1/10W +-1%(0603)'                   | 'CHIP0603'     | ''          | ''            | '20101221'
 '499'        | '1%'      | '1/10W'  | '0603LF'  | 'CHIP'   | 'CS14993F939'(!)        = ''              | ''                 | 'CS14993F939'           | 'R0603'             | '(SMR0603AW)'                  | '499'     | '1%'    | '1/10W'  | 'DISCRETE' | 'RESISTOR CHIP 499 1/10W +-1%(0603)'               | 'CHIP0603'     | ''          | ''            | '20101221'
 '499'        | '1%'      | '1/10W'  | '0603LF'  | 'EMPTY'  | 'CS14993F939'(!)        = ''              | ''                 | 'CS14993F939'           | 'R0603'             | '(SMR0603AW)'                  | '499'     | '1%'    | '1/10W'  | 'IO'       | 'RESISTOR CHIP 499 1/10W +-1%(0603)'               | 'CHIP0603'     | ''          | ''            | '20101221'
 '150K'       | '1%'      | '1/10W'  | '0603LF'  | 'CHIP'   | 'CS41503F906'(!)        = ''              | ''                 | 'CS41503F906'           | 'R0603'             | '(SMR0603AW)'                  | '150K'    | '1%'    | '1/10W'  | 'DISCRETE' | 'RES CHIP 150K 1/10W +-1%(0603)'                   | 'CHIP0603'     | ''          | ''            | '20110106'
 '150K'       | '1%'      | '1/10W'  | '0603LF'  | 'EMPTY'  | 'CS41503F906'(!)        = ''              | ''                 | 'CS41503F906'           | 'R0603'             | '(SMR0603AW)'                  | '150K'    | '1%'    | '1/10W'  | 'IO'       | 'RES CHIP 150K 1/10W +-1%(0603)'                   | 'CHIP0603'     | ''          | ''            | '20110106'
 '499'        | '1%'      | '1/10W'  | '0603LF'  | 'CHIP'   | 'CS41503F914'(!)        = 'End of Design' | 'Comp-Approve'     | 'CS41503F914'           | 'R0603'             | '(SMR0603AW)'                  | '499'     | '1%'    | '1/10W'  | 'DISCRETE' | 'RES CHIP 150K 1/10W +-1%(0603)'                   | 'CHIP0603'     | ''          | ''            | '20110106'
 '499'        | '1%'      | '1/10W'  | '0603LF'  | 'EMPTY'  | 'CS41503F914'(!)        = 'End of Design' | 'Comp-Approve'     | 'CS41503F914'           | 'R0603'             | '(SMR0603AW)'                  | '499'     | '1%'    | '1/10W'  | 'IO'       | 'RES CHIP 150K 1/10W +-1%(0603)'                   | 'CHIP0603'     | ''          | ''            | '20110106'
 '0.004'      | '1%'      | '1W'     | '2512LF'  | 'CHIP'   | 'CS+0048FR00'(!)        = ''              | ''                 | 'CS+0048FR00'           | 'R2512A'            | '(SMR2512AW)'                  | '0.004'   | '1%'    | '1W'     | 'DISCRETE' | 'RES CHIP 0.004 1W +-1%(2512)'                     | 'CHIP2512'     | ''          | ''            | '20110106'
 '0.004'      | '1%'      | '1W'     | '2512LF'  | 'EMPTY'  | 'CS+0048FR00'(!)        = ''              | ''                 | 'CS+0048FR00'           | 'R2512A'            | '(SMR2512AW)'                  | '0.004'   | '1%'    | '1W'     | 'IO'       | 'RES CHIP 0.004 1W +-1%(2512)'                     | 'CHIP2512'     | ''          | ''            | '20110106'
 '0'          | '1%'      | '1/2W'   | '1206LF'  | 'CHIP'   | 'CS00007F209'(!)        = 'End of Design' | 'Comp-Approve'     | 'CS00007F209'           | 'R1206'             | '(SMR1206AW)'                  | '0'       | '1%'    | '1/2W'   | 'DISCRETE' | 'RESISTOR CHIP 0 1/2W 1%(1206)'                    | 'CHIP1206'     | ''          | ''            | '20110113'
 '0'          | '1%'      | '1/2W'   | '1206LF'  | 'EMPTY'  | 'CS00007F209'(!)        = 'End of Design' | 'Comp-Approve'     | 'CS00007F209'           | 'R1206'             | '(SMR1206AW)'                  | '0'       | '1%'    | '1/2W'   | 'IO'       | 'RESISTOR CHIP 0 1/2W 1%(1206)'                    | 'CHIP1206'     | ''          | ''            | '20110113'
 '75'         | '1%'      | '1/8W'   | '0805LF'  | 'CHIP'   | 'CS07504FA11'(!)        = ''              | ''                 | 'CS07504FA11'           | 'R0805'             | '(SMR0805AW)'                  | '75'      | '1%'    | '1/8W'   | 'DISCRETE' | 'RES CHIP 75 1/8W +-1%(0805)'                      | 'CHIP0805'     | ''          | ''            | '20110113'
 '75'         | '1%'      | '1/8W'   | '0805LF'  | 'EMPTY'  | 'CS07504FA11'(!)        = ''              | ''                 | 'CS07504FA11'           | 'R0805'             | '(SMR0805AW)'                  | '75'      | '1%'    | '1/8W'   | 'IO'       | 'RES CHIP 75 1/8W +-1%(0805)'                      | 'CHIP0805'     | ''          | ''            | '20110113'
 '118'        | '1%'      | '1/16W'  | '0402LF'  | 'CHIP'   | 'CS11182FB00'(!)        = 'End of Design' | 'Comp-Approve'     | 'CS11182FB00'           | 'R0402'             | '(R0402-0201)'                 | '118'     | '1%'    | '1/16W'  | 'DISCRETE' | 'RES CHIP 118 1/16W +-1%(0402)'                    | 'CHIP0402'     | ''          | ''            | '20110113'
 '118'        | '1%'      | '1/16W'  | '0402LF'  | 'EMPTY'  | 'CS11182FB00'(!)        = 'End of Design' | 'Comp-Approve'     | 'CS11182FB00'           | 'R0402'             | '(R0402-0201)'                 | '118'     | '1%'    | '1/16W'  | 'IO'       | 'RES CHIP 118 1/16W +-1%(0402)'                    | 'CHIP0402'     | ''          | ''            | '20110113'
 '140'        | '1%'      | '1/16W'  | '0402LF'  | 'CHIP'   | 'CS11402FB19'(!)        = 'End of Design' | 'Comp-Approve'     | 'CS11402FB19'           | 'R0402'             | '(R0402-0201)'                 | '140'     | '1%'    | '1/16W'  | 'DISCRETE' | 'RES CHIP 140 1/16W +-1%(0402)'                    | 'CHIP0402'     | ''          | ''            | '20110113'
 '140'        | '1%'      | '1/16W'  | '0402LF'  | 'EMPTY'  | 'CS11402FB19'(!)        = 'End of Design' | 'Comp-Approve'     | 'CS11402FB19'           | 'R0402'             | '(R0402-0201)'                 | '140'     | '1%'    | '1/16W'  | 'IO'       | 'RES CHIP 140 1/16W +-1%(0402)'                    | 'CHIP0402'     | ''          | ''            | '20110113'
 '4.99M'      | '1%'      | '1/16W'  | '0402LF'  | 'CHIP'   | 'CS54992FB00'(!)        = 'End of Design' | 'Comp-Release Qty' | 'CS54992FB00'           | 'R0402'             | '(R0402-0201)'                 | '4.99M'   | '1%'    | '1/16W'  | 'DISCRETE' | 'RES CHIP 4.99M 1/16W +-1%(0402)'                  | 'CHIP0402'     | ''          | ''            | '20110113'
 '4.99M'      | '1%'      | '1/16W'  | '0402LF'  | 'EMPTY'  | 'CS54992FB00'(!)        = 'End of Design' | 'Comp-Release Qty' | 'CS54992FB00'           | 'R0402'             | '(R0402-0201)'                 | '4.99M'   | '1%'    | '1/16W'  | 'IO'       | 'RES CHIP 4.99M 1/16W +-1%(0402)'                  | 'CHIP0402'     | ''          | ''            | '20110113'
 '10M'        | '1%'      | '1/16W'  | '0402LF'  | 'CHIP'   | 'CS61002FB00'(!)        = 'End of Design' | 'Comp-Approve'     | 'CS61002FB00'           | 'R0402'             | '(R0402-0201)'                 | '10M'     | '1%'    | '1/16W'  | 'DISCRETE' | 'RES CHIP 10M 1/16W +-1%(0402)'                    | 'CHIP0402'     | ''          | ''            | '20110113'
 '10M'        | '1%'      | '1/16W'  | '0402LF'  | 'EMPTY'  | 'CS61002FB00'(!)        = 'End of Design' | 'Comp-Approve'     | 'CS61002FB00'           | 'R0402'             | '(R0402-0201)'                 | '10M'     | '1%'    | '1/16W'  | 'IO'       | 'RES CHIP 10M 1/16W +-1%(0402)'                    | 'CHIP0402'     | ''          | ''            | '20110113'
 '31.6'       | '1%'      | '1/16W'  | '0402LF'  | 'CHIP'   | 'CS03162FB01'(!)        = ''              | ''                 | 'CS03162FB01'           | 'R0402'             | '(R0402-0201)'                 | '31.6'    | '1%'    | '1/16W'  | 'DISCRETE' | 'RES CHIP 31.6 1/16W +-1%(0402)'                   | 'CHIP0402'     | ''          | ''            | '20110124'
 '31.6'       | '1%'      | '1/16W'  | '0402LF'  | 'EMPTY'  | 'CS03162FB01'(!)        = ''              | ''                 | 'CS03162FB01'           | 'R0402'             | '(R0402-0201)'                 | '31.6'    | '1%'    | '1/16W'  | 'IO'       | 'RES CHIP 31.6 1/16W +-1%(0402)'                   | 'CHIP0402'     | ''          | ''            | '20110124'
 '931'        | '1%'      | '1/16W'  | '0402LF'  | 'CHIP'   | 'CS19312FB00'(!)        = 'End of Design' | 'Comp-Approve'     | 'CS19312FB00'           | 'R0402'             | '(R0402-0201)'                 | '931'     | '1%'    | '1/16W'  | 'DISCRETE' | 'RES CHIP 931 1/16W +-1%(0402)HF'                  | 'CHIP0402'     | ''          | ''            | '20110128'
 '931'        | '1%'      | '1/16W'  | '0402LF'  | 'EMPTY'  | 'CS19312FB00'(!)        = 'End of Design' | 'Comp-Approve'     | 'CS19312FB00'           | 'R0402'             | '(R0402-0201)'                 | '931'     | '1%'    | '1/16W'  | 'IO'       | 'RES CHIP 931 1/16W +-1%(0402)HF'                  | 'CHIP0402'     | ''          | ''            | '20110128'
 '576'        | '1%'      | '1/16W'  | '0402LF'  | 'CHIP'   | 'CS15762FB26'(!)        = 'End of Design' | 'Comp-Release Qty' | 'CS15762FB26'           | 'R0402'             | '(R0402-0201)'                 | '576'     | '1%'    | '1/16W'  | 'DISCRETE' | 'RES CHIP 576 1/16W +-1%(0402)'                    | 'CHIP0402'     | ''          | ''            | '20110128'
 '576'        | '1%'      | '1/16W'  | '0402LF'  | 'EMPTY'  | 'CS15762FB26'(!)        = 'End of Design' | 'Comp-Release Qty' | 'CS15762FB26'           | 'R0402'             | '(R0402-0201)'                 | '576'     | '1%'    | '1/16W'  | 'IO'       | 'RES CHIP 576 1/16W +-1%(0402)'                    | 'CHIP0402'     | ''          | ''            | '20110128'
 '365'        | '1%'      | '1/16W'  | '0402LF'  | 'CHIP'   | 'CS13652FB14'(!)        = 'End of Design' | 'Comp-Approve'     | 'CS13652FB14'           | 'R0402'             | '(R0402-0201)'                 | '365'     | '1%'    | '1/16W'  | 'DISCRETE' | 'RES CHIP 365 1/16W +-1% (0402)'                   | 'CHIP0402'     | ''          | ''            | '20110128'
 '365'        | '1%'      | '1/16W'  | '0402LF'  | 'EMPTY'  | 'CS13652FB14'(!)        = 'End of Design' | 'Comp-Approve'     | 'CS13652FB14'           | 'R0402'             | '(R0402-0201)'                 | '365'     | '1%'    | '1/16W'  | 'IO'       | 'RES CHIP 365 1/16W +-1% (0402)'                   | 'CHIP0402'     | ''          | ''            | '20110128'
 '12.4K'      | '1%'      | '1/16W'  | '0402LF'  | 'CHIP'   | 'CS31242FB13'(!)        = 'End of Design' | 'Comp-Approve'     | 'CS31242FB13'           | 'R0402'             | '(R0402-0201)'                 | '12.4K'   | '1%'    | '1/16W'  | 'DISCRETE' | 'RES CHIP 12.4k 1/16W +-1% (0402)'                 | 'CHIP0402'     | ''          | ''            | '20110215'
 '12.4K'      | '1%'      | '1/16W'  | '0402LF'  | 'EMPTY'  | 'CS31242FB13'(!)        = 'End of Design' | 'Comp-Approve'     | 'CS31242FB13'           | 'R0402'             | '(R0402-0201)'                 | '12.4K'   | '1%'    | '1/16W'  | 'IO'       | 'RES CHIP 12.4k 1/16W +-1% (0402)'                 | 'CHIP0402'     | ''          | ''            | '20110215'
 '0.001'      | '1%'      | '1W'     | '2512LF'  | 'CHIP'   | 'CS+0018F111'(!)        = 'End of Design' | 'Comp-Approve'     | 'CS+0018F111'           | 'R2512XE'           | '(SMR2512AW)'                  | '0.001'   | '1%'    | '1W'     | 'DISCRETE' | 'RES CHIP 0.001 1W +-1% (2512)'                    | 'CHIP2512'     | ''          | ''            | '20110405'
 '0.001'      | '1%'      | '1W'     | '2512LF'  | 'EMPTY'  | 'CS+0018F111'(!)        = 'End of Design' | 'Comp-Approve'     | 'CS+0018F111'           | 'R2512XE'           | '(SMR2512AW)'                  | '0.001'   | '1%'    | '1W'     | 'IO'       | 'RES CHIP 0.001 1W +-1% (2512)'                    | 'CHIP2512'     | ''          | ''            | '20110405'
 '49.9'       | '1%'      | '1/8W'   | '0805LF'  | 'CHIP'   | 'CS04994FA00'(!)        = ''              | ''                 | 'CS04994FA00'           | 'R0805'             | '(SMR0805AW)'                  | '49.9'    | '1%'    | '1/8W'   | 'DISCRETE' | 'RES CHIP 49.9 1/8W +-1% (0805)'                   | 'CHIP0805'     | ''          | ''            | '20110221'
 '49.9'       | '1%'      | '1/8W'   | '0805LF'  | 'EMPTY'  | 'CS04994FA00'(!)        = ''              | ''                 | 'CS04994FA00'           | 'R0805'             | '(SMR0805AW)'                  | '49.9'    | '1%'    | '1/8W'   | 'IO'       | 'RES CHIP 49.9 1/8W +-1% (0805)'                   | 'CHIP0805'     | ''          | ''            | '20110221'
 '10'         | '1%'      | '1/10W'  | '0603LF'  | 'CHIP'   | 'CS01003F935'(!)        = ''              | ''                 | 'CS01003F935'           | 'R0603'             | '(SMR0603AW)'                  | '10'      | '1%'    | '1/10W'  | 'DISCRETE' | 'RES CHIP 10 1/10W +-1% (0603)'                    | 'CHIP0603'     | ''          | ''            | '20110221'
 '10'         | '1%'      | '1/10W'  | '0603LF'  | 'EMPTY'  | 'CS01003F935'(!)        = ''              | ''                 | 'CS01003F935'           | 'R0603'             | '(SMR0603AW)'                  | '10'      | '1%'    | '1/10W'  | 'IO'       | 'RES CHIP 10 1/10W +-1% (0603)'                    | 'CHIP0603'     | ''          | ''            | '20110221'
 '0.402'      | '1%'      | '1/10W'  | '0603LF'  | 'CHIP'   | 'CS+4023F900'(!)        = ''              | ''                 | 'CS+4023F900'           | 'R0603'             | '(SMR0603AW)'                  | '0.402'   | '1%'    | '1/10W'  | 'DISCRETE' | 'RES CHIP 0.402 1/10W +-1%(0603)'                  | 'CHIP0603'     | ''          | ''            | '20110302'
 '0.402'      | '1%'      | '1/10W'  | '0603LF'  | 'EMPTY'  | 'CS+4023F900'(!)        = ''              | ''                 | 'CS+4023F900'           | 'R0603'             | '(SMR0603AW)'                  | '0.402'   | '1%'    | '1/10W'  | 'IO'       | 'RES CHIP 0.402 1/10W +-1%(0603)'                  | 'CHIP0603'     | ''          | ''            | '20110302'
 '0.1'        | '1%'      | '1/10W'  | '0603LF'  | 'CHIP'   | 'CS+1003F900'(!)        = ''              | ''                 | 'CS+1003F900'           | 'R0603'             | '(SMR0603AW)'                  | '0.1'     | '1%'    | '1/10W'  | 'DISCRETE' | 'RES CHIP 0.1 1/10W +-1%(0603)'                    | 'CHIP0603'     | ''          | ''            | '20110302'
 '0.1'        | '1%'      | '1/10W'  | '0603LF'  | 'EMPTY'  | 'CS+1003F900'(!)        = ''              | ''                 | 'CS+1003F900'           | 'R0603'             | '(SMR0603AW)'                  | '0.1'     | '1%'    | '1/10W'  | 'IO'       | 'RES CHIP 0.1 1/10W +-1%(0603)'                    | 'CHIP0603'     | ''          | ''            | '20110302'
 '270'        | '1%'      | '1/16W'  | '0402LF'  | 'CHIP'   | 'CS12702FB12'(!)        = 'End of Design' | 'Comp-Approve'     | 'CS12702FB12'           | 'R0402'             | '(R0402-0201)'                 | '270'     | '1%'    | '1/16W'  | 'DISCRETE' | 'RES CHIP 270 1/16W +-1%(0402)'                    | 'CHIP0402'     | ''          | ''            | '20110303'
 '270'        | '1%'      | '1/16W'  | '0402LF'  | 'EMPTY'  | 'CS12702FB12'(!)        = 'End of Design' | 'Comp-Approve'     | 'CS12702FB12'           | 'R0402'             | '(R0402-0201)'                 | '270'     | '1%'    | '1/16W'  | 'IO'       | 'RES CHIP 270 1/16W +-1%(0402)'                    | 'CHIP0402'     | ''          | ''            | '20110303'
 '0.05'       | '1%'      | '1W'     | '2512LF'  | 'CHIP'   | 'CS+0508FR00'(!)        = ''              | ''                 | 'CS+0508FR00'           | 'R2512XB'           | '(SMR2512AW)'                  | '0.05'    | '1%'    | '1W'     | 'DISCRETE' | 'RES CHIP 0.05 1W +-1% (2512)'                     | 'CHIP2512'     | ''          | ''            | '20110304'
 '0.05'       | '1%'      | '1W'     | '2512LF'  | 'EMPTY'  | 'CS+0508FR00'(!)        = ''              | ''                 | 'CS+0508FR00'           | 'R2512XB'           | '(SMR2512AW)'                  | '0.05'    | '1%'    | '1W'     | 'IO'       | 'RES CHIP 0.05 1W +-1% (2512)'                     | 'CHIP2512'     | ''          | ''            | '20110304'
 '0.05'       | '1%'      | '1W'     | '3720LF'  | 'CHIP'   | 'CS+0508FL11'(!)        = ''              | ''                 | 'CS+0508FL11'           | 'R3720'             | '(SMR3720AW)'                  | '0.05'    | '1%'    | '1W'     | 'DISCRETE' | 'RES CHIP 0.05 1W +-1%(3720)'                      | 'CHIP3720'     | ''          | ''            | '20110304'
 '0.05'       | '1%'      | '1W'     | '3720LF'  | 'EMPTY'  | 'CS+0508FL11'(!)        = ''              | ''                 | 'CS+0508FL11'           | 'R3720'             | '(SMR3720AW)'                  | '0.05'    | '1%'    | '1W'     | 'IO'       | 'RES CHIP 0.05 1W +-1%(3720)'                      | 'CHIP3720'     | ''          | ''            | '20110304'
 '523'        | '1%'      | '1/16W'  | '0402LF'  | 'CHIP'   | 'CS15232FB00'(!)        = 'End of Design' | 'Comp-Approve'     | 'CS15232FB00'           | 'R0402'             | '(R0402-0201)'                 | '523'     | '1%'    | '1/16W'  | 'DISCRETE' | 'RES CHIP 523 1/16W +-1%(0402)'                    | 'CHIP0402'     | ''          | ''            | '20110308'
 '523'        | '1%'      | '1/16W'  | '0402LF'  | 'EMPTY'  | 'CS15232FB00'(!)        = 'End of Design' | 'Comp-Approve'     | 'CS15232FB00'           | 'R0402'             | '(R0402-0201)'                 | '523'     | '1%'    | '1/16W'  | 'IO'       | 'RES CHIP 523 1/16W +-1%(0402)'                    | 'CHIP0402'     | ''          | ''            | '20110308'
 '19.6K'      | '1%'      | '1/16W'  | '0402LF'  | 'CHIP'   | 'CS31962FB18'(!)        = 'End of Design' | 'Comp-Approve'     | 'CS31962FB18'           | 'R0402'             | '(R0402-0201)'                 | '19.6K'   | '1%'    | '1/16W'  | 'DISCRETE' | 'RES CHIP 19.6K 1/16W +-1% (0402)'                 | 'CHIP0402'     | ''          | ''            | '20110308'
 '19.6K'      | '1%'      | '1/16W'  | '0402LF'  | 'EMPTY'  | 'CS31962FB18'(!)        = 'End of Design' | 'Comp-Approve'     | 'CS31962FB18'           | 'R0402'             | '(R0402-0201)'                 | '19.6K'   | '1%'    | '1/16W'  | 'IO'       | 'RES CHIP 19.6K 1/16W +-1% (0402)'                 | 'CHIP0402'     | ''          | ''            | '20110308'
 '46.4K'      | '1%'      | '1/16W'  | '0402LF'  | 'CHIP'   | 'CS34642FB16'(!)        = 'End of Design' | 'Comp-Approve'     | 'CS34642FB16'           | 'R0402'             | '(R0402-0201)'                 | '46.4K'   | '1%'    | '1/16W'  | 'DISCRETE' | 'RES CHIP 46.4K 1/16W +-1%(0402)'                  | 'CHIP0402'     | ''          | ''            | '20110314'
 '46.4K'      | '1%'      | '1/16W'  | '0402LF'  | 'EMPTY'  | 'CS34642FB16'(!)        = 'End of Design' | 'Comp-Approve'     | 'CS34642FB16'           | 'R0402'             | '(R0402-0201)'                 | '46.4K'   | '1%'    | '1/16W'  | 'IO'       | 'RES CHIP 46.4K 1/16W +-1%(0402)'                  | 'CHIP0402'     | ''          | ''            | '20110314'
 '43K'        | '1%'      | '1/16W'  | '0402LF'  | 'CHIP'   | 'CS34302FB17'(!)        = 'End of Design' | 'Comp-Approve'     | 'CS34302FB17'           | 'R0402'             | '(R0402-0201)'                 | '43K'     | '1%'    | '1/16W'  | 'DISCRETE' | 'RES CHIP 43K 1/16W +-1% (0402)'                   | 'CHIP0402'     | ''          | ''            | '20110316'
 '43K'        | '1%'      | '1/16W'  | '0402LF'  | 'EMPTY'  | 'CS34302FB17'(!)        = 'End of Design' | 'Comp-Approve'     | 'CS34302FB17'           | 'R0402'             | '(R0402-0201)'                 | '43K'     | '1%'    | '1/16W'  | 'IO'       | 'RES CHIP 43K 1/16W +-1% (0402)'                   | 'CHIP0402'     | ''          | ''            | '20110316'
 '1.2K'       | '1%'      | '1/10W'  | '0603LF'  | 'CHIP'   | 'CS21203F910'(!)        = 'End of Design' | 'Comp-Approve'     | 'CS21203F910'           | 'R0603'             | '(SMR0603AW)'                  | '1.2K'    | '1%'    | '1/10W'  | 'DISCRETE' | 'RES CHIP 1.2K 1/10W +-1%(0603)'                   | 'CHIP0603'     | ''          | ''            | '20110316'
 '1.2K'       | '1%'      | '1/10W'  | '0603LF'  | 'EMPTY'  | 'CS21203F910'(!)        = 'End of Design' | 'Comp-Approve'     | 'CS21203F910'           | 'R0603'             | '(SMR0603AW)'                  | '1.2K'    | '1%'    | '1/10W'  | 'IO'       | 'RES CHIP 1.2K 1/10W +-1%(0603)'                   | 'CHIP0603'     | ''          | ''            | '20110316'
 '680'        | '1%'      | '1/10W'  | '0603LF'  | 'CHIP'   | 'CS16803F913'(!)        = 'End of Design' | 'Comp-Approve'     | 'CS16803F913'           | 'R0603'             | '(SMR0603AW)'                  | '680'     | '1%'    | '1/10W'  | 'DISCRETE' | 'RES CHIP 680 1/10W +-1%(0603)'                    | 'CHIP0603'     | ''          | ''            | '20110317'
 '680'        | '1%'      | '1/10W'  | '0603LF'  | 'EMPTY'  | 'CS16803F913'(!)        = 'End of Design' | 'Comp-Approve'     | 'CS16803F913'           | 'R0603'             | '(SMR0603AW)'                  | '680'     | '1%'    | '1/10W'  | 'IO'       | 'RES CHIP 680 1/10W +-1%(0603)'                    | 'CHIP0603'     | ''          | ''            | '20110317'
 '150K'       | '5%'      | '1/16W'  | '0402LF'  | 'CHIP'   | 'CS41502JB10'(!)        = 'End of Design' | 'Comp-Approve'     | 'CS41502JB10'           | 'R0402'             | '(R0402-0201)'                 | '150K'    | '5%'    | '1/16W'  | 'DISCRETE' | 'RES CHIP 150K 1/16W+-5%(0402)'                    | 'CHIP0402'     | ''          | ''            | '20110321'
 '150K'       | '5%'      | '1/16W'  | '0402LF'  | 'EMPTY'  | 'CS41502JB10'(!)        = 'End of Design' | 'Comp-Approve'     | 'CS41502JB10'           | 'R0402'             | '(R0402-0201)'                 | '150K'    | '5%'    | '1/16W'  | 'IO'       | 'RES CHIP 150K 1/16W+-5%(0402)'                    | 'CHIP0402'     | ''          | ''            | '20110321'
 '124K'       | '1%'      | '1/16W'  | '0402LF'  | 'CHIP'   | 'CS41242FB15'(!)        = 'End of Design' | 'Comp-Approve'     | 'CS41242FB15'           | 'R0402'             | '(R0402-0201)'                 | '124K'    | '1%'    | '1/16W'  | 'DISCRETE' | 'RES CHIP 124K 1/16W +-1%( 0402)'                  | 'CHIP0402'     | ''          | ''            | '20110328'
 '124K'       | '1%'      | '1/16W'  | '0402LF'  | 'EMPTY'  | 'CS41242FB15'(!)        = 'End of Design' | 'Comp-Approve'     | 'CS41242FB15'           | 'R0402'             | '(R0402-0201)'                 | '124K'    | '1%'    | '1/16W'  | 'IO'       | 'RES CHIP 124K 1/16W +-1%( 0402)'                  | 'CHIP0402'     | ''          | ''            | '20110328'
 '180'        | '1%'      | '1/16W'  | '0402LF'  | 'CHIP'   | 'CS11802FB13'(!)        = 'End of Design' | 'Comp-Approve'     | 'CS11802FB13'           | 'R0402'             | '(R0402-0201)'                 | '180'     | '1%'    | '1/16W'  | 'DISCRETE' | 'RES CHIP 180 1/16W +-1% (0402)'                   | 'CHIP0402'     | ''          | ''            | '20110331'
 '180'        | '1%'      | '1/16W'  | '0402LF'  | 'EMPTY'  | 'CS11802FB13'(!)        = 'End of Design' | 'Comp-Approve'     | 'CS11802FB13'           | 'R0402'             | '(R0402-0201)'                 | '180'     | '1%'    | '1/16W'  | 'IO'       | 'RES CHIP 180 1/16W +-1% (0402)'                   | 'CHIP0402'     | ''          | ''            | '20110331'
 '8.25K'      | '1%'      | '1/16W'  | '0402LF'  | 'CHIP'   | 'CS28252FB15'(!)        = 'End of Design' | 'Comp-Approve'     | 'CS28252FB15'           | 'R0402'             | '(R0402-0201)'                 | '8.25K'   | '1%'    | '1/16W'  | 'DISCRETE' | 'RESISTOR CHIP 8.25K 1/16W+-1%(0402)'              | 'CHIP0402'     | ''          | ''            | '20110331'
 '8.25K'      | '1%'      | '1/16W'  | '0402LF'  | 'EMPTY'  | 'CS28252FB15'(!)        = 'End of Design' | 'Comp-Approve'     | 'CS28252FB15'           | 'R0402'             | '(R0402-0201)'                 | '8.25K'   | '1%'    | '1/16W'  | 'IO'       | 'RESISTOR CHIP 8.25K 1/16W+-1%(0402)'              | 'CHIP0402'     | ''          | ''            | '20110331'
 '3.9K'       | '1%'      | '1/16W'  | '0402LF'  | 'CHIP'   | 'CS23902FB14'(!)        = 'End of Design' | 'Comp-Approve'     | 'CS23902FB14'           | 'R0402'             | '(R0402-0201)'                 | '3.9K'    | '1%'    | '1/16W'  | 'DISCRETE' | 'RES CHIP 3.9K 1/16W+-1%(0402)'                    | 'CHIP0402'     | ''          | ''            | '20110331'
 '3.9K'       | '1%'      | '1/16W'  | '0402LF'  | 'EMPTY'  | 'CS23902FB14'(!)        = 'End of Design' | 'Comp-Approve'     | 'CS23902FB14'           | 'R0402'             | '(R0402-0201)'                 | '3.9K'    | '1%'    | '1/16W'  | 'IO'       | 'RES CHIP 3.9K 1/16W+-1%(0402)'                    | 'CHIP0402'     | ''          | ''            | '20110331'
 '1.6K'       | '1%'      | '1/16W'  | '0402LF'  | 'CHIP'   | 'CS21602FB00'(!)        = 'End of Design' | 'Comp-Approve'     | 'CS21602FB00'           | 'R0402'             | '(R0402-0201)'                 | '1.6K'    | '1%'    | '1/16W'  | 'DISCRETE' | 'RES CHIP 1.6K(1/16W.+-1%.0402)'                   | 'CHIP0402'     | ''          | ''            | '20110331'
 '1.6K'       | '1%'      | '1/16W'  | '0402LF'  | 'EMPTY'  | 'CS21602FB00'(!)        = 'End of Design' | 'Comp-Approve'     | 'CS21602FB00'           | 'R0402'             | '(R0402-0201)'                 | '1.6K'    | '1%'    | '1/16W'  | 'IO'       | 'RES CHIP 1.6K(1/16W.+-1%.0402)'                   | 'CHIP0402'     | ''          | ''            | '20110331'
 '56.2K'      | '1%'      | '1/16W'  | '0402LF'  | 'CHIP'   | 'CS35622FB10'(!)        = 'End of Design' | 'Comp-Approve'     | 'CS35622FB10'           | 'R0402'             | '(R0402-0201)'                 | '56.2K'   | '1%'    | '1/16W'  | 'DISCRETE' | 'RES CHIP 56.2K 1/16W +-1% (0402)'                 | 'CHIP0402'     | ''          | ''            | '20110407'
 '56.2K'      | '1%'      | '1/16W'  | '0402LF'  | 'EMPTY'  | 'CS35622FB10'(!)        = 'End of Design' | 'Comp-Approve'     | 'CS35622FB10'           | 'R0402'             | '(R0402-0201)'                 | '56.2K'   | '1%'    | '1/16W'  | 'IO'       | 'RES CHIP 56.2K 1/16W +-1% (0402)'                 | 'CHIP0402'     | ''          | ''            | '20110407'
 '71.5K'      | '1%'      | '1/16W'  | '0402LF'  | 'CHIP'   | 'CS37152FB11'(!)        = 'End of Design' | 'Comp-Approve'     | 'CS37152FB11'           | 'R0402'             | '(R0402-0201)'                 | '71.5K'   | '1%'    | '1/16W'  | 'DISCRETE' | 'RES CHIP 71.5K 1/16W +-1%(0402)'                  | 'CHIP0402'     | ''          | ''            | '20110411'
 '71.5K'      | '1%'      | '1/16W'  | '0402LF'  | 'EMPTY'  | 'CS37152FB11'(!)        = 'End of Design' | 'Comp-Approve'     | 'CS37152FB11'           | 'R0402'             | '(R0402-0201)'                 | '71.5K'   | '1%'    | '1/16W'  | 'IO'       | 'RES CHIP 71.5K 1/16W +-1%(0402)'                  | 'CHIP0402'     | ''          | ''            | '20110411'
 '2.0M'       | '1%'      | '1/10W'  | '0603LF'  | 'CHIP'   | 'CS52003F911'(!)        = 'End of Design' | 'Comp-Approve'     | 'CS52003F911'           | 'R0603'             | '(SMR0603AW)'                  | '2.0M'    | '1%'    | '1/10W'  | 'DISCRETE' | 'RESISTOR CHIP 2M 1/10W +-1%(0603)'                | 'CHIP0603'     | ''          | ''            | '20110411'
 '2.0M'       | '1%'      | '1/10W'  | '0603LF'  | 'EMPTY'  | 'CS52003F911'(!)        = 'End of Design' | 'Comp-Approve'     | 'CS52003F911'           | 'R0603'             | '(SMR0603AW)'                  | '2.0M'    | '1%'    | '1/10W'  | 'IO'       | 'RESISTOR CHIP 2M 1/10W +-1%(0603)'                | 'CHIP0603'     | ''          | ''            | '20110411'
 '4.7M'       | '1%'      | '1/10W'  | '0603LF'  | 'CHIP'   | 'CS54703F903'(!)        = 'End of Design' | 'Comp-Approve'     | 'CS54703F903'           | 'R0603'             | '(SMR0603AW)'                  | '4.7M'    | '1%'    | '1/10W'  | 'DISCRETE' | 'RES CHIP 4.7M 1/10W +-1%(0603)'                   | 'CHIP0603'     | ''          | ''            | '20110411'
 '4.7M'       | '1%'      | '1/10W'  | '0603LF'  | 'EMPTY'  | 'CS54703F903'(!)        = 'End of Design' | 'Comp-Approve'     | 'CS54703F903'           | 'R0603'             | '(SMR0603AW)'                  | '4.7M'    | '1%'    | '1/10W'  | 'IO'       | 'RES CHIP 4.7M 1/10W +-1%(0603)'                   | 'CHIP0603'     | ''          | ''            | '20110411'
 '15.4K'      | '1%'      | '1/16W'  | '0402LF'  | 'CHIP'   | 'CS31542FB14'(!)        = 'End of Design' | 'Comp-Approve'     | 'CS31542FB14'           | 'R0402'             | '(R0402-0201)'                 | '15.4K'   | '1%'    | '1/16W'  | 'DISCRETE' | 'RES CHIP 15.4K 1/16W +-1%(0402)'                  | 'CHIP0402'     | ''          | ''            | '20110411'
 '15.4K'      | '1%'      | '1/16W'  | '0402LF'  | 'EMPTY'  | 'CS31542FB14'(!)        = 'End of Design' | 'Comp-Approve'     | 'CS31542FB14'           | 'R0402'             | '(R0402-0201)'                 | '15.4K'   | '1%'    | '1/16W'  | 'IO'       | 'RES CHIP 15.4K 1/16W +-1%(0402)'                  | 'CHIP0402'     | ''          | ''            | '20110411'
 '49.9'       | '1%'      | '1/10W'  | '0603LF'  | 'CHIP'   | 'CS04993F953'(!)        = ''              | ''                 | 'CS04993F953'           | 'R0603'             | '(SMR0603AW)'                  | '49.9'    | '1%'    | '1/10W'  | 'DISCRETE' | 'RESISTOR CHIP 49.9 1/10W +-1%(1608) '             | 'CHIP0603'     | ''          | ''            | '20110419'
 '49.9'       | '1%'      | '1/10W'  | '0603LF'  | 'EMPTY'  | 'CS04993F953'(!)        = ''              | ''                 | 'CS04993F953'           | 'R0603'             | '(SMR0603AW)'                  | '49.9'    | '1%'    | '1/10W'  | 'IO'       | 'RESISTOR CHIP 49.9 1/10W +-1%(1608) '             | 'CHIP0603'     | ''          | ''            | '20110419'
 '35.7K'      | '1%'      | '1/16W'  | '0402LF'  | 'CHIP'   | 'CS33572FB13'(!)        = 'End of Design' | 'Comp-Approve'     | 'CS33572FB13'           | 'R0402'             | '(R0402-0201)'                 | '35.7K'   | '1%'    | '1/16W'  | 'DISCRETE' | 'RES CHIP 35.7K 1/16W +-1%(0402)'                  | 'CHIP0402'     | ''          | ''            | '20110420'
 '35.7K'      | '1%'      | '1/16W'  | '0402LF'  | 'EMPTY'  | 'CS33572FB13'(!)        = 'End of Design' | 'Comp-Approve'     | 'CS33572FB13'           | 'R0402'             | '(R0402-0201)'                 | '35.7K'   | '1%'    | '1/16W'  | 'IO'       | 'RES CHIP 35.7K 1/16W +-1%(0402)'                  | 'CHIP0402'     | ''          | ''            | '20110420'
 '24.3K'      | '1%'      | '1/16W'  | '0402LF'  | 'CHIP'   | 'CS32432FB19'(!)        = 'End of Design' | 'Comp-Approve'     | 'CS32432FB19'           | 'R0402'             | '(R0402-0201)'                 | '24.3K'   | '1%'    | '1/16W'  | 'DISCRETE' | 'RES CHIP 24.3K 1/16W +-1%(0402)'                  | 'CHIP0402'     | ''          | ''            | '20110420'
 '24.3K'      | '1%'      | '1/16W'  | '0402LF'  | 'EMPTY'  | 'CS32432FB19'(!)        = 'End of Design' | 'Comp-Approve'     | 'CS32432FB19'           | 'R0402'             | '(R0402-0201)'                 | '24.3K'   | '1%'    | '1/16W'  | 'IO'       | 'RES CHIP 24.3K 1/16W +-1%(0402)'                  | 'CHIP0402'     | ''          | ''            | '20110420'
 '25.5K'      | '1%'      | '1/16W'  | '0402LF'  | 'CHIP'   | 'CS32552FB11'(!)        = 'End of Design' | 'Comp-Approve'     | 'CS32552FB11'           | 'R0402'             | '(R0402-0201)'                 | '25.5K'   | '1%'    | '1/16W'  | 'DISCRETE' | 'RES CHIP 25.5K 1/16W +-1%(0402)'                  | 'CHIP0402'     | ''          | ''            | '20110420'
 '25.5K'      | '1%'      | '1/16W'  | '0402LF'  | 'EMPTY'  | 'CS32552FB11'(!)        = 'End of Design' | 'Comp-Approve'     | 'CS32552FB11'           | 'R0402'             | '(R0402-0201)'                 | '25.5K'   | '1%'    | '1/16W'  | 'IO'       | 'RES CHIP 25.5K 1/16W +-1%(0402)'                  | 'CHIP0402'     | ''          | ''            | '20110420'
 '60.4K'      | '1%'      | '1/16W'  | '0402LF'  | 'CHIP'   | 'CS36042FB10'(!)        = 'End of Design' | 'Comp-Approve'     | 'CS36042FB10'           | 'R0402'             | '(R0402-0201)'                 | '60.4K'   | '1%'    | '1/16W'  | 'DISCRETE' | 'RES CHIP 60.4K 1/16W +-1%(0402)'                  | 'CHIP0402'     | ''          | ''            | '20110531'
 '60.4K'      | '1%'      | '1/16W'  | '0402LF'  | 'EMPTY'  | 'CS36042FB10'(!)        = 'End of Design' | 'Comp-Approve'     | 'CS36042FB10'           | 'R0402'             | '(R0402-0201)'                 | '60.4K'   | '1%'    | '1/16W'  | 'IO'       | 'RES CHIP 60.4K 1/16W +-1%(0402)'                  | 'CHIP0402'     | ''          | ''            | '20110531'
 '39.2K'      | '1%'      | '1/16W'  | '0402LF'  | 'CHIP'   | 'CS33922FB15'(!)        = 'End of Design' | 'Comp-Approve'     | 'CS33922FB15'           | 'R0402'             | '(R0402-0201)'                 | '39.2K'   | '1%'    | '1/16W'  | 'DISCRETE' | 'RES CHIP 39.2K 1/16W +-1%(0402)'                  | 'CHIP0402'     | ''          | ''            | '20110531'
 '39.2K'      | '1%'      | '1/16W'  | '0402LF'  | 'EMPTY'  | 'CS33922FB15'(!)        = 'End of Design' | 'Comp-Approve'     | 'CS33922FB15'           | 'R0402'             | '(R0402-0201)'                 | '39.2K'   | '1%'    | '1/16W'  | 'IO'       | 'RES CHIP 39.2K 1/16W +-1%(0402)'                  | 'CHIP0402'     | ''          | ''            | '20110531'
 '1.18K'      | '1%'      | '1/16W'  | '0402LF'  | 'CHIP'   | 'CS21182FB08'(!)        = 'End of Design' | 'Comp-Approve'     | 'CS21182FB08'           | 'R0402'             | '(R0402-0201)'                 | '1.18K'   | '1%'    | '1/16W'  | 'DISCRETE' | 'RES CHIP 1.18K 1/16W +-1%(0402)'                  | 'CHIP0402'     | ''          | ''            | '20110601'
 '1.18K'      | '1%'      | '1/16W'  | '0402LF'  | 'EMPTY'  | 'CS21182FB08'(!)        = 'End of Design' | 'Comp-Approve'     | 'CS21182FB08'           | 'R0402'             | '(R0402-0201)'                 | '1.18K'   | '1%'    | '1/16W'  | 'IO'       | 'RES CHIP 1.18K 1/16W +-1%(0402)'                  | 'CHIP0402'     | ''          | ''            | '20110601'
 '4.22K'      | '1%'      | '1/16W'  | '0402LF'  | 'CHIP'   | 'CS24222FB11'(!)        = 'End of Design' | 'Comp-Approve'     | 'CS24222FB11'           | 'R0402'             | '(R0402-0201)'                 | '4.22K'   | '1%'    | '1/16W'  | 'DISCRETE' | 'RES CHIP 4.22K 1/16W +-1%(0402)'                  | 'CHIP0402'     | ''          | ''            | '20110601'
 '4.22K'      | '1%'      | '1/16W'  | '0402LF'  | 'EMPTY'  | 'CS24222FB11'(!)        = 'End of Design' | 'Comp-Approve'     | 'CS24222FB11'           | 'R0402'             | '(R0402-0201)'                 | '4.22K'   | '1%'    | '1/16W'  | 'IO'       | 'RES CHIP 4.22K 1/16W +-1%(0402)'                  | 'CHIP0402'     | ''          | ''            | '20110601'
 '2'          | '1%'      | '1/10W'  | '0603LF'  | 'CHIP'   | 'CS-2003F900'(!)        = ''              | ''                 | 'CS-2003F900'           | 'R0603'             | '(SMR0603AW)'                  | '2'       | '1%'    | '1/10W'  | 'DISCRETE' | 'RES CHIP 2 1/10W +-1%(0603)'                      | 'CHIP0603'     | ''          | ''            | '20110624'
 '2'          | '1%'      | '1/10W'  | '0603LF'  | 'EMPTY'  | 'CS-2003F900'(!)        = ''              | ''                 | 'CS-2003F900'           | 'R0603'             | '(SMR0603AW)'                  | '2'       | '1%'    | '1/10W'  | 'IO'       | 'RES CHIP 2 1/10W +-1%(0603)'                      | 'CHIP0603'     | ''          | ''            | '20110624'
 '29.4K'      | '1%'      | '1/16W'  | '0402LF'  | 'CHIP'   | 'CS32942FB03'(!)        = 'End of Design' | 'Comp-Approve'     | 'CS32942FB03'           | 'R0402'             | '(R0402-0201)'                 | '29.4K'   | '1%'    | '1/16W'  | 'DISCRETE' | 'RES CHIP 29.4K 1/16W +-1%(0402)'                  | 'CHIP0402'     | ''          | ''            | '20110725'
 '29.4K'      | '1%'      | '1/16W'  | '0402LF'  | 'EMPTY'  | 'CS32942FB03'(!)        = 'End of Design' | 'Comp-Approve'     | 'CS32942FB03'           | 'R0402'             | '(R0402-0201)'                 | '29.4K'   | '1%'    | '1/16W'  | 'IO'       | 'RES CHIP 29.4K 1/16W +-1%(0402)'                  | 'CHIP0402'     | ''          | ''            | '20110725'
 '22.6K'      | '1%'      | '1/16W'  | '0402LF'  | 'CHIP'   | 'CS32262FB15'(!)        = 'End of Design' | 'Comp-Approve'     | 'CS32262FB15'           | 'R0402'             | '(R0402-0201)'                 | '22.6K'   | '1%'    | '1/16W'  | 'DISCRETE' | 'RES CHIP 22.6K 1/16W +-1%(0402)'                  | 'CHIP0402'     | ''          | ''            | '20110725'
 '22.6K'      | '1%'      | '1/16W'  | '0402LF'  | 'EMPTY'  | 'CS32262FB15'(!)        = 'End of Design' | 'Comp-Approve'     | 'CS32262FB15'           | 'R0402'             | '(R0402-0201)'                 | '22.6K'   | '1%'    | '1/16W'  | 'IO'       | 'RES CHIP 22.6K 1/16W +-1%(0402)'                  | 'CHIP0402'     | ''          | ''            | '20110725'
 '383'        | '1%'      | '1/16W'  | '0402LF'  | 'CHIP'   | 'CS13832FB00'(!)        = 'End of Design' | 'Comp-Approve'     | 'CS13832FB00'           | 'R0402'             | '(R0402-0201)'                 | '383'     | '1%'    | '1/16W'  | 'DISCRETE' | 'RES CHIP 383 1/16W +-1%(0402)'                    | 'CHIP0402'     | ''          | ''            | '20110725'
 '383'        | '1%'      | '1/16W'  | '0402LF'  | 'EMPTY'  | 'CS13832FB00'(!)        = 'End of Design' | 'Comp-Approve'     | 'CS13832FB00'           | 'R0402'             | '(R0402-0201)'                 | '383'     | '1%'    | '1/16W'  | 'IO'       | 'RES CHIP 383 1/16W +-1%(0402)'                    | 'CHIP0402'     | ''          | ''            | '20110725'
 '2.2'        | '1%'      | '1/16W'  | '0402LF'  | 'CHIP'   | 'CS-2202FB00'(!)        = 'End of Design' | 'Comp-Approve'     | 'CS-2202FB00'           | 'R0402'             | '(R0402-0201)'                 | '2.2'     | '1%'    | '1/16W'  | 'DISCRETE' | 'RES CHIP 2.2 1/16W +-1% (0402)'                   | 'CHIP0402'     | ''          | ''            | '20110725'
 '2.2'        | '1%'      | '1/16W'  | '0402LF'  | 'EMPTY'  | 'CS-2202FB00'(!)        = 'End of Design' | 'Comp-Approve'     | 'CS-2202FB00'           | 'R0402'             | '(R0402-0201)'                 | '2.2'     | '1%'    | '1/16W'  | 'IO'       | 'RES CHIP 2.2 1/16W +-1% (0402)'                   | 'CHIP0402'     | ''          | ''            | '20110725'
 '1.13k'      | '1%'      | '1/16W'  | '0402LF'  | 'CHIP'   | 'CS21132FB13'(!)        = ''              | ''                 | 'CS21132FB13'           | 'R0402'             | '(R0402-0201)'                 | '1.13k'   | '1%'    | '1/16W'  | 'DISCRETE' | 'RES CHIP 1.13K 1/16W +-1%(0402)'                  | 'CHIP0402'     | ''          | ''            | '20110725'
 '1.13k'      | '1%'      | '1/16W'  | '0402LF'  | 'EMPTY'  | 'CS21132FB13'(!)        = ''              | ''                 | 'CS21132FB13'           | 'R0402'             | '(R0402-0201)'                 | '1.13k'   | '1%'    | '1/16W'  | 'IO'       | 'RES CHIP 1.13K 1/16W +-1%(0402)'                  | 'CHIP0402'     | ''          | ''            | '20110725'
 '38.3K'      | '1%'      | '1/16W'  | '0402LF'  | 'CHIP'   | 'CS33832FB08'(!)        = 'End of Design' | 'Comp-Approve'     | 'CS33832FB08'           | 'R0402'             | '(R0402-0201)'                 | '38.3K'   | '1%'    | '1/16W'  | 'DISCRETE' | 'RES CHIP 38.3K 1/16W +-1% (0402)'                 | 'CHIP0402'     | ''          | ''            | '20110725'
 '38.3K'      | '1%'      | '1/16W'  | '0402LF'  | 'EMPTY'  | 'CS33832FB08'(!)        = 'End of Design' | 'Comp-Approve'     | 'CS33832FB08'           | 'R0402'             | '(R0402-0201)'                 | '38.3K'   | '1%'    | '1/16W'  | 'IO'       | 'RES CHIP 38.3K 1/16W +-1% (0402)'                 | 'CHIP0402'     | ''          | ''            | '20110725'
 '4.12K'      | '1%'      | '1/16W'  | '0402LF'  | 'CHIP'   | 'CS24122FB17'(!)        = 'End of Design' | 'Comp-Approve'     | 'CS24122FB17'           | 'R0402'             | '(R0402-0201)'                 | '4.12K'   | '1%'    | '1/16W'  | 'DISCRETE' | 'RES CHIP 4.12K 1/16W +-1%(0402)'                  | 'CHIP0402'     | ''          | ''            | '20110805'
 '4.12K'      | '1%'      | '1/16W'  | '0402LF'  | 'EMPTY'  | 'CS24122FB17'(!)        = 'End of Design' | 'Comp-Approve'     | 'CS24122FB17'           | 'R0402'             | '(R0402-0201)'                 | '4.12K'   | '1%'    | '1/16W'  | 'IO'       | 'RES CHIP 4.12K 1/16W +-1%(0402)'                  | 'CHIP0402'     | ''          | ''            | '20110805'
 '1.91K'      | '1%'      | '1/16W'  | '0402LF'  | 'CHIP'   | 'CS21912FB05'(!)        = ''              | ''                 | 'CS21912FB05'           | 'R0402'             | '(R0402-0201)'                 | '1.91K'   | '1%'    | '1/16W'  | 'DISCRETE' | 'RES CHIP 1.91K 1/16W +-1%(0402)'                  | 'CHIP0402'     | ''          | ''            | '20110810'
 '1.91K'      | '1%'      | '1/16W'  | '0402LF'  | 'EMPTY'  | 'CS21912FB05'(!)        = ''              | ''                 | 'CS21912FB05'           | 'R0402'             | '(R0402-0201)'                 | '1.91K'   | '1%'    | '1/16W'  | 'IO'       | 'RES CHIP 1.91K 1/16W +-1%(0402)'                  | 'CHIP0402'     | ''          | ''            | '20110810'
 '88.7K'      | '1%'      | '1/16W'  | '0402LF'  | 'CHIP'   | 'CS38872FB18'(!)        = 'End of Design' | 'Comp-Approve'     | 'CS38872FB18'           | 'R0402'             | '(R0402-0201)'                 | '88.7K'   | '1%'    | '1/16W'  | 'DISCRETE' | 'RES CHIP 88.7K 1/16W +-1%(0402)'                  | 'CHIP0402'     | ''          | ''            | '20110812'
 '88.7K'      | '1%'      | '1/16W'  | '0402LF'  | 'EMPTY'  | 'CS38872FB18'(!)        = 'End of Design' | 'Comp-Approve'     | 'CS38872FB18'           | 'R0402'             | '(R0402-0201)'                 | '88.7K'   | '1%'    | '1/16W'  | 'IO'       | 'RES CHIP 88.7K 1/16W +-1%(0402)'                  | 'CHIP0402'     | ''          | ''            | '20110812'
 '5.9K'       | '1%'      | '1/16W'  | '0402LF'  | 'CHIP'   | 'CS25902FB10'(!)        = 'End of Design' | 'Comp-Approve'     | 'CS25902FB10'           | 'R0402'             | '(R0402-0201)'                 | '5.9K'    | '1%'    | '1/16W'  | 'DISCRETE' | 'RES CHIP 5.9K 1/16W +-1%(0402)'                   | 'CHIP0402'     | ''          | ''            | '20110812'
 '5.9K'       | '1%'      | '1/16W'  | '0402LF'  | 'EMPTY'  | 'CS25902FB10'(!)        = 'End of Design' | 'Comp-Approve'     | 'CS25902FB10'           | 'R0402'             | '(R0402-0201)'                 | '5.9K'    | '1%'    | '1/16W'  | 'IO'       | 'RES CHIP 5.9K 1/16W +-1%(0402)'                   | 'CHIP0402'     | ''          | ''            | '20110812'
 '4.42K'      | '1%'      | '1/16W'  | '0402LF'  | 'CHIP'   | 'CS24422FB00'(!)        = 'End of Design' | 'Comp-Approve'     | 'CS24422FB00'           | 'R0402'             | '(R0402-0201)'                 | '4.42K'   | '1%'    | '1/16W'  | 'DISCRETE' | 'RES CHIP 4.42K 1/16W +-1%(0402)'                  | 'CHIP0402'     | ''          | ''            | '20110812'
 '4.42K'      | '1%'      | '1/16W'  | '0402LF'  | 'EMPTY'  | 'CS24422FB00'(!)        = 'End of Design' | 'Comp-Approve'     | 'CS24422FB00'           | 'R0402'             | '(R0402-0201)'                 | '4.42K'   | '1%'    | '1/16W'  | 'IO'       | 'RES CHIP 4.42K 1/16W +-1%(0402)'                  | 'CHIP0402'     | ''          | ''            | '20110812'
 '17.4K'      | '1%'      | '1/16W'  | '0402LF'  | 'CHIP'   | 'CS31742FB20'(!)        = 'End of Design' | 'Comp-Approve'     | 'CS31742FB20'           | 'R0402'             | '(R0402-0201)'                 | '17.4K'   | '1%'    | '1/16W'  | 'DISCRETE' | 'RES CHIP 17.4K 1/16W +-1% (0402)'                 | 'CHIP0402'     | ''          | ''            | '20110823'
 '17.4K'      | '1%'      | '1/16W'  | '0402LF'  | 'EMPTY'  | 'CS31742FB20'(!)        = 'End of Design' | 'Comp-Approve'     | 'CS31742FB20'           | 'R0402'             | '(R0402-0201)'                 | '17.4K'   | '1%'    | '1/16W'  | 'IO'       | 'RES CHIP 17.4K 1/16W +-1% (0402)'                 | 'CHIP0402'     | ''          | ''            | '20110823'
 '26.7K'      | '1%'      | '1/16W'  | '0402LF'  | 'CHIP'   | 'CS32672FB14'(!)        = 'End of Design' | 'Comp-Approve'     | 'CS32672FB14'           | 'R0402'             | '(R0402-0201)'                 | '26.7K'   | '1%'    | '1/16W'  | 'DISCRETE' | 'RES CHIP 26.7K 1/16W +-1%(0402)'                  | 'CHIP0402'     | ''          | ''            | '20110825'
 '26.7K'      | '1%'      | '1/16W'  | '0402LF'  | 'EMPTY'  | 'CS32672FB14'(!)        = 'End of Design' | 'Comp-Approve'     | 'CS32672FB14'           | 'R0402'             | '(R0402-0201)'                 | '26.7K'   | '1%'    | '1/16W'  | 'IO'       | 'RES CHIP 26.7K 1/16W +-1%(0402)'                  | 'CHIP0402'     | ''          | ''            | '20110825'
 '102K'       | '1%'      | '1/16W'  | '0402LF'  | 'CHIP'   | 'CS41022FB19'(!)        = 'End of Design' | 'Comp-Approve'     | 'CS41022FB19'           | 'R0402'             | '(R0402-0201)'                 | '102K'    | '1%'    | '1/16W'  | 'DISCRETE' | 'RES CHIP 102K 1/16W +-1%(0402)'                   | 'CHIP0402'     | ''          | ''            | '20110826'
 '102K'       | '1%'      | '1/16W'  | '0402LF'  | 'EMPTY'  | 'CS41022FB19'(!)        = 'End of Design' | 'Comp-Approve'     | 'CS41022FB19'           | 'R0402'             | '(R0402-0201)'                 | '102K'    | '1%'    | '1/16W'  | 'IO'       | 'RES CHIP 102K 1/16W +-1%(0402)'                   | 'CHIP0402'     | ''          | ''            | '20110826'
 '105K'       | '1%'      | '1/16W'  | '0402LF'  | 'CHIP'   | 'CS41052FB04'(!)        = 'End of Design' | 'Comp-Approve'     | 'CS41052FB04'           | 'R0402'             | '(R0402-0201)'                 | '105K'    | '1%'    | '1/16W'  | 'DISCRETE' | 'RES CHIP 105K 1/16W +-1%(0402)'                   | 'CHIP0402'     | ''          | ''            | '20110826'
 '105K'       | '1%'      | '1/16W'  | '0402LF'  | 'EMPTY'  | 'CS41052FB04'(!)        = 'End of Design' | 'Comp-Approve'     | 'CS41052FB04'           | 'R0402'             | '(R0402-0201)'                 | '105K'    | '1%'    | '1/16W'  | 'IO'       | 'RES CHIP 105K 1/16W +-1%(0402)'                   | 'CHIP0402'     | ''          | ''            | '20110826'
 '182K'       | '1%'      | '1/16W'  | '0402LF'  | 'CHIP'   | 'CS41822FB18'(!)        = 'End of Design' | 'Comp-Approve'     | 'CS41822FB18'           | 'R0402'             | '(R0402-0201)'                 | '182K'    | '1%'    | '1/16W'  | 'DISCRETE' | 'RES CHIP 182K 1/16W +-1%(0402)'                   | 'CHIP0402'     | ''          | ''            | '20110826'
 '182K'       | '1%'      | '1/16W'  | '0402LF'  | 'EMPTY'  | 'CS41822FB18'(!)        = 'End of Design' | 'Comp-Approve'     | 'CS41822FB18'           | 'R0402'             | '(R0402-0201)'                 | '182K'    | '1%'    | '1/16W'  | 'IO'       | 'RES CHIP 182K 1/16W +-1%(0402)'                   | 'CHIP0402'     | ''          | ''            | '20110826'
 '280K'       | '1%'      | '1/16W'  | '0402LF'  | 'CHIP'   | 'CS42802FB03'(!)        = 'End of Design' | 'Comp-Approve'     | 'CS42802FB03'           | 'R0402'             | '(R0402-0201)'                 | '182K'    | '1%'    | '1/16W'  | 'DISCRETE' | 'RES CHIP 280K 1/16W +-1%(0402)'                   | 'CHIP0402'     | ''          | ''            | '20110826'
 '280K'       | '1%'      | '1/16W'  | '0402LF'  | 'EMPTY'  | 'CS42802FB03'(!)        = 'End of Design' | 'Comp-Approve'     | 'CS42802FB03'           | 'R0402'             | '(R0402-0201)'                 | '182K'    | '1%'    | '1/16W'  | 'IO'       | 'RES CHIP 280K 1/16W +-1%(0402)'                   | 'CHIP0402'     | ''          | ''            | '20110826'
 '5.6K'       | '1%'      | '1/16W'  | '0402LF'  | 'CHIP'   | 'CS25602FB19'(!)        = 'End of Design' | 'Comp-Approve'     | 'CS25602FB19'           | 'R0402'             | '(R0402-0201)'                 | '5.6K'    | '1%'    | '1/16W'  | 'DISCRETE' | 'RES CHIP 5.6K 1/16W +-1%(0402)'                   | 'CHIP0402'     | ''          | ''            | '20110826'
 '5.6K'       | '1%'      | '1/16W'  | '0402LF'  | 'EMPTY'  | 'CS25602FB19'(!)        = 'End of Design' | 'Comp-Approve'     | 'CS25602FB19'           | 'R0402'             | '(R0402-0201)'                 | '5.6K'    | '1%'    | '1/16W'  | 'IO'       | 'RES CHIP 5.6K 1/16W +-1%(0402)'                   | 'CHIP0402'     | ''          | ''            | '20110826'
 '1K'         | '0.1%'    | '1/16W'  | '0402LF'  | 'CHIP'   | 'CS21002BB00'(!)        = ''              | ''                 | 'CS21002BB00'           | 'R0402'             | '(R0402-0201)'                 | '1K'      | '0.1%'  | '1/16W'  | 'DISCRETE' | 'RES CHIP 1K 1/16W +-0.1%(0402)'                   | 'CHIP0402'     | ''          | ''            | '20110909'
 '1K'         | '0.1%'    | '1/16W'  | '0402LF'  | 'EMPTY'  | 'CS21002BB00'(!)        = ''              | ''                 | 'CS21002BB00'           | 'R0402'             | '(R0402-0201)'                 | '1K'      | '0.1%'  | '1/16W'  | 'IO'       | 'RES CHIP 1K 1/16W +-0.1%(0402)'                   | 'CHIP0402'     | ''          | ''            | '20110909'
 '24.9'       | '0.5%'    | '1/16W'  | '0402LF'  | 'CHIP'   | 'CS02492DB00'(!)        = 'End of Design' | 'Comp-Approve'     | 'CS02492DB00'           | 'R0402'             | '(R0402-0201)'                 | '24.9'    | '0.5%'  | '1/16W'  | 'DISCRETE' | 'RES CHIP 24.9 1/16W +-0.5%(0402)'                 | 'CHIP0402'     | ''          | ''            | '20110909'
 '24.9'       | '0.5%'    | '1/16W'  | '0402LF'  | 'EMPTY'  | 'CS02492DB00'(!)        = 'End of Design' | 'Comp-Approve'     | 'CS02492DB00'           | 'R0402'             | '(R0402-0201)'                 | '24.9'    | '0.5%'  | '1/16W'  | 'IO'       | 'RES CHIP 24.9 1/16W +-0.5%(0402)'                 | 'CHIP0402'     | ''          | ''            | '20110909'
 '619K'       | '1%'      | '1/16W'  | '0402LF'  | 'CHIP'   | 'CS46192FB18'(!)        = 'End of Design' | 'Comp-Release Qty' | 'CS46192FB18'           | 'R0402'             | '(R0402-0201)'                 | '619K'    | '1%'    | '1/16W'  | 'DISCRETE' | 'RES CHIP 619K 1/16W +-1%(0402)'                   | 'CHIP0402'     | ''          | ''            | '20111111'
 '619K'       | '1%'      | '1/16W'  | '0402LF'  | 'EMPTY'  | 'CS46192FB18'(!)        = 'End of Design' | 'Comp-Release Qty' | 'CS46192FB18'           | 'R0402'             | '(R0402-0201)'                 | '619K'    | '1%'    | '1/16W'  | 'IO'       | 'RES CHIP 619K 1/16W +-1%(0402))'                  | 'CHIP0402'     | ''          | ''            | '20111111'
 '10.7K'      | '1%'      | '1/16W'  | '0402LF'  | 'CHIP'   | 'CS31072FB10'(!)        = 'End of Design' | 'Comp-Approve'     | 'CS31072FB10'           | 'R0402'             | '(R0402-0201)'                 | '10.7K'   | '1%'    | '1/16W'  | 'DISCRETE' | 'RES CHIP 10.7K 1/16W +-1% (0402)'                 | 'CHIP0402'     | ''          | ''            | '20111122'
 '10.7K'      | '1%'      | '1/16W'  | '0402LF'  | 'EMPTY'  | 'CS31072FB10'(!)        = 'End of Design' | 'Comp-Approve'     | 'CS31072FB10'           | 'R0402'             | '(R0402-0201)'                 | '10.7K'   | '1%'    | '1/16W'  | 'IO'       | 'RES CHIP 10.7K 1/16W +-1% (0402)'                 | 'CHIP0402'     | ''          | ''            | '20111122'
 '51K'        | '1%'      | '1/16W'  | '0402LF'  | 'CHIP'   | 'CS35102FB04'(!)        = 'End of Design' | 'Comp-Approve'     | 'CS35102FB04'           | 'R0402'             | '(R0402-0201)'                 | '51K'     | '1%'    | '1/16W'  | 'DISCRETE' | 'RES CHIP 51K 1/16W +-1%(0402)'                    | 'CHIP0402'     | ''          | ''            | '20111123'
 '51K'        | '1%'      | '1/16W'  | '0402LF'  | 'EMPTY'  | 'CS35102FB04'(!)        = 'End of Design' | 'Comp-Approve'     | 'CS35102FB04'           | 'R0402'             | '(R0402-0201)'                 | '51K'     | '1%'    | '1/16W'  | 'IO'       | 'RES CHIP 51K 1/16W +-1%(0402)'                    | 'CHIP0402'     | ''          | ''            | '20111123'
 '3.6K'       | '5%'      | '1/16W'  | '0402LF'  | 'CHIP'   | 'CS23602JB15'(!)        = 'End of Design' | 'Comp-Approve'     | 'CS23602JB15'           | 'R0402'             | '(R0402-0201)'                 | '3.6K'    | '5%'    | '1/16W'  | 'DISCRETE' | 'RES CHIP 3.6K 1/16W +-5%(0402)'                   | 'CHIP0402'     | ''          | ''            | '20111123'
 '3.6K'       | '5%'      | '1/16W'  | '0402LF'  | 'EMPTY'  | 'CS23602JB15'(!)        = 'End of Design' | 'Comp-Approve'     | 'CS23602JB15'           | 'R0402'             | '(R0402-0201)'                 | '3.6K'    | '5%'    | '1/16W'  | 'IO'       | 'RES CHIP 3.6K 1/16W +-5%(0402)'                   | 'CHIP0402'     | ''          | ''            | '20111123'
 '7.5'        | '1%'      | '1/16W'  | '0402LF'  | 'CHIP'   | 'CS-7502FB00'(!)        = 'End of Design' | 'Comp-Approve'     | 'CS-7502FB00'           | 'R0402'             | '(R0402-0201)'                 | '7.5'     | '1%'    | '1/16W'  | 'DISCRETE' | 'RES CHIP 7.5 1/16W +-1%(0402)'                    | 'CHIP0402'     | ''          | ''            | '20111123'
 '7.5'        | '1%'      | '1/16W'  | '0402LF'  | 'EMPTY'  | 'CS-7502FB00'(!)        = 'End of Design' | 'Comp-Approve'     | 'CS-7502FB00'           | 'R0402'             | '(R0402-0201)'                 | '7.5'     | '1%'    | '1/16W'  | 'IO'       | 'RES CHIP 7.5 1/16W +-1%(0402)'                    | 'CHIP0402'     | ''          | ''            | '20111123'
 '20'         | '5%'      | '2W'     | '2512LF'  | 'CHIP'   | 'CS0200AJR00'(!)        = ''              | ''                 | 'CS0200AJR00'           | 'R2512'             | '(SMR2512AW)'                  | '20'      | '5%'    | '2W'     | 'DISCRETE' | 'RESISTOR CHIP 20 2W +-5%(2512)'                   | 'CHIP2512'     | ''          | ''            | '20111124'
 '20'         | '5%'      | '2W'     | '2512LF'  | 'EMPTY'  | 'CS0200AJR00'(!)        = ''              | ''                 | 'CS0200AJR00'           | 'R2512'             | '(SMR2512AW)'                  | '20'      | '5%'    | '2W'     | 'IO'       | 'RESISTOR CHIP 20 2W +-5%(2512)'                   | 'CHIP2512'     | ''          | ''            | '20111124'
 '698'        | '1%'      | '1/16W'  | '0402LF'  | 'CHIP'   | 'CS16982FB00'(!)        = 'End of Design' | 'Comp-Approve'     | 'CS16982FB00'           | 'R0402'             | '(R0402-0201)'                 | '698'     | '1%'    | '1/16W'  | 'DISCRETE' | 'RES CHIP 698 1/16W +-1%(0402)'                    | 'CHIP0402'     | ''          | ''            | '20111125'
 '698'        | '1%'      | '1/16W'  | '0402LF'  | 'EMPTY'  | 'CS16982FB00'(!)        = 'End of Design' | 'Comp-Approve'     | 'CS16982FB00'           | 'R0402'             | '(R0402-0201)'                 | '698'     | '1%'    | '1/16W'  | 'IO'       | 'RES CHIP 698 1/16W +-1%(0402)'                    | 'CHIP0402'     | ''          | ''            | '20111125'
 '75K'        | '1%'      | '1/16W'  | '0402LF'  | 'CHIP'   | 'CS37502FB12'(!)        = 'End of Design' | 'Comp-Approve'     | 'CS37502FB12'           | 'R0402'             | '(R0402-0201)'                 | '75K'     | '1%'    | '1/16W'  | 'DISCRETE' | 'RES CHIP 75K 1/16W +-1%(0402)'                    | 'CHIP0402'     | ''          | ''            | '20111130'
 '75K'        | '1%'      | '1/16W'  | '0402LF'  | 'EMPTY'  | 'CS37502FB12'(!)        = 'End of Design' | 'Comp-Approve'     | 'CS37502FB12'           | 'R0402'             | '(R0402-0201)'                 | '75K'     | '1%'    | '1/16W'  | 'IO'       | 'RES CHIP 75K 1/16W +-1%(0402)'                    | 'CHIP0402'     | ''          | ''            | '20111130'
 '121K'       | '1%'      | '1/16W'  | '0402LF'  | 'CHIP'   | 'CS41212FB11'(!)        = 'End of Design' | 'Comp-Approve'     | 'CS41212FB11'           | 'R0402'             | '(R0402-0201)'                 | '121K'    | '1%'    | '1/16W'  | 'DISCRETE' | 'RES CHIP 121K 1/16W +-1%(0402)'                   | 'CHIP0402'     | ''          | ''            | '20111130'
 '121K'       | '1%'      | '1/16W'  | '0402LF'  | 'EMPTY'  | 'CS41212FB11'(!)        = 'End of Design' | 'Comp-Approve'     | 'CS41212FB11'           | 'R0402'             | '(R0402-0201)'                 | '121K'    | '1%'    | '1/16W'  | 'IO'       | 'RES CHIP 121K 1/16W +-1%(0402)'                   | 'CHIP0402'     | ''          | ''            | '20111130'
 '22.1K'      | '1%'      | '1/16W'  | '0402LF'  | 'CHIP'   | 'CS32212FB12'(!)        = 'End of Design' | 'Comp-Approve'     | 'CS32212FB12'           | 'R0402'             | '(R0402-0201)'                 | '22.1K'   | '1%'    | '1/16W'  | 'DISCRETE' | 'RES CHIP 22.1K 1/16W +-1%(0402)'                  | 'CHIP0402'     | ''          | ''            | '20111130'
 '22.1K'      | '1%'      | '1/16W'  | '0402LF'  | 'EMPTY'  | 'CS32212FB12'(!)        = 'End of Design' | 'Comp-Approve'     | 'CS32212FB12'           | 'R0402'             | '(R0402-0201)'                 | '22.1K'   | '1%'    | '1/16W'  | 'IO'       | 'RES CHIP 22.1K 1/16W +-1%(0402)'                  | 'CHIP0402'     | ''          | ''            | '20111130'
 '3K'         | '1%'      | '1/10W'  | '0603LF'  | 'CHIP'   | 'CS23003F926'(!)        = 'End of Design' | 'Comp-Approve'     | 'CS23003F926'           | 'R0603'             | '(SMR0603AW)'                  | '3K'      | '1%'    | '1/10W'  | 'DISCRETE' | 'RES CHIP 3K 1/10W +-1%(0603)'                     | 'CHIP0603'     | ''          | ''            | '20111202'
 '3K'         | '1%'      | '1/10W'  | '0603LF'  | 'EMPTY'  | 'CS23003F926'(!)        = 'End of Design' | 'Comp-Approve'     | 'CS23003F926'           | 'R0603'             | '(SMR0603AW)'                  | '3K'      | '1%'    | '1/10W'  | 'IO'       | 'RES CHIP 3K 1/10W +-1%(0603)'                     | 'CHIP0603'     | ''          | ''            | '20111202'
 '470'        | '5%'      | '1/10W'  | '0603LF'  | 'CHIP'   | 'CS14703J941'(!)        = 'End of Design' | 'Comp-Approve'     | 'CS14703J941'           | 'R0603'             | '(SMR0603AW)'                  | '470'     | '5%'    | '1/10W'  | 'DISCRETE' | 'RESISTOR CHIP 470 1/10W+-5%(0603)'                | 'CHIP0603'     | ''          | ''            | '20111207'
 '470'        | '5%'      | '1/10W'  | '0603LF'  | 'EMPTY'  | 'CS14703J941'(!)        = 'End of Design' | 'Comp-Approve'     | 'CS14703J941'           | 'R0603'             | '(SMR0603AW)'                  | '470'     | '5%'    | '1/10W'  | 'IO'       | 'RESISTOR CHIP 470 1/10W+-5%(0603)'                | 'CHIP0603'     | ''          | ''            | '20111207'
 '8.2K'       | '1%'      | '1/16W'  | '0402LF'  | 'CHIP'   | 'CS28202FB12'(!)        = 'End of Design' | 'Comp-Approve'     | 'CS28202FB12'           | 'R0402'             | '(R0402-0201)'                 | '8.2K'    | '1%'    | '1/16W'  | 'DISCRETE' | 'RES CHIP 8.2K 1/16W +-1%(0402)'                   | 'CHIP0402'     | ''          | ''            | '20111208'
 '8.2K'       | '1%'      | '1/16W'  | '0402LF'  | 'EMPTY'  | 'CS28202FB12'(!)        = 'End of Design' | 'Comp-Approve'     | 'CS28202FB12'           | 'R0402'             | '(R0402-0201)'                 | '8.2K'    | '1%'    | '1/16W'  | 'IO'       | 'RES CHIP 8.2K 1/16W +-1%(0402)'                   | 'CHIP0402'     | ''          | ''            | '20111208'
 '63.4K'      | '1%'      | '1/16W'  | '0402LF'  | 'CHIP'   | 'CS36342FB11'(!)        = 'End of Design' | 'Comp-Approve'     | 'CS36342FB11'           | 'R0402'             | '(R0402-0201)'                 | '63.4K'   | '1%'    | '1/16W'  | 'DISCRETE' | 'RES CHIP 63.4K 1/16W +-1% (0402)'                 | 'CHIP0402'     | ''          | ''            | '20111208'
 '63.4K'      | '1%'      | '1/16W'  | '0402LF'  | 'EMPTY'  | 'CS36342FB11'(!)        = 'End of Design' | 'Comp-Approve'     | 'CS36342FB11'           | 'R0402'             | '(R0402-0201)'                 | '63.4K'   | '1%'    | '1/16W'  | 'IO'       | 'RES CHIP 63.4K 1/16W +-1% (0402)'                 | 'CHIP0402'     | ''          | ''            | '20111208'
 '2K'         | '1%'      | '1/10W'  | '0603LF'  | 'CHIP'   | 'CS22003F915'(!)        = ''              | ''                 | 'CS22003F915'           | 'R0603'             | '(SMR0603AW)'                  | '2K'      | '1%'    | '1/10W'  | 'DISCRETE' | 'RES CHIP 2K 1/10W +-1%(0603)'                     | 'CHIP0603'     | ''          | ''            | '20111208'
 '2K'         | '1%'      | '1/10W'  | '0603LF'  | 'EMPTY'  | 'CS22003F915'(!)        = ''              | ''                 | 'CS22003F915'           | 'R0603'             | '(SMR0603AW)'                  | '2K'      | '1%'    | '1/10W'  | 'IO'       | 'RES CHIP 2K 1/10W +-1%(0603)'                     | 'CHIP0603'     | ''          | ''            | '20111208'
 '5.11'       | '1%'      | '1/16W'  | '0402LF'  | 'CHIP'   | 'CS-5112FB06'(!)        = 'End of Design' | 'Comp-Approve'     | 'CS-5112FB06'           | 'R0402'             | '(R0402-0201)'                 | '5.11'    | '1%'    | '1/16W'  | 'DISCRETE' | 'RES CHIP 5.11 1/16W +-1%(0402)'                   | 'CHIP0402'     | ''          | ''            | '20111209'
 '5.11'       | '1%'      | '1/16W'  | '0402LF'  | 'EMPTY'  | 'CS-5112FB06'(!)        = 'End of Design' | 'Comp-Approve'     | 'CS-5112FB06'           | 'R0402'             | '(R0402-0201)'                 | '5.11'    | '1%'    | '1/16W'  | 'IO'       | 'RES CHIP 5.11 1/16W +-1%(0402)'                   | 'CHIP0402'     | ''          | ''            | '20111209'
 '0.51'       | '1%'      | '1/16W'  | '0402LF'  | 'CHIP'   | 'CS+5102FB00'(!)        = ''              | ''                 | 'CS+5102FB00'           | 'R0402'             | '(R0402-0201)'                 | '0.51'    | '1%'    | '1/16W'  | 'DISCRETE' | 'RES CHIP 0.51 1/16W +-1%(0402)'                   | 'CHIP0402'     | ''          | ''            | '20111209'
 '0.51'       | '1%'      | '1/16W'  | '0402LF'  | 'EMPTY'  | 'CS+5102FB00'(!)        = ''              | ''                 | 'CS+5102FB00'           | 'R0402'             | '(R0402-0201)'                 | '0.51'    | '1%'    | '1/16W'  | 'IO'       | 'RES CHIP 0.51 1/16W +-1%(0402)'                   | 'CHIP0402'     | ''          | ''            | '20111209'
 '39K'        | '1%'      | '1/10W'  | '0603LF ' | 'CHIP'   | 'CS33903F912'(!)        = ''              | ''                 | 'CS33903F912'           | 'R0603'             | '(SMR0603AW)'                  | '39K'     | '1%'    | '1/10W'  | 'DISCRETE' | 'RESISTOR CHIP 39K 1/10W+-1%(0603)'                | 'CHIP0603'     | ''          | ''            | '20111209'
 '39K'        | '1%'      | '1/10W'  | '0603LF ' | 'EMPTY'  | 'CS33903F912'(!)        = ''              | ''                 | 'CS33903F912'           | 'R0603'             | '(SMR0603AW)'                  | '39K'     | '1%'    | '1/10W'  | 'IO'       | 'RESISTOR CHIP 39K 1/10W+-1%(0603)'                | 'CHIP0603'     | ''          | ''            | '20111209'
 '31.6'       | '1%'      | '1/16W'  | '0402LF'  | 'CHIP'   | 'CS03162FB00'(!)        = ''              | ''                 | 'CS03162FB00'           | 'R0402'             | '(R0402-0201)'                 | '31.6'    | '1%'    | '1/16W'  | 'DISCRETE' | 'RES CHIP 31.6 1/16W +-1%(0402)'                   | 'CHIP0402'     | ''          | ''            | '20111213'
 '31.6'       | '1%'      | '1/16W'  | '0402LF'  | 'EMPTY'  | 'CS03162FB00'(!)        = ''              | ''                 | 'CS03162FB00'           | 'R0402'             | '(R0402-0201)'                 | '31.6'    | '1%'    | '1/16W'  | 'IO'       | 'RES CHIP 31.6 1/16W +-1%(0402)'                   | 'CHIP0402'     | ''          | ''            | '20111213'
 '33.2'       | '1%'      | '1/16W'  | '0402LF'  | 'CHIP'   | 'CS03322FB34'(!)        = 'End of Design' | 'Comp-Approve'     | 'CS03322FB34'           | 'R0402'             | '(R0402-0201)'                 | '33.2'    | '1%'    | '1/16W'  | 'DISCRETE' | 'RES CHIP 33.2 1/16W +-1%(0402)'                   | 'CHIP0402'     | ''          | ''            | '20111213'
 '33.2'       | '1%'      | '1/16W'  | '0402LF'  | 'EMPTY'  | 'CS03322FB34'(!)        = 'End of Design' | 'Comp-Approve'     | 'CS03322FB34'           | 'R0402'             | '(R0402-0201)'                 | '33.2'    | '1%'    | '1/16W'  | 'IO'       | 'RES CHIP 33.2 1/16W +-1%(0402)'                   | 'CHIP0402'     | ''          | ''            | '20111213'
 '42.2'       | '1%'      | '1/16W'  | '0402LF'  | 'CHIP'   | 'CS04222FB00'(!)        = 'End of Design' | 'End of Life'      | 'CS04222FB00'           | 'R0402_EOL'         | '(R0402-0201)'                 | '42.2'    | '1%'    | '1/16W'  | 'DISCRETE' | 'RES CHIP 42.2 1/16W +-1%(0402)'                   | 'CHIP0402'     | ''          | ''            | '20111213'
 '42.2'       | '1%'      | '1/16W'  | '0402LF'  | 'EMPTY'  | 'CS04222FB00'(!)        = 'End of Design' | 'End of Life'      | 'CS04222FB00'           | 'R0402_EOL'         | '(R0402-0201)'                 | '42.2'    | '1%'    | '1/16W'  | 'IO'       | 'RES CHIP 42.2 1/16W +-1%(0402)'                   | 'CHIP0402'     | ''          | ''            | '20111213'
 '51.1'       | '1%'      | '1/16W'  | '0402LF'  | 'CHIP'   | 'CS05112FB11'(!)        = 'End of Design' | 'Comp-Approve'     | 'CS05112FB11'           | 'R0402'             | '(R0402-0201)'                 | '51.1'    | '1%'    | '1/16W'  | 'DISCRETE' | 'RESISTOR CHIP 51.1,1/16W,+-1%(0402)'              | 'CHIP0402'     | ''          | ''            | '20111213'
 '51.1'       | '1%'      | '1/16W'  | '0402LF'  | 'EMPTY'  | 'CS05112FB11'(!)        = 'End of Design' | 'Comp-Approve'     | 'CS05112FB11'           | 'R0402'             | '(R0402-0201)'                 | '51.1'    | '1%'    | '1/16W'  | 'IO'       | 'RESISTOR CHIP 51.1,1/16W,+-1%(0402)'              | 'CHIP0402'     | ''          | ''            | '20111213'
 '270'        | '5%'      | '1/16W'  | '0402LF'  | 'CHIP'   | 'CS12702JB14'(!)        = 'End of Design' | 'Comp-Approve'     | 'CS12702JB14'           | 'R0402'             | '(R0402-0201)'                 | '270'     | '5%'    | '1/16W'  | 'DISCRETE' | 'RES CHIP 270(1/16W,+-5%,0402)'                    | 'CHIP0402'     | ''          | ''            | '20111213'
 '270'        | '5%'      | '1/16W'  | '0402LF'  | 'EMPTY'  | 'CS12702JB14'(!)        = 'End of Design' | 'Comp-Approve'     | 'CS12702JB14'           | 'R0402'             | '(R0402-0201)'                 | '270'     | '5%'    | '1/16W'  | 'IO'       | 'RES CHIP 270(1/16W,+-5%,0402)'                    | 'CHIP0402'     | ''          | ''            | '20111213'
 '274'        | '1%'      | '1/16W'  | '0402LF'  | 'CHIP'   | 'CS12742FB02'(!)        = 'End of Design' | 'Comp-Approve'     | 'CS12742FB02'           | 'R0402'             | '(R0402-0201)'                 | '274'     | '1%'    | '1/16W'  | 'DISCRETE' | 'RES CHIP 274 1/16W +-1%(0402)'                    | 'CHIP0402'     | ''          | ''            | '20111213'
 '274'        | '1%'      | '1/16W'  | '0402LF'  | 'EMPTY'  | 'CS12742FB02'(!)        = 'End of Design' | 'Comp-Approve'     | 'CS12742FB02'           | 'R0402'             | '(R0402-0201)'                 | '274'     | '1%'    | '1/16W'  | 'IO'       | 'RES CHIP 274 1/16W +-1%(0402)'                    | 'CHIP0402'     | ''          | ''            | '20111213'
 '2.43K'      | '1%'      | '1/16W'  | '0402LF'  | 'CHIP'   | 'CS22432FB09'(!)        = 'End of Design' | 'Comp-Approve'     | 'CS22432FB09'           | 'R0402'             | '(R0402-0201)'                 | '2.43K'   | '1%'    | '1/16W'  | 'DISCRETE' | 'RES CHIP 2.43K 1/16W +-1%(0402)'                  | 'CHIP0402'     | ''          | ''            | '20111213'
 '2.43K'      | '1%'      | '1/16W'  | '0402LF'  | 'EMPTY'  | 'CS22432FB09'(!)        = 'End of Design' | 'Comp-Approve'     | 'CS22432FB09'           | 'R0402'             | '(R0402-0201)'                 | '2.43K'   | '1%'    | '1/16W'  | 'IO'       | 'RES CHIP 2.43K 1/16W +-1%(0402)'                  | 'CHIP0402'     | ''          | ''            | '20111213'
 '27.4K'      | '1%'      | '1/10W'  | '0603LF'  | 'CHIP'   | 'CS32743F929'(!)        = ''              | ''                 | 'CS32743F929'           | 'R0603'             | '(SMR0603AW)'                  | '27.4K'   | '1%'    | '1/10W'  | 'DISCRETE' | 'RES CHIP 27.4K 1/10W +-1%(0603)'                  | 'CHIP0603'     | ''          | ''            | '20111213'
 '27.4K'      | '1%'      | '1/10W'  | '0603LF'  | 'EMPTY'  | 'CS32743F929'(!)        = ''              | ''                 | 'CS32743F929'           | 'R0603'             | '(SMR0603AW)'                  | '27.4K'   | '1%'    | '1/10W'  | 'IO'       | 'RES CHIP 27.4K 1/10W +-1%(0603)'                  | 'CHIP0603'     | ''          | ''            | '20111213'
 '48.7K'      | '1%'      | '1/16W'  | '0402LF'  | 'CHIP'   | 'CS34872FB17'(!)        = 'End of Design' | 'Comp-Approve'     | 'CS34872FB17'           | 'R0402'             | '(R0402-0201)'                 | '48.7K'   | '1%'    | '1/16W'  | 'DISCRETE' | 'RES CHIP 48.7K 1/16W +-1%(0402)'                  | 'CHIP0402'     | ''          | ''            | '20111213'
 '48.7K'      | '1%'      | '1/16W'  | '0402LF'  | 'EMPTY'  | 'CS34872FB17'(!)        = 'End of Design' | 'Comp-Approve'     | 'CS34872FB17'           | 'R0402'             | '(R0402-0201)'                 | '48.7K'   | '1%'    | '1/16W'  | 'IO'       | 'RES CHIP 48.7K 1/16W +-1%(0402)'                  | 'CHIP0402'     | ''          | ''            | '20111213'
 '220K'       | '5%'      | '1/16W'  | '0402LF'  | 'CHIP'   | 'CS42202JB11'(!)        = 'End of Design' | 'Comp-Approve'     | 'CS42202JB11'           | 'R0402'             | '(R0402-0201)'                 | '220K'    | '5%'    | '1/16W'  | 'DISCRETE' | 'RES CHIP 220K 1/16W+-5%(0402)'                    | 'CHIP0402'     | ''          | ''            | '20111213'
 '220K'       | '5%'      | '1/16W'  | '0402LF'  | 'EMPTY'  | 'CS42202JB11'(!)        = 'End of Design' | 'Comp-Approve'     | 'CS42202JB11'           | 'R0402'             | '(R0402-0201)'                 | '220K'    | '5%'    | '1/16W'  | 'IO'       | 'RES CHIP 220K 1/16W+-5%(0402)'                    | 'CHIP0402'     | ''          | ''            | '20111213'
 '390K'       | '5%'      | '1/16W'  | '0402LF'  | 'CHIP'   | 'CS43902JB10'(!)        = 'End of Design' | 'Comp-Approve'     | 'CS43902JB10'           | 'R0402'             | '(R0402-0201)'                 | '390K'    | '5%'    | '1/16W'  | 'DISCRETE' | 'RES CHIP 390K(1/16W +-5% 0402)'                   | 'CHIP0402'     | ''          | ''            | '20111213'
 '390K'       | '5%'      | '1/16W'  | '0402LF'  | 'EMPTY'  | 'CS43902JB10'(!)        = 'End of Design' | 'Comp-Approve'     | 'CS43902JB10'           | 'R0402'             | '(R0402-0201)'                 | '390K'    | '5%'    | '1/16W'  | 'IO'       | 'RES CHIP 390K(1/16W +-5% 0402)'                   | 'CHIP0402'     | ''          | ''            | '20111213'
 '0.01'       | '5%'      | '3/4W'   | '2010LF'  | 'CHIP'   | 'CS+010BFJ28'(!)        = 'End of Design' | 'Comp-Approve'     | 'CS+010BFJ28'           | 'R2010'             | '(SMR2010AW)'                  | '0.01'    | '5%'    | '3/4W'   | 'DISCRETE' | 'RES CHIP 0.01 3/4W +-1%(2010)'                    | 'CHIP2010'     | ''          | ''            | '20111215'
 '0.01'       | '5%'      | '3/4W'   | '2010LF'  | 'EMPTY'  | 'CS+010BFJ28'(!)        = 'End of Design' | 'Comp-Approve'     | 'CS+010BFJ28'           | 'R2010'             | '(SMR2010AW)'                  | '0.01'    | '5%'    | '3/4W'   | 'IO'       | 'RES CHIP 0.01 3/4W +-1%(2010)'                    | 'CHIP2010'     | ''          | ''            | '20111215'
 '5.11'       | '1%'      | '1/4W'   | '1206LF'  | 'CHIP'   | 'CS-5116F208'(!)        = ''              | ''                 | 'CS-5116F208'           | 'R1206'             | '(SMR1206AW)'                  | '5.11'    | '1%'    | '1/4W'   | 'DISCRETE' | 'RES CHIP 5.11 1/4W +-1%(1206)'                    | 'CHIP1206'     | ''          | ''            | '20111219'
 '5.11'       | '1%'      | '1/4W'   | '1206LF'  | 'EMPTY'  | 'CS-5116F208'(!)        = ''              | ''                 | 'CS-5116F208'           | 'R1206'             | '(SMR1206AW)'                  | '5.11'    | '1%'    | '1/4W'   | 'IO'       | 'RES CHIP 5.11 1/4W +-1%(1206)'                    | 'CHIP1206'     | ''          | ''            | '20111219'
 '20'         | '1%'      | '1/4W'   | '1206LF'  | 'CHIP'   | 'CS02006F200'(!)        = ''              | ''                 | 'CS02006F200'           | 'R1206'             | '(SMR1206AW)'                  | '20'      | '1%'    | '1/4W'   | 'DISCRETE' | 'RES CHIP 20 1/4 +-1%(1206)'                       | 'CHIP1206'     | ''          | ''            | '20111219'
 '20'         | '1%'      | '1/4W'   | '1206LF'  | 'EMPTY'  | 'CS02006F200'(!)        = ''              | ''                 | 'CS02006F200'           | 'R1206'             | '(SMR1206AW)'                  | '20'      | '1%'    | '1/4W'   | 'IO'       | 'RES CHIP 20 1/4 +-1%(1206)'                       | 'CHIP1206'     | ''          | ''            | '20111219'
 '121'        | '1%'      | '1/16W'  | '0402LF'  | 'CHIP'   | 'CS11212FB24'(!)        = 'End of Design' | 'Comp-Approve'     | 'CS11212FB24'           | 'R0402'             | '(R0402-0201)'                 | '121'     | '1%'    | '1/16W'  | 'DISCRETE' | 'RES CHIP 121 1/16W +-1%(0402)'                    | 'CHIP0402'     | ''          | ''            | '20111219'
 '121'        | '1%'      | '1/16W'  | '0402LF'  | 'EMPTY'  | 'CS11212FB24'(!)        = 'End of Design' | 'Comp-Approve'     | 'CS11212FB24'           | 'R0402'             | '(R0402-0201)'                 | '121'     | '1%'    | '1/16W'  | 'IO'       | 'RES CHIP 121 1/16W +-1%(0402)'                    | 'CHIP0402'     | ''          | ''            | '20111219'
 '11.5K'      | '1%'      | '1/16W'  | '0402LF'  | 'CHIP'   | 'CS31152FB14'(!)        = 'End of Design' | 'Comp-Approve'     | 'CS31152FB14'           | 'R0402'             | '(R0402-0201)'                 | '11.5K'   | '1%'    | '1/16W'  | 'DISCRETE' | 'RES CHIP 11.5K 1/16W +-1%( 0402)'                 | 'CHIP0402'     | ''          | ''            | '20111219'
 '11.5K'      | '1%'      | '1/16W'  | '0402LF'  | 'EMPTY'  | 'CS31152FB14'(!)        = 'End of Design' | 'Comp-Approve'     | 'CS31152FB14'           | 'R0402'             | '(R0402-0201)'                 | '11.5K'   | '1%'    | '1/16W'  | 'IO'       | 'RES CHIP 11.5K 1/16W +-1%( 0402)'                 | 'CHIP0402'     | ''          | ''            | '20111219'
 '0.003'      | '1%'      | '1W'     | '2512LF'  | 'CHIP'   | 'CS+0038F128'(!)        = 'End of Design' | 'Comp-Approve'     | 'CS+0038F128'           | 'R2512'             | '(SMR2512AW)'                  | '0.003'   | '1%'    | '1W'     | 'DISCRETE' | 'RES CHIP 0.003 1W +-1%(2512)'                     | 'CHIP2512'     | ''          | ''            | '20111219'
 '0.003'      | '1%'      | '1W'     | '2512LF'  | 'EMPTY'  | 'CS+0038F128'(!)        = 'End of Design' | 'Comp-Approve'     | 'CS+0038F128'           | 'R2512'             | '(SMR2512AW)'                  | '0.003'   | '1%'    | '1W'     | 'IO'       | 'RES CHIP 0.003 1W +-1%(2512)'                     | 'CHIP2512'     | ''          | ''            | '20111219'
 '28K'        | '1%'      | '1/16W'  | '0402LF'  | 'CHIP'   | 'CS32802FB10'(!)        = 'End of Design' | 'Comp-Approve'     | 'CS32802FB10'           | 'R0402'             | '(R0402-0201)'                 | '28K'     | '1%'    | '1/16W'  | 'DISCRETE' | 'RES CHIP 28K 1/16W +-1%(0402)'                    | 'CHIP0402'     | ''          | ''            | '20111219'
 '28K'        | '1%'      | '1/16W'  | '0402LF'  | 'EMPTY'  | 'CS32802FB10'(!)        = 'End of Design' | 'Comp-Approve'     | 'CS32802FB10'           | 'R0402'             | '(R0402-0201)'                 | '28K'     | '1%'    | '1/16W'  | 'IO'       | 'RES CHIP 28K 1/16W +-1%(0402)'                    | 'CHIP0402'     | ''          | ''            | '20111219'
 '0.01'       | '1%'      | '1W'     | '2512LF'  | 'CHIP'   | 'CS+0108F128'(!)        = 'End of Design' | 'Comp-Release Qty' | 'CS+0108F128'           | 'R2512'             | '(SMR2512AW)'                  | '0.01'    | '1%'    | '1W'     | 'DISCRETE' | 'RES CHIP 0.01 1W +-1%(2512)'                      | 'CHIP2512'     | ''          | ''            | '20111219'
 '0.01'       | '1%'      | '1W'     | '2512LF'  | 'EMPTY'  | 'CS+0108F128'(!)        = 'End of Design' | 'Comp-Release Qty' | 'CS+0108F128'           | 'R2512'             | '(SMR2512AW)'                  | '0.01'    | '1%'    | '1W'     | 'IO'       | 'RES CHIP 0.01 1W +-1%(2512)'                      | 'CHIP2512'     | ''          | ''            | '20111219'
 '100K'       | '1%'      | '1/10W'  | '0603LF'  | 'CHIP'   | 'CS41003F932'(!)        = ''              | ''                 | 'CS41003F932'           | 'R0603'             | '(SMR0603AW)'                  | '100K'    | '1%'    | '1/10W'  | 'DISCRETE' | 'RESISTOR CHIP 100K 1/10W+-1%(0603)'               | 'CHIP0603'     | ''          | ''            | '20111219'
 '100K'       | '1%'      | '1/10W'  | '0603LF'  | 'EMPTY'  | 'CS41003F932'(!)        = ''              | ''                 | 'CS41003F932'           | 'R0603'             | '(SMR0603AW)'                  | '100K'    | '1%'    | '1/10W'  | 'IO'       | 'RESISTOR CHIP 100K 1/10W+-1%(0603)'               | 'CHIP0603'     | ''          | ''            | '20111219'
 '475'        | '1%'      | '1/10W'  | '0603LF'  | 'CHIP'   | 'CS14753F933'(!)        = ''              | ''                 | 'CS14753F933'           | 'R0603'             | '(SMR0603AW)'                  | '475'     | '1%'    | '1/10W'  | 'DISCRETE' | 'RESISTOR CHIP 475 1/10W(+-1%.0603)'               | 'CHIP0603'     | ''          | ''            | '20111223'
 '475'        | '1%'      | '1/10W'  | '0603LF'  | 'EMPTY'  | 'CS14753F933'(!)        = ''              | ''                 | 'CS14753F933'           | 'R0603'             | '(SMR0603AW)'                  | '475'     | '1%'    | '1/10W'  | 'IO'       | 'RESISTOR CHIP 475 1/10W(+-1%.0603)'               | 'CHIP0603'     | ''          | ''            | '20111223'
 '28K'        | '1%'      | '1/10W'  | '0603LF'  | 'CHIP'   | 'CS32803F932'(!)        = ''              | ''                 | 'CS32803F932'           | 'R0603'             | '(SMR0603AW)'                  | '28K'     | '1%'    | '1/10W'  | 'DISCRETE' | 'RES CHIP 28K 1/10W+-1%(0603)'                     | 'CHIP0603'     | ''          | ''            | '20111223'
 '28K'        | '1%'      | '1/10W'  | '0603LF'  | 'EMPTY'  | 'CS32803F932'(!)        = ''              | ''                 | 'CS32803F932'           | 'R0603'             | '(SMR0603AW)'                  | '28K'     | '1%'    | '1/10W'  | 'IO'       | 'RES CHIP 28K 1/10W+-1%(0603)'                     | 'CHIP0603'     | ''          | ''            | '20111223'
 '33'         | '1%'      | '1/10W'  | '0603LF'  | 'CHIP'   | 'CS03303F915'(!)        = ''              | ''                 | 'CS03303F915'           | 'R0603'             | '(SMR0603AW)'                  | '33'      | '1%'    | '1/10W'  | 'DISCRETE' | 'RES CHIP 33 1/10W +-1%(0603)'                     | 'CHIP0603'     | ''          | ''            | '20111223'
 '33'         | '1%'      | '1/10W'  | '0603LF'  | 'EMPTY'  | 'CS03303F915'(!)        = ''              | ''                 | 'CS03303F915'           | 'R0603'             | '(SMR0603AW)'                  | '33'      | '1%'    | '1/10W'  | 'IO'       | 'RES CHIP 33 1/10W +-1%(0603)'                     | 'CHIP0603'     | ''          | ''            | '20111223'
 '536'        | '1%'      | '1/16W'  | '0402LF'  | 'CHIP'   | 'CS15362FB13'(!)        = 'End of Design' | 'Comp-Approve'     | 'CS15362FB13'           | 'R0402'             | '(R0402-0201)'                 | '536'     | '1%'    | '1/16W'  | 'DISCRETE' | 'RES CHIP 536 1/16W.+-1%(0402)'                    | 'CHIP0402'     | ''          | ''            | '20111223'
 '536'        | '1%'      | '1/16W'  | '0402LF'  | 'EMPTY'  | 'CS15362FB13'(!)        = 'End of Design' | 'Comp-Approve'     | 'CS15362FB13'           | 'R0402'             | '(R0402-0201)'                 | '536'     | '1%'    | '1/16W'  | 'IO'       | 'RES CHIP 536 1/16W.+-1%(0402)'                    | 'CHIP0402'     | ''          | ''            | '20111223'
 '27.4K'      | '1%'      | '1/16W'  | '0402LF'  | 'CHIP'   | 'CS32742FB14'(!)        = 'End of Design' | 'Comp-Approve'     | 'CS32742FB14'           | 'R0402'             | '(R0402-0201)'                 | '27.4K'   | '1%'    | '1/16W'  | 'DISCRETE' | 'RES CHIP 27.4K 1/16W +-1% (0402)'                 | 'CHIP0402'     | ''          | ''            | '20111223'
 '27.4K'      | '1%'      | '1/16W'  | '0402LF'  | 'EMPTY'  | 'CS32742FB14'(!)        = 'End of Design' | 'Comp-Approve'     | 'CS32742FB14'           | 'R0402'             | '(R0402-0201)'                 | '27.4K'   | '1%'    | '1/16W'  | 'IO'       | 'RES CHIP 27.4K 1/16W +-1% (0402)'                 | 'CHIP0402'     | ''          | ''            | '20111223'
 '73.2K'      | '1%'      | '1/16W'  | '0402LF'  | 'CHIP'   | 'CS37322FB14'(!)        = 'End of Design' | 'Comp-Approve'     | 'CS37322FB14'           | 'R0402'             | '(R0402-0201)'                 | '73.2K'   | '1%'    | '1/16W'  | 'DISCRETE' | 'RES CHIP 73.2K 1/16W +-1%(0402)'                  | 'CHIP0402'     | ''          | ''            | '20111223'
 '73.2K'      | '1%'      | '1/16W'  | '0402LF'  | 'EMPTY'  | 'CS37322FB14'(!)        = 'End of Design' | 'Comp-Approve'     | 'CS37322FB14'           | 'R0402'             | '(R0402-0201)'                 | '73.2K'   | '1%'    | '1/16W'  | 'IO'       | 'RES CHIP 73.2K 1/16W +-1%(0402)'                  | 'CHIP0402'     | ''          | ''            | '20111223'
 '1K'         | '1%'      | '1/8W'   | '0805LF'  | 'CHIP'   | 'CS21004FA10'(!)        = ''              | ''                 | 'CS21004FA10'           | 'R0805'             | '(SMR0805AW)'                  | '1K'      | '1%'    | '1/8W'   | 'DISCRETE' | 'RES CHIP 1K 1/8W+-1%(0805)L-F'                    | 'CHIP0805'     | ''          | ''            | '20111227'
 '1K'         | '1%'      | '1/8W'   | '0805LF'  | 'EMPTY'  | 'CS21004FA10'(!)        = ''              | ''                 | 'CS21004FA10'           | 'R0805'             | '(SMR0805AW)'                  | '1K'      | '1%'    | '1/8W'   | 'IO'       | 'RES CHIP 1K 1/8W+-1%(0805)L-F'                    | 'CHIP0805'     | ''          | ''            | '20111227'
 '220'        | '1%'      | '1/10W'  | '0603LF'  | 'CHIP'   | 'CS12203F911'(!)        = 'End of Design' | 'Comp-Approve'     | 'CS12203F911'           | 'R0603'             | '(SMR0603AW)'                  | '220'     | '1%'    | '1/10W'  | 'DISCRETE' | 'RESISTOR CHIP 220 1/10W.+-1%(0603)'               | 'CHIP0603'     | ''          | ''            | '20111227'
 '220'        | '1%'      | '1/10W'  | '0603LF'  | 'EMPTY'  | 'CS12203F911'(!)        = 'End of Design' | 'Comp-Approve'     | 'CS12203F911'           | 'R0603'             | '(SMR0603AW)'                  | '220'     | '1%'    | '1/10W'  | 'IO'       | 'RESISTOR CHIP 220 1/10W.+-1%(0603)'               | 'CHIP0603'     | ''          | ''            | '20111227'
 '2.49K'      | '1%'      | '1/10W'  | '0603LF'  | 'CHIP'   | 'CS22493F945'(!)        = ''              | ''                 | 'CS22493F945'           | 'R0603'             | '(SMR0603AW)'                  | '2.49K'   | '1%'    | '1/10W'  | 'DISCRETE' | 'RES CHIP 2.49K 1/10W +-1%(0603)'                  | 'CHIP0603'     | ''          | ''            | '20111227'
 '2.49K'      | '1%'      | '1/10W'  | '0603LF'  | 'EMPTY'  | 'CS22493F945'(!)        = ''              | ''                 | 'CS22493F945'           | 'R0603'             | '(SMR0603AW)'                  | '2.49K'   | '1%'    | '1/10W'  | 'IO'       | 'RES CHIP 2.49K 1/10W +-1%(0603)'                  | 'CHIP0603'     | ''          | ''            | '20111227'
 '93.1'       | '1%'      | '1/16W'  | '0402LF'  | 'CHIP'   | 'CS09312FB00'(!)        = 'End of Design' | 'Comp-Approve'     | 'CS09312FB00'           | 'R0402'             | '(R0402-0201)'                 | '93.1'    | '1%'    | '1/16W'  | 'DISCRETE' | 'RES CHIP 93.1 1/16W +-1%(0402)'                   | 'CHIP0402'     | ''          | ''            | '20111230'
 '93.1'       | '1%'      | '1/16W'  | '0402LF'  | 'EMPTY'  | 'CS09312FB00'(!)        = 'End of Design' | 'Comp-Approve'     | 'CS09312FB00'           | 'R0402'             | '(R0402-0201)'                 | '93.1'    | '1%'    | '1/16W'  | 'IO'       | 'RES CHIP 93.1 1/16W +-1%(0402)'                   | 'CHIP0402'     | ''          | ''            | '20111230'
 '536'        | '1%'      | '1/8W'   | '0805LF'  | 'CHIP'   | 'CS15364FA00'(!)        = ''              | ''                 | 'CS15364FA00'           | 'R0805'             | '(SMR0805AW)'                  | '536'     | '1%'    | '1/8W'   | 'DISCRETE' | 'RES CHIP 536 1/8W(+-1%,0805)'                     | 'CHIP0805'     | ''          | ''            | '20111230'
 '536'        | '1%'      | '1/8W'   | '0805LF'  | 'EMPTY'  | 'CS15364FA00'(!)        = ''              | ''                 | 'CS15364FA00'           | 'R0805'             | '(SMR0805AW)'                  | '536'     | '1%'    | '1/8W'   | 'IO'       | 'RES CHIP 536 1/8W(+-1%,0805)'                     | 'CHIP0805'     | ''          | ''            | '20111230'
 '24K'        | '1%'      | '1/16W'  | '0402LF'  | 'CHIP'   | 'CS32402FB15'(!)        = 'End of Design' | 'Comp-Approve'     | 'CS32402FB15'           | 'R0402'             | '(R0402-0201)'                 | '24K'     | '1%'    | '1/16W'  | 'DISCRETE' | 'RES CHIP 24K 1/16W +-1%(0402)'                    | 'CHIP0402'     | ''          | ''            | '20111230'
 '24K'        | '1%'      | '1/16W'  | '0402LF'  | 'EMPTY'  | 'CS32402FB15'(!)        = 'End of Design' | 'Comp-Approve'     | 'CS32402FB15'           | 'R0402'             | '(R0402-0201)'                 | '24K'     | '1%'    | '1/16W'  | 'IO'       | 'RES CHIP 24K 1/16W +-1%(0402)'                    | 'CHIP0402'     | ''          | ''            | '20111230'
 '11.8K'      | '1%'      | '1/10W'  | '0603LF'  | 'CHIP'   | 'CS31183F914'(!)        = ''              | ''                 | 'CS31183F914'           | 'R0603'             | '(SMR0603AW)'                  | '11.8K'   | '1%'    | '1/10W'  | 'DISCRETE' | 'RES CHIP 11.8K 1/10W +-1%(0603)'                  | 'CHIP0603'     | ''          | ''            | '20111230'
 '11.8K'      | '1%'      | '1/10W'  | '0603LF'  | 'EMPTY'  | 'CS31183F914'(!)        = ''              | ''                 | 'CS31183F914'           | 'R0603'             | '(SMR0603AW)'                  | '11.8K'   | '1%'    | '1/10W'  | 'IO'       | 'RES CHIP 11.8K 1/10W +-1%(0603)'                  | 'CHIP0603'     | ''          | ''            | '20111230'
 '102K'       | '0.50%'   | '1/10W'  | '0603LF'  | 'CHIP'   | 'CS41023D900'(!)        = ''              | ''                 | 'CS41023D900'           | 'R0603'             | '(SMR0603AW)'                  | '102K'    | '0.50%' | '1/10W'  | 'DISCRETE' | 'RES CHIP 102K 1/10W +-0.5%(0603)'                 | 'CHIP0603'     | ''          | ''            | '20111230'
 '102K'       | '0.50%'   | '1/10W'  | '0603LF'  | 'EMPTY'  | 'CS41023D900'(!)        = ''              | ''                 | 'CS41023D900'           | 'R0603'             | '(SMR0603AW)'                  | '102K'    | '0.50%' | '1/10W'  | 'IO'       | 'RES CHIP 102K 1/10W +-0.5%(0603)'                 | 'CHIP0603'     | ''          | ''            | '20111230'
 '442'        | '1%'      | '1/10W'  | '0603LF'  | 'CHIP'   | 'CS14423F939'(!)        = ''              | ''                 | 'CS14423F939'           | 'R0603'             | '(SMR0603AW)'                  | '442'     | '1%'    | '1/10W'  | 'DISCRETE' | 'RES CHIP 442 1/10W +-1%(0603)EP'                  | 'CHIP0603'     | ''          | ''            | '20111230'
 '442'        | '1%'      | '1/10W'  | '0603LF'  | 'EMPTY'  | 'CS14423F939'(!)        = ''              | ''                 | 'CS14423F939'           | 'R0603'             | '(SMR0603AW)'                  | '442'     | '1%'    | '1/10W'  | 'IO'       | 'RES CHIP 442 1/10W +-1%(0603)EP'                  | 'CHIP0603'     | ''          | ''            | '20111230'
 '90.9K'      | '1%'      | '1/10W'  | '0603LF'  | 'CHIP'   | 'CS39093F917'(!)        = 'End of Design' | 'Comp-Approve'     | 'CS39093F917'           | 'R0603'             | '(SMR0603AW)'                  | '90.9K'   | '1%'    | '1/10W'  | 'DISCRETE' | 'RES CHIP 90.9K 1/10W+-1%(0603)'                   | 'CHIP0603'     | ''          | ''            | '20120109'
 '90.9K'      | '1%'      | '1/10W'  | '0603LF'  | 'EMPTY'  | 'CS39093F917'(!)        = 'End of Design' | 'Comp-Approve'     | 'CS39093F917'           | 'R0603'             | '(SMR0603AW)'                  | '90.9K'   | '1%'    | '1/10W'  | 'IO'       | 'RES CHIP 90.9K 1/10W+-1%(0603)'                   | 'CHIP0603'     | ''          | ''            | '20120109'
 '91K'        | '1%'      | '1/16W'  | '0402LF'  | 'CHIP'   | 'CS39102FB05'(!)        = 'End of Design' | 'Comp-Approve'     | 'CS39102FB05'           | 'R0402'             | '(R0402-0201)'                 | '91K'     | '1%'    | '1/16W'  | 'DISCRETE' | 'RES CHIP 91K 1/16W +-1%(0402)'                    | 'CHIP0402'     | ''          | ''            | '20120109'
 '91K'        | '1%'      | '1/16W'  | '0402LF'  | 'EMPTY'  | 'CS39102FB05'(!)        = 'End of Design' | 'Comp-Approve'     | 'CS39102FB05'           | 'R0402'             | '(R0402-0201)'                 | '91K'     | '1%'    | '1/16W'  | 'IO'       | 'RES CHIP 91K 1/16W +-1%(0402)'                    | 'CHIP0402'     | ''          | ''            | '20120109'
 '2.1K'       | '1%'      | '1/16W'  | '0402LF'  | 'CHIP'   | 'CS22102FB12'(!)        = 'End of Design' | 'Comp-Approve'     | 'CS22102FB12'           | 'R0402'             | '(R0402-0201)'                 | '2.1K'    | '1%'    | '1/16W'  | 'DISCRETE' | 'RES CHIP 2.1K 1/16W +-1%(0402)'                   | 'CHIP0402'     | ''          | ''            | '20120110'
 '2.1K'       | '1%'      | '1/16W'  | '0402LF'  | 'EMPTY'  | 'CS22102FB12'(!)        = 'End of Design' | 'Comp-Approve'     | 'CS22102FB12'           | 'R0402'             | '(R0402-0201)'                 | '2.1K'    | '1%'    | '1/16W'  | 'IO'       | 'RES CHIP 2.1K 1/16W +-1%(0402)'                   | 'CHIP0402'     | ''          | ''            | '20120110'
 '210'        | '1%'      | '1/16W'  | '0402LF'  | 'CHIP'   | 'CS12102FB11'(!)        = 'End of Design' | 'Comp-Approve'     | 'CS12102FB11'           | 'R0402'             | '(R0402-0201)'                 | '210'     | '1%'    | '1/16W'  | 'DISCRETE' | 'RES CHIP 210 1/16W 1%(0402)'                      | 'CHIP0402'     | ''          | ''            | '20120113'
 '210'        | '1%'      | '1/16W'  | '0402LF'  | 'EMPTY'  | 'CS12102FB11'(!)        = 'End of Design' | 'Comp-Approve'     | 'CS12102FB11'           | 'R0402'             | '(R0402-0201)'                 | '210'     | '1%'    | '1/16W'  | 'IO'       | 'RES CHIP 210 1/16W 1%(0402)'                      | 'CHIP0402'     | ''          | ''            | '20120113'
 '44.2K'      | '1%'      | '1/16W'  | '0402LF'  | 'CHIP'   | 'CS34422FB00'(!)        = 'End of Design' | 'Comp-Approve'     | 'CS34422FB00'           | 'R0402'             | '(R0402-0201)'                 | '44.2K'   | '1%'    | '1/16W'  | 'DISCRETE' | 'RES CHIP 44.2K 1/16W +-1%(0402)'                  | 'CHIP0402'     | ''          | ''            | '20120114'
 '44.2K'      | '1%'      | '1/16W'  | '0402LF'  | 'EMPTY'  | 'CS34422FB00'(!)        = 'End of Design' | 'Comp-Approve'     | 'CS34422FB00'           | 'R0402'             | '(R0402-0201)'                 | '44.2K'   | '1%'    | '1/16W'  | 'IO'       | 'RES CHIP 44.2K 1/16W +-1%(0402)'                  | 'CHIP0402'     | ''          | ''            | '20120114'
 '174K'       | '1%'      | '1/16W'  | '0402LF'  | 'CHIP'   | 'CS41742FB13'(!)        = 'End of Design' | 'Comp-Approve'     | 'CS41742FB13'           | 'R0402'             | '(R0402-0201)'                 | '174K'    | '1%'    | '1/16W'  | 'DISCRETE' | 'RES CHIP 174K 1/16W +-1%(0402)'                   | 'CHIP0402'     | ''          | ''            | '20120114'
 '174K'       | '1%'      | '1/16W'  | '0402LF'  | 'EMPTY'  | 'CS41742FB13'(!)        = 'End of Design' | 'Comp-Approve'     | 'CS41742FB13'           | 'R0402'             | '(R0402-0201)'                 | '174K'    | '1%'    | '1/16W'  | 'IO'       | 'RES CHIP 174K 1/16W +-1%(0402)'                   | 'CHIP0402'     | ''          | ''            | '20120114'
 '1'          | '5%'      | '1/16W'  | '0402LF'  | 'CHIP'   | 'CS-1002JB17'(!)        = 'End of Design' | 'Comp-Approve'     | 'CS-1002JB17'           | 'R0402'             | '(R0402-0201)'                 | '1'       | '5%'    | '1/16W'  | 'DISCRETE' | 'RES CHIP 1 1/16W +-5%(0402)'                      | 'CHIP0402'     | ''          | ''            | '20120114'
 '1'          | '5%'      | '1/16W'  | '0402LF'  | 'EMPTY'  | 'CS-1002JB17'(!)        = 'End of Design' | 'Comp-Approve'     | 'CS-1002JB17'           | 'R0402'             | '(R0402-0201)'                 | '1'       | '5%'    | '1/16W'  | 'IO'       | 'RES CHIP 1 1/16W +-5%(0402)'                      | 'CHIP0402'     | ''          | ''            | '20120114'
 '56.2'       | '1%'      | '1/4W'   | '1206LF'  | 'CHIP'   | 'CS05626F216'(!)        = ''              | ''                 | 'CS05626F216'           | 'R1206'             | '(SMR1206AW)'                  | '56.2'    | '1%'    | '1/4W'   | 'DISCRETE' | 'RESISTOR CHIP 56.2 1/4W +-1%(1206)EP'             | 'CHIP1206'     | ''          | ''            | '20120114'
 '56.2'       | '1%'      | '1/4W'   | '1206LF'  | 'EMPTY'  | 'CS05626F216'(!)        = ''              | ''                 | 'CS05626F216'           | 'R1206'             | '(SMR1206AW)'                  | '56.2'    | '1%'    | '1/4W'   | 'IO'       | 'RESISTOR CHIP 56.2 1/4W +-1%(1206)EP'             | 'CHIP1206'     | ''          | ''            | '20120114'
 '16.9K'      | '1%'      | '1/16W'  | '0402LF'  | 'CHIP'   | 'CS31692FB11'(!)        = 'End of Design' | 'Comp-Approve'     | 'CS31692FB11'           | 'R0402'             | '(R0402-0201)'                 | '16.9K'   | '1%'    | '1/16W'  | 'DISCRETE' | 'RES CHIP 16.9K 1/16W +-1% (0402)'                 | 'CHIP0402'     | ''          | ''            | '20120119'
 '16.9K'      | '1%'      | '1/16W'  | '0402LF'  | 'EMPTY'  | 'CS31692FB11'(!)        = 'End of Design' | 'Comp-Approve'     | 'CS31692FB11'           | 'R0402'             | '(R0402-0201)'                 | '16.9K'   | '1%'    | '1/16W'  | 'IO'       | 'RES CHIP 16.9K 1/16W +-1% (0402)'                 | 'CHIP0402'     | ''          | ''            | '20120119'
 '191K'       | '1%'      | '1/16W'  | '0402LF'  | 'CHIP'   | 'CS41912FB17'(!)        = 'End of Design' | 'Comp-Approve'     | 'CS41912FB17'           | 'R0402'             | '(R0402-0201)'                 | '191K'    | '1%'    | '1/16W'  | 'DISCRETE' | 'RES CHIP 191K 1/16W +-1%(0402)'                   | 'CHIP0402'     | ''          | ''            | '20120119'
 '191K'       | '1%'      | '1/16W'  | '0402LF'  | 'EMPTY'  | 'CS41912FB17'(!)        = 'End of Design' | 'Comp-Approve'     | 'CS41912FB17'           | 'R0402'             | '(R0402-0201)'                 | '191K'    | '1%'    | '1/16W'  | 'IO'       | 'RES CHIP 191K 1/16W +-1%(0402)'                   | 'CHIP0402'     | ''          | ''            | '20120119'
 '154K'       | '1%'      | '1/16W'  | '0402LF'  | 'CHIP'   | 'CS41542FB16'(!)        = 'End of Design' | 'Comp-Approve'     | 'CS41542FB16'           | 'R0402'             | '(R0402-0201)'                 | '154K'    | '1%'    | '1/16W'  | 'DISCRETE' | 'RES CHIP 154K 1/16W +1%(0402)'                    | 'CHIP0402'     | ''          | ''            | '20120119'
 '154K'       | '1%'      | '1/16W'  | '0402LF'  | 'EMPTY'  | 'CS41542FB16'(!)        = 'End of Design' | 'Comp-Approve'     | 'CS41542FB16'           | 'R0402'             | '(R0402-0201)'                 | '154K'    | '1%'    | '1/16W'  | 'IO'       | 'RES CHIP 154K 1/16W +1%(0402)'                    | 'CHIP0402'     | ''          | ''            | '20120119'
 '4.99'       | '1%'      | '1/10W'  | '0603LF'  | 'CHIP'   | 'CS-4993F913'(!)        = ''              | ''                 | 'CS-4993F913'           | 'R0603'             | '(SMR0603AW)'                  | '4.99'    | '1%'    | '1/10W'  | 'DISCRETE' | 'RES CHIP 4.99 1/10W +-1%(0603)'                   | 'CHIP0603'     | ''          | ''            | '20120119'
 '4.99'       | '1%'      | '1/10W'  | '0603LF'  | 'EMPTY'  | 'CS-4993F913'(!)        = ''              | ''                 | 'CS-4993F913'           | 'R0603'             | '(SMR0603AW)'                  | '4.99'    | '1%'    | '1/10W'  | 'IO'       | 'RES CHIP 4.99 1/10W +-1%(0603)'                   | 'CHIP0603'     | ''          | ''            | '20120119'
 '249K'       | '1%'      | '1/16W'  | '0402LF'  | 'CHIP'   | 'CS42492FB00'(!)        = 'End of Design' | 'Comp-Approve'     | 'CS42492FB00'           | 'R0402'             | '(R0402-0201)'                 | '249K'    | '1%'    | '1/16W'  | 'DISCRETE' | 'RES CHIP 249K 1/16W +-1%(0402)'                   | 'CHIP0402'     | ''          | ''            | '20120120'
 '249K'       | '1%'      | '1/16W'  | '0402LF'  | 'EMPTY'  | 'CS42492FB00'(!)        = 'End of Design' | 'Comp-Approve'     | 'CS42492FB00'           | 'R0402'             | '(R0402-0201)'                 | '249K'    | '1%'    | '1/16W'  | 'IO'       | 'RES CHIP 249K 1/16W +-1%(0402)'                   | 'CHIP0402'     | ''          | ''            | '20120120'
 '19.1K'      | '1%'      | '1/16W'  | '0402LF'  | 'CHIP'   | 'CS31912FB15'(!)        = 'End of Design' | 'Comp-Approve'     | 'CS31912FB15'           | 'R0402'             | '(R0402-0201)'                 | '19.1K'   | '1%'    | '1/16W'  | 'DISCRETE' | 'RES CHIP 19.1K 1/16W +-1%(0402)'                  | 'CHIP0402'     | ''          | ''            | '20120120'
 '19.1K'      | '1%'      | '1/16W'  | '0402LF'  | 'EMPTY'  | 'CS31912FB15'(!)        = 'End of Design' | 'Comp-Approve'     | 'CS31912FB15'           | 'R0402'             | '(R0402-0201)'                 | '19.1K'   | '1%'    | '1/16W'  | 'IO'       | 'RES CHIP 19.1K 1/16W +-1%(0402)'                  | 'CHIP0402'     | ''          | ''            | '20120120'
 '16.5K'      | '1%'      | '1/16W'  | '0402LF'  | 'CHIP'   | 'CS31652FB12'(!)        = 'End of Design' | 'Comp-Approve'     | 'CS31652FB12'           | 'R0402'             | '(R0402-0201)'                 | '16.5K'   | '1%'    | '1/16W'  | 'DISCRETE' | 'RES CHIP 16.5K 1/16W +-1% (0402)'                 | 'CHIP0402'     | ''          | ''            | '20120120'
 '16.5K'      | '1%'      | '1/16W'  | '0402LF'  | 'EMPTY'  | 'CS31652FB12'(!)        = 'End of Design' | 'Comp-Approve'     | 'CS31652FB12'           | 'R0402'             | '(R0402-0201)'                 | '16.5K'   | '1%'    | '1/16W'  | 'IO'       | 'RES CHIP 16.5K 1/16W +-1% (0402)'                 | 'CHIP0402'     | ''          | ''            | '20120120'
 '26.1K'      | '1%'      | '1/16W'  | '0402LF'  | 'CHIP'   | 'CS32612FB09'(!)        = 'End of Design' | 'Comp-Approve'     | 'CS32612FB09'           | 'R0402'             | '(R0402-0201)'                 | '26.1K'   | '1%'    | '1/16W'  | 'DISCRETE' | 'RES CHIP 26.1K 1/16W +-1%(0402)'                  | 'CHIP0402'     | ''          | ''            | '20120120'
 '26.1K'      | '1%'      | '1/16W'  | '0402LF'  | 'EMPTY'  | 'CS32612FB09'(!)        = 'End of Design' | 'Comp-Approve'     | 'CS32612FB09'           | 'R0402'             | '(R0402-0201)'                 | '26.1K'   | '1%'    | '1/16W'  | 'IO'       | 'RES CHIP 26.1K 1/16W +-1%(0402)'                  | 'CHIP0402'     | ''          | ''            | '20120120'
 '249'        | '1%'      | '1/16W'  | '0402LF'  | 'CHIP'   | 'CS12492FB12'(!)        = 'End of Design' | 'Comp-Approve'     | 'CS12492FB12'           | 'R0402'             | '(R0402-0201)'                 | '249'     | '1%'    | '1/16W'  | 'DISCRETE' | 'RES CHIP 249 1/16W +-1%(0402)'                    | 'CHIP0402'     | ''          | ''            | '20120120'
 '249'        | '1%'      | '1/16W'  | '0402LF'  | 'EMPTY'  | 'CS12492FB12'(!)        = 'End of Design' | 'Comp-Approve'     | 'CS12492FB12'           | 'R0402'             | '(R0402-0201)'                 | '249'     | '1%'    | '1/16W'  | 'IO'       | 'RES CHIP 249 1/16W +-1%(0402)'                    | 'CHIP0402'     | ''          | ''            | '20120120'
 '205'        | '1%'      | '1/16W'  | '0402LF'  | 'CHIP'   | 'CS12052FB10'(!)        = 'End of Design' | 'Comp-Release Qty' | 'CS12052FB10'           | 'R0402'             | '(R0402-0201)'                 | '205'     | '1%'    | '1/16W'  | 'DISCRETE' | 'RES CHIP 205(1/16W.+-1%.0402)'                    | 'CHIP0402'     | ''          | ''            | '20120120'
 '205'        | '1%'      | '1/16W'  | '0402LF'  | 'EMPTY'  | 'CS12052FB10'(!)        = 'End of Design' | 'Comp-Release Qty' | 'CS12052FB10'           | 'R0402'             | '(R0402-0201)'                 | '205'     | '1%'    | '1/16W'  | 'IO'       | 'RES CHIP 205(1/16W.+-1%.0402)'                    | 'CHIP0402'     | ''          | ''            | '20120120'
 '200K'       | '5%'      | '1/16W'  | '0402LF'  | 'CHIP'   | 'CS42002JB14'(!)        = 'End of Design' | 'Comp-Approve'     | 'CS42002JB14'           | 'R0402'             | '(R0402-0201)'                 | '200K'    | '5%'    | '1/16W'  | 'DISCRETE' | 'RES CHIP 200K 1/16W +-5%(0402)'                   | 'CHIP0402'     | ''          | ''            | '20120131'
 '200K'       | '5%'      | '1/16W'  | '0402LF'  | 'EMPTY'  | 'CS42002JB14'(!)        = 'End of Design' | 'Comp-Approve'     | 'CS42002JB14'           | 'R0402'             | '(R0402-0201)'                 | '200K'    | '5%'    | '1/16W'  | 'IO'       | 'RES CHIP 200K 1/16W +-5%(0402)'                   | 'CHIP0402'     | ''          | ''            | '20120131'
 '9.09K'      | '1%'      | '1/16W'  | '0402LF'  | 'CHIP'   | 'CS29092FB27'(!)        = 'End of Design' | 'Comp-Approve'     | 'CS29092FB27'           | 'R0402'             | '(R0402-0201)'                 | '9.09K'   | '1%'    | '1/16W'  | 'DISCRETE' | 'RES CHIP 9.09K 1/16W +-1%(0402)'                  | 'CHIP0402'     | ''          | ''            | '20120207'
 '9.09K'      | '1%'      | '1/16W'  | '0402LF'  | 'EMPTY'  | 'CS29092FB27'(!)        = 'End of Design' | 'Comp-Approve'     | 'CS29092FB27'           | 'R0402'             | '(R0402-0201)'                 | '9.09K'   | '1%'    | '1/16W'  | 'IO'       | 'RES CHIP 9.09K 1/16W +-1%(0402)'                  | 'CHIP0402'     | ''          | ''            | '20120207'
 '1.21M'      | '1%'      | '1/16W'  | '0402LF'  | 'CHIP'   | 'CS51212FB00'(!)        = ''              | ''                 | 'CS51212FB00'           | 'R0402'             | '(R0402-0201)'                 | '1.21M'   | '1%'    | '1/16W'  | 'DISCRETE' | 'RES CHIP 1.21M 1/16W +-1%(0402)'                  | 'CHIP0402'     | ''          | ''            | '20120202'
 '1.21M'      | '1%'      | '1/16W'  | '0402LF'  | 'EMPTY'  | 'CS51212FB00'(!)        = ''              | ''                 | 'CS51212FB00'           | 'R0402'             | '(R0402-0201)'                 | '1.21M '  | '1%'    | '1/16W'  | 'IO'       | 'RES CHIP 1.21M 1/16W +-1%(0402)'                  | 'CHIP0402'     | ''          | ''            | '20120202'
 '301K'       | '1%'      | '1/16W'  | '0402LF'  | 'CHIP'   | 'CS43012FB10'(!)        = 'End of Design' | 'Comp-Approve'     | 'CS43012FB10'           | 'R0402'             | '(R0402-0201)'                 | '301K  '  | '1%'    | '1/16W'  | 'DISCRETE' | 'RES CHIP 301K 1/16W +-1%( 0402)'                  | 'CHIP0402'     | ''          | ''            | '20120202'
 '301K'       | '1%'      | '1/16W'  | '0402LF'  | 'EMPTY'  | 'CS43012FB10'(!)        = 'End of Design' | 'Comp-Approve'     | 'CS43012FB10'           | 'R0402'             | '(R0402-0201)'                 | '301K'    | '1%'    | '1/16W'  | 'IO'       | 'RES CHIP 301K 1/16W +-1%( 0402)'                  | 'CHIP0402'     | ''          | ''            | '20120202'
 '43.2'       | '1%'      | '1/16W'  | '0402LF'  | 'CHIP'   | 'CS04322FB11'(!)        = 'End of Design' | 'Comp-Approve'     | 'CS04322FB11'           | 'R0402'             | '(R0402-0201)'                 | '43.2'    | '1%'    | '1/16W'  | 'DISCRETE' | 'RES CHIP 43.2 1/16W +-1%(0402)'                   | 'CHIP0402'     | ''          | ''            | '20120210'
 '43.2'       | '1%'      | '1/16W'  | '0402LF'  | 'EMPTY'  | 'CS04322FB11'(!)        = 'End of Design' | 'Comp-Approve'     | 'CS04322FB11'           | 'R0402'             | '(R0402-0201)'                 | '43.2'    | '1%'    | '1/16W'  | 'IO'       | 'RES CHIP 43.2 1/16W +-1%(0402)'                   | 'CHIP0402'     | ''          | ''            | '20120210'
 '14K'        | '1%'      | '1/16W'  | '0402LF'  | 'CHIP'   | 'CS31402FB04'(!)        = ''              | ''                 | 'CS31402FB04'           | 'R0402'             | '(R0402-0201)'                 | '14K'     | '1%'    | '1/16W'  | 'DISCRETE' | 'RES CHIP 14K +-1% 1/16W(0402)'                    | 'CHIP0402'     | ''          | ''            | '20120210'
 '14K'        | '1%'      | '1/16W'  | '0402LF'  | 'EMPTY'  | 'CS31402FB04'(!)        = ''              | ''                 | 'CS31402FB04'           | 'R0402'             | '(R0402-0201)'                 | '14K'     | '1%'    | '1/16W'  | 'IO'       | 'RES CHIP 14K +-1% 1/16W(0402)'                    | 'CHIP0402'     | ''          | ''            | '20120210'
 '0.00025'    | '1%'      | '4W'     | '2725LF'  | 'CHIP'   | 'CS0000FFT00'(!)        = 'End of Design' | 'Comp-Approve'     | 'CS0000FFT00'           | 'R2725'             | '(SMR2725AW)'                  | '0.00025' | '1%'    | '4W'     | 'DISCRETE' | 'RES CHIP 0.00025 4W +-1%(2725)H0.99'              | 'CHIP2725'     | ''          | ''            | '20120216'
 '0.00025'    | '1%'      | '4W'     | '2725LF'  | 'EMPTY'  | 'CS0000FFT00'(!)        = 'End of Design' | 'Comp-Approve'     | 'CS0000FFT00'           | 'R2725'             | '(SMR2725AW)'                  | '0.00025' | '1%'    | '4W'     | 'IO'       | 'RES CHIP 0.00025 4W +-1%(2725)H0.99'              | 'CHIP2725'     | ''          | ''            | '20120216'
 '300K'       | '1%'      | '1/16W'  | '0402LF'  | 'CHIP'   | 'CS43002FB15'(!)        = 'End of Design' | 'Comp-Approve'     | 'CS43002FB15'           | 'R0402'             | '(R0402-0201)'                 | '300K'    | '1%'    | '1/16W'  | 'DISCRETE' | 'RES CHIP 300K +-1% 1/16W(0402)'                   | 'CHIP0402'     | ''          | ''            | '20120215'
 '300K'       | '1%'      | '1/16W'  | '0402LF'  | 'EMPTY'  | 'CS43002FB15'(!)        = 'End of Design' | 'Comp-Approve'     | 'CS43002FB15'           | 'R0402'             | '(R0402-0201)'                 | '300K'    | '1%'    | '1/16W'  | 'IO'       | 'RES CHIP 300K +-1% 1/16W(0402)'                   | 'CHIP0402'     | ''          | ''            | '20120215'
 '169K'       | '1%'      | '1/16W'  | '0402LF'  | 'CHIP'   | 'CS41692FB12'(!)        = 'End of Design' | 'Comp-Approve'     | 'CS41692FB12'           | 'R0402'             | '(R0402-0201)'                 | '169K'    | '1%'    | '1/16W'  | 'DISCRETE' | 'RES CHIP 169K +-1% 1/16W(0402)'                   | 'CHIP0402'     | ''          | ''            | '20120215'
 '169K'       | '1%'      | '1/16W'  | '0402LF'  | 'EMPTY'  | 'CS41692FB12'(!)        = 'End of Design' | 'Comp-Approve'     | 'CS41692FB12'           | 'R0402'             | '(R0402-0201)'                 | '169K'    | '1%'    | '1/16W'  | 'IO'       | 'RES CHIP 169K +-1% 1/16W(0402)'                   | 'CHIP0402'     | ''          | ''            | '20120215'
 '3.3'        | '1%'      | '1/10W'  | '0603LF'  | 'CHIP'   | 'CS-3303F918'(!)        = 'End of Design' | 'Comp-Approve'     | 'CS-3303F918'           | 'R0603'             | '(SMR0603AW)'                  | '3.3'     | '1%'    | '1/10W'  | 'DISCRETE' | 'RES CHIP 3.3 1/10W +-1% (0603) EP'                | 'CHIP0603'     | ''          | ''            | '20120215'
 '3.3'        | '1%'      | '1/10W'  | '0603LF'  | 'EMPTY'  | 'CS-3303F918'(!)        = 'End of Design' | 'Comp-Approve'     | 'CS-3303F918'           | 'R0603'             | '(SMR0603AW)'                  | '3.3'     | '1%'    | '1/10W'  | 'IO'       | 'RES CHIP 3.3 1/10W +-1% (0603) EP'                | 'CHIP0603'     | ''          | ''            | '20120215'
 '0.009'      | '1%'      | '1W'     | '2512LF'  | 'CHIP'   | 'CS00008FR00'(!)        = ''              | ''                 | 'CS00008FR00'           | 'R2512XD'           | '(SMR2512AW)'                  | '0.009'   | '1%'    | '1W'     | 'DISCRETE' | 'RES CHIP 0.009 1W +-1%(2512)H0.787'               | 'CHIP2512'     | ''          | ''            | '20120216'
 '0.009'      | '1%'      | '1W'     | '2512LF'  | 'EMPTY'  | 'CS00008FR00'(!)        = ''              | ''                 | 'CS00008FR00'           | 'R2512XD'           | '(SMR2512AW)'                  | '0.009'   | '1%'    | '1W'     | 'IO'       | 'RES CHIP 0.009 1W +-1%(2512)H0.787'               | 'CHIP2512'     | ''          | ''            | '20120216'
 '90.9'       | '1%'      | '1/16W'  | '0402LF'  | 'CHIP'   | 'CS09092FB15'(!)        = 'End of Design' | 'Comp-Approve'     | 'CS09092FB15'           | 'R0402'             | '(R0402-0201)'                 | '90.9'    | '1%'    | '1/16W'  | 'DISCRETE' | 'RES CHIP 90.9 1/16W +-1%(0402)'                   | 'CHIP0402'     | ''          | ''            | '20120221'
 '90.9'       | '1%'      | '1/16W'  | '0402LF'  | 'EMPTY'  | 'CS09092FB15'(!)        = 'End of Design' | 'Comp-Approve'     | 'CS09092FB15'           | 'R0402'             | '(R0402-0201)'                 | '90.9'    | '1%'    | '1/16W'  | 'IO'       | 'RES CHIP 90.9 1/16W +-1%(0402)'                   | 'CHIP0402'     | ''          | ''            | '20120221'
 '0.008'      | '1%'      | '2W'     | '2512LF'  | 'CHIP'   | 'CS+008AFR00'(!)        = ''              | ''                 | 'CS+008AFR00'           | 'R2512'             | '(SMR2512AW)'                  | '0.008'   | '1%'    | '2W'     | 'DISCRETE' | 'RES CHIP 0.008 2W +-1%(2512)'                     | 'CHIP2512'     | ''          | ''            | '20120222'
 '0.008'      | '1%'      | '2W'     | '2512LF'  | 'EMPTY'  | 'CS+008AFR00'(!)        = ''              | ''                 | 'CS+008AFR00'           | 'R2512'             | '(SMR2512AW)'                  | '0.008'   | '1%'    | '2W'     | 'IO'       | 'RES CHIP 0.008 2W +-1%(2512)'                     | 'CHIP2512'     | ''          | ''            | '20120222'
 '0.008'      | '1%'      | '2W'     | '2512LF'  | 'CHIP'   | 'CS+008AFR01'(!)        = ''              | ''                 | 'CS+008AFR01'           | 'R2512'             | '(SMR2512AW)'                  | '0.008'   | '1%'    | '2W'     | 'DISCRETE' | 'RES CHIP 0.008 2W +-1%(2512)HF'                   | 'CHIP2512'     | ''          | ''            | '20120222'
 '0.008'      | '1%'      | '2W'     | '2512LF'  | 'EMPTY'  | 'CS+008AFR01'(!)        = ''              | ''                 | 'CS+008AFR01'           | 'R2512'             | '(SMR2512AW)'                  | '0.008'   | '1%'    | '2W'     | 'IO'       | 'RES CHIP 0.008 2W +-1%(2512)HF'                   | 'CHIP2512'     | ''          | ''            | '20120222'
 '107K'       | '1%'      | '1/16W'  | '0402LF'  | 'CHIP'   | 'CS41072FB11'(!)        = 'End of Design' | 'Comp-Approve'     | 'CS41072FB11'           | 'R0402'             | '(R0402-0201)'                 | '107K'    | '1%'    | '1/16W'  | 'DISCRETE' | 'RES CHIP 107K 1/16W +-1%(0402)'                   | 'CHIP0402'     | ''          | ''            | '20120222'
 '107K'       | '1%'      | '1/16W'  | '0402LF'  | 'EMPTY'  | 'CS41072FB11'(!)        = 'End of Design' | 'Comp-Approve'     | 'CS41072FB11'           | 'R0402'             | '(R0402-0201)'                 | '107K'    | '1%'    | '1/16W'  | 'IO'       | 'RES CHIP 107K 1/16W +-1%(0402)'                   | 'CHIP0402'     | ''          | ''            | '20120222'
 '13'         | '1%'      | '1/16W'  | '0402LF'  | 'CHIP'   | 'CS01302FB05'(!)        = 'End of Design' | 'Comp-Approve'     | 'CS01302FB05'           | 'R0402'             | '(R0402-0201)'                 | '13'      | '1%'    | '1/16W'  | 'DISCRETE' | 'RES CHIP 13 1/16W +-1%(0402)'                     | 'CHIP0402'     | ''          | ''            | '20120228'
 '13'         | '1%'      | '1/16W'  | '0402LF'  | 'EMPTY'  | 'CS01302FB05'(!)        = 'End of Design' | 'Comp-Approve'     | 'CS01302FB05'           | 'R0402'             | '(R0402-0201)'                 | '13'      | '1%'    | '1/16W'  | 'IO'       | 'RES CHIP 13 1/16W +-1%(0402)'                     | 'CHIP0402'     | ''          | ''            | '20120228'
 '6.8'        | '1%'      | '1/16W'  | '0402LF'  | 'CHIP'   | 'CS-6802FB00'(!)        = 'End of Design' | 'Comp-Approve'     | 'CS-6802FB00'           | 'R0402'             | '(R0402-0201)'                 | '6.8'     | '1%'    | '1/16W'  | 'DISCRETE' | 'RES CHIP 6.8 1/16W +-1%(0402)'                    | 'CHIP0402'     | ''          | ''            | '20120228'
 '6.8'        | '1%'      | '1/16W'  | '0402LF'  | 'EMPTY'  | 'CS-6802FB00'(!)        = 'End of Design' | 'Comp-Approve'     | 'CS-6802FB00'           | 'R0402'             | '(R0402-0201)'                 | '6.8'     | '1%'    | '1/16W'  | 'IO'       | 'RES CHIP 6.8 1/16W +-1%(0402)'                    | 'CHIP0402'     | ''          | ''            | '20120228'
 '3.83K'      | '1%'      | '1/16W'  | '0402LF'  | 'CHIP'   | 'CS23832FB01'(!)        = 'End of Design' | 'Comp-Approve'     | 'CS23832FB01'           | 'R0402'             | '(R0402-0201)'                 | '3.83K'   | '1%'    | '1/16W'  | 'DISCRETE' | 'RES CHIP 3.83K 1/16W +-1%(0402)'                  | 'CHIP0402'     | ''          | ''            | '20120304'
 '3.83K'      | '1%'      | '1/16W'  | '0402LF'  | 'EMPTY'  | 'CS23832FB01'(!)        = 'End of Design' | 'Comp-Approve'     | 'CS23832FB01'           | 'R0402'             | '(R0402-0201)'                 | '3.83K'   | '1%'    | '1/16W'  | 'IO'       | 'RES CHIP 3.83K 1/16W +-1%(0402)'                  | 'CHIP0402'     | ''          | ''            | '20120304'
 '95.3K'      | '1%'      | '1/16W'  | '0402LF'  | 'CHIP'   | 'CS39532FB03'(!)        = 'End of Design' | 'Comp-Approve'     | 'CS39532FB03'           | 'R0402'             | '(R0402-0201)'                 | '95.3K'   | '1%'    | '1/16W'  | 'DISCRETE' | 'RESISTOR CHIP 95.3K,1/16W,+-1%(0402)'             | 'CHIP0402'     | ''          | ''            | '20120304'
 '95.3K'      | '1%'      | '1/16W'  | '0402LF'  | 'EMPTY'  | 'CS39532FB03'(!)        = 'End of Design' | 'Comp-Approve'     | 'CS39532FB03'           | 'R0402'             | '(R0402-0201)'                 | '95.3K'   | '1%'    | '1/16W'  | 'IO'       | 'RESISTOR CHIP 95.3K,1/16W,+-1%(0402)'             | 'CHIP0402'     | ''          | ''            | '20120304'
 '453K'       | '1%'      | '1/16W'  | '0402LF'  | 'CHIP'   | 'CS44532FB10'(!)        = 'End of Design' | 'Comp-Approve'     | 'CS44532FB10'           | 'R0402'             | '(R0402-0201)'                 | '453K'    | '1%'    | '1/16W'  | 'DISCRETE' | 'RES CHIP 453K 1/16W +-1%(0402)'                   | 'CHIP0402'     | ''          | ''            | '20120304'
 '453K'       | '1%'      | '1/16W'  | '0402LF'  | 'EMPTY'  | 'CS44532FB10'(!)        = 'End of Design' | 'Comp-Approve'     | 'CS44532FB10'           | 'R0402'             | '(R0402-0201)'                 | '453K'    | '1%'    | '1/16W'  | 'IO'       | 'RES CHIP 453K 1/16W +-1%(0402)'                   | 'CHIP0402'     | ''          | ''            | '20120304'
 '7.68K'      | '1%'      | '1/16W'  | '0402LF'  | 'CHIP'   | 'CS27682FB11'(!)        = 'End of Design' | 'Comp-Approve'     | 'CS27682FB11'           | 'R0402'             | '(R0402-0201)'                 | '7.68K'   | '1%'    | '1/16W'  | 'DISCRETE' | 'RES CHIP 7.68K 1/16W +-1%(0402)'                  | 'CHIP0402'     | ''          | ''            | '20120304'
 '7.68K'      | '1%'      | '1/16W'  | '0402LF'  | 'EMPTY'  | 'CS27682FB11'(!)        = 'End of Design' | 'Comp-Approve'     | 'CS27682FB11'           | 'R0402'             | '(R0402-0201)'                 | '7.68K'   | '1%'    | '1/16W'  | 'IO'       | 'RES CHIP 7.68K 1/16W +-1%(0402)'                  | 'CHIP0402'     | ''          | ''            | '20120304'
 '0.0005'     | '1%'      | '2W'     | '2512LF'  | 'CHIP'   | 'CS0000AFR00'(!)        = ''              | ''                 | 'CS0000AFR00'           | 'R2512XD'           | '(SMR2512AW)'                  | '0.0005'  | '1%'    | '2W'     | 'DISCRETE' | 'RES CHIP 0.0005 2W +-1%(2512)'                    | 'CHIP2512'     | ''          | ''            | '20120627'
 '0.0005'     | '1%'      | '2W'     | '2512LF'  | 'EMPTY'  | 'CS0000AFR00'(!)        = ''              | ''                 | 'CS0000AFR00'           | 'R2512XD'           | '(SMR2512AW)'                  | '0.0005'  | '1%'    | '2W'     | 'IO'       | 'RES CHIP 0.0005 2W +-1%(2512)'                    | 'CHIP2512'     | ''          | ''            | '20120627'
 '240'        | '1%'      | '1/10W'  | '0603LF'  | 'CHIP'   | 'CS12403F918'(!)        = ''              | ''                 | 'CS12403F918'           | 'R0603'             | '(SMR0603AW)'                  | '240'     | '1%'    | '1/10W'  | 'DISCRETE' | 'RES CHIP 240 1/10W +-1%(0603)'                    | 'CHIP0603'     | ''          | ''            | '20120310'
 '240'        | '1%'      | '1/10W'  | '0603LF'  | 'EMPTY'  | 'CS12403F918'(!)        = ''              | ''                 | 'CS12403F918'           | 'R0603'             | '(SMR0603AW)'                  | '240'     | '1%'    | '1/10W'  | 'IO'       | 'RES CHIP 240 1/10W +-1%(0603)'                    | 'CHIP0603'     | ''          | ''            | '20120310'
 '6.34K'      | '1%'      | '1/16W'  | '0402LF'  | 'CHIP'   | 'CS26342FB27'(!)        = 'End of Design' | 'Comp-Approve'     | 'CS26342FB27'           | 'R0402'             | '(R0402-0201)'                 | '6.34K'   | '1%'    | '1/16W'  | 'DISCRETE' | 'RES CHIP 6.34K 1/16W +-1%(0402)'                  | 'CHIP0402'     | ''          | ''            | '20120314'
 '6.34K'      | '1%'      | '1/16W'  | '0402LF'  | 'EMPTY'  | 'CS26342FB27'(!)        = 'End of Design' | 'Comp-Approve'     | 'CS26342FB27'           | 'R0402'             | '(R0402-0201)'                 | '6.34K'   | '1%'    | '1/16W'  | 'IO'       | 'RES CHIP 6.34K 1/16W +-1%(0402)'                  | 'CHIP0402'     | ''          | ''            | '20120314'
 '9.76K'      | '1%'      | '1/16W'  | '0402LF'  | 'CHIP'   | 'CS29762FB00'(!)        = 'End of Design' | 'Comp-Approve'     | 'CS29762FB00'           | 'R0402'             | '(R0402-0201)'                 | '9.76K'   | '1%'    | '1/16W'  | 'DISCRETE' | 'RES CHIP 9.76K 1/16W +-1%(0402)'                  | 'CHIP0402'     | ''          | ''            | '20120314'
 '9.76K'      | '1%'      | '1/16W'  | '0402LF'  | 'EMPTY'  | 'CS29762FB00'(!)        = 'End of Design' | 'Comp-Approve'     | 'CS29762FB00'           | 'R0402'             | '(R0402-0201)'                 | '9.76K'   | '1%'    | '1/16W'  | 'IO'       | 'RES CHIP 9.76K 1/16W +-1%(0402)'                  | 'CHIP0402'     | ''          | ''            | '20120314'
 '39K'        | '1%'      | '1/16W'  | '0402LF'  | 'CHIP'   | 'CS33902FB16'(!)        = 'End of Design' | 'Comp-Approve'     | 'CS33902FB16'           | 'R0402'             | '(R0402-0201)'                 | '39K'     | '1%'    | '1/16W'  | 'DISCRETE' | 'RES CHIP 39K 1/16W +-1%(0402)'                    | 'CHIP0402'     | ''          | ''            | '20120314'
 '39K'        | '1%'      | '1/16W'  | '0402LF'  | 'EMPTY'  | 'CS33902FB16'(!)        = 'End of Design' | 'Comp-Approve'     | 'CS33902FB16'           | 'R0402'             | '(R0402-0201)'                 | '39K'     | '1%'    | '1/16W'  | 'IO'       | 'RES CHIP 39K 1/16W +-1%(0402)'                    | 'CHIP0402'     | ''          | ''            | '20120314'
 '14K'        | '1%'      | '1/16W'  | '0402LF'  | 'CHIP'   | 'CS31402FB12'(!)        = 'End of Design' | 'Comp-Approve'     | 'CS31402FB12'           | 'R0402'             | '(R0402-0201)'                 | '14K'     | '1%'    | '1/16W'  | 'DISCRETE' | 'RES CHIP 14K 1/16W +-1% (0402)'                   | 'CHIP0402'     | ''          | ''            | '20120314'
 '14K'        | '1%'      | '1/16W'  | '0402LF'  | 'EMPTY'  | 'CS31402FB12'(!)        = 'End of Design' | 'Comp-Approve'     | 'CS31402FB12'           | 'R0402'             | '(R0402-0201)'                 | '14K'     | '1%'    | '1/16W'  | 'IO'       | 'RES CHIP 14K 1/16W +-1% (0402)'                   | 'CHIP0402'     | ''          | ''            | '20120314'
 '215K'       | '1%'      | '1/16W'  | '0402LF'  | 'CHIP'   | 'CS42152FB19'(!)        = 'End of Design' | 'Comp-Approve'     | 'CS42152FB19'           | 'R0402'             | '(R0402-0201)'                 | '215K'    | '1%'    | '1/16W'  | 'DISCRETE' | 'RES CHIP 215K 1/16W +-1%(0402)'                   | 'CHIP0402'     | ''          | ''            | '20120320'
 '215K'       | '1%'      | '1/16W'  | '0402LF'  | 'EMPTY'  | 'CS42152FB19'(!)        = 'End of Design' | 'Comp-Approve'     | 'CS42152FB19'           | 'R0402'             | '(R0402-0201)'                 | '215K'    | '1%'    | '1/16W'  | 'IO'       | 'RES CHIP 215K 1/16W +-1%(0402)'                   | 'CHIP0402'     | ''          | ''            | '20120320'
 '53.6K'      | '1%'      | '1/16W'  | '0402LF'  | 'CHIP'   | 'CS35362FB17'(!)        = 'End of Design' | 'Comp-Approve'     | 'CS35362FB17'           | 'R0402'             | '(R0402-0201)'                 | '53.6K'   | '1%'    | '1/16W'  | 'DISCRETE' | 'RES CHIP 53.6K 1/16W +-1%(0402)'                  | 'CHIP0402'     | ''          | ''            | '20120320'
 '53.6K'      | '1%'      | '1/16W'  | '0402LF'  | 'EMPTY'  | 'CS35362FB17'(!)        = 'End of Design' | 'Comp-Approve'     | 'CS35362FB17'           | 'R0402'             | '(R0402-0201)'                 | '53.6K'   | '1%'    | '1/16W'  | 'IO'       | 'RES CHIP 53.6K 1/16W +-1%(0402)'                  | 'CHIP0402'     | ''          | ''            | '20120320'
 '13K'        | '1%'      | '1/10W'  | '0603LF'  | 'CHIP'   | 'CS31303F931'(!)        = ''              | ''                 | 'CS31303F931'           | 'R0603'             | '(SMR0603AW)'                  | '13K'     | '1%'    | '1/10W'  | 'DISCRETE' | 'RESISTOR CHIP 13K 1/10W +-1%(0603)'               | 'CHIP0603'     | ''          | ''            | '20120321'
 '13K'        | '1%'      | '1/10W'  | '0603LF'  | 'EMPTY'  | 'CS31303F931'(!)        = ''              | ''                 | 'CS31303F931'           | 'R0603'             | '(SMR0603AW)'                  | '13K'     | '1%'    | '1/10W'  | 'IO'       | 'RESISTOR CHIP 13K 1/10W +-1%(0603)'               | 'CHIP0603'     | ''          | ''            | '20120321'
 '6.81K'      | '1%'      | '1/16W'  | '0402LF'  | 'CHIP'   | 'CS26812FB13'(!)        = 'End of Design' | 'Comp-Approve'     | 'CS26812FB13'           | 'R0402'             | '(R0402-0201)'                 | '6.81K'   | '1%'    | '1/16W'  | 'DISCRETE' | 'RES CHIP 6.81K 1/16W +-1% (0402)'                 | 'CHIP0402'     | ''          | ''            | '20120322'
 '6.81K'      | '1%'      | '1/16W'  | '0402LF'  | 'EMPTY'  | 'CS26812FB13'(!)        = 'End of Design' | 'Comp-Approve'     | 'CS26812FB13'           | 'R0402'             | '(R0402-0201)'                 | '6.81K'   | '1%'    | '1/16W'  | 'IO'       | 'RES CHIP 6.81K 1/16W +-1% (0402)'                 | 'CHIP0402'     | ''          | ''            | '20120322'
 '549'        | '1%'      | '1/8W'   | '0805LF'  | 'CHIP'   | 'CS15494FA00'(!)        = ''              | ''                 | 'CS15494FA00'           | 'R0805'             | '(SMR0805AW)'                  | '549'     | '1%'    | '1/8W'   | 'DISCRETE' | 'RES CHIP 549 1/8W +-1%(0805)'                     | 'CHIP0805'     | ''          | ''            | '20120325'
 '549'        | '1%'      | '1/8W'   | '0805LF'  | 'EMPTY'  | 'CS15494FA00'(!)        = ''              | ''                 | 'CS15494FA00'           | 'R0805'             | '(SMR0805AW)'                  | '549'     | '1%'    | '1/8W'   | 'IO'       | 'RES CHIP 549 1/8W +-1%(0805)'                     | 'CHIP0805'     | ''          | ''            | '20120325'
 '91'         | '0.1%'    | '1/10W'  | '0603LF'  | 'CHIP'   | 'CS09103B900'(!)        = ''              | ''                 | 'CS09103B900'           | 'R0603'             | '(SMR0603AW)'                  | '91'      | '0.1%'  | '1/10W'  | 'DISCRETE' | 'RES CHIP 91 1/10W +-0.1%(0603)'                   | 'CHIP0603'     | ''          | ''            | '20120325'
 '91'         | '0.1%'    | '1/10W'  | '0603LF'  | 'EMPTY'  | 'CS09103B900'(!)        = ''              | ''                 | 'CS09103B900'           | 'R0603'             | '(SMR0603AW)'                  | '91'      | '0.1%'  | '1/10W'  | 'IO'       | 'RES CHIP 91 1/10W +-0.1%(0603)'                   | 'CHIP0603'     | ''          | ''            | '20120325'
 '115'        | '0.1%'    | '1/10W'  | '0603LF'  | 'CHIP'   | 'CS11153B900'(!)        = ''              | ''                 | 'CS11153B900'           | 'R0603'             | '(SMR0603AW)'                  | '115'     | '0.1%'  | '1/10W'  | 'DISCRETE' | 'RES CHIP 115 1/10W +-0.1%(0603)'                  | 'CHIP0603'     | ''          | ''            | '20120325'
 '115'        | '0.1%'    | '1/10W'  | '0603LF'  | 'EMPTY'  | 'CS11153B900'(!)        = ''              | ''                 | 'CS11153B900'           | 'R0603'             | '(SMR0603AW)'                  | '115'     | '0.1%'  | '1/10W'  | 'IO'       | 'RES CHIP 115 1/10W +-0.1%(0603)'                  | 'CHIP0603'     | ''          | ''            | '20120325'
 '768'        | '0.1%'    | '1/10W'  | '0603LF'  | 'CHIP'   | 'CS17683B900'(!)        = ''              | ''                 | 'CS17683B900'           | 'R0603'             | '(SMR0603AW)'                  | '768'     | '0.1%'  | '1/10W'  | 'DISCRETE' | 'RES CHIP 768 1/10W +-0.1%(0603)'                  | 'CHIP0603'     | ''          | ''            | '20120325'
 '768'        | '0.1%'    | '1/10W'  | '0603LF'  | 'EMPTY'  | 'CS17683B900'(!)        = ''              | ''                 | 'CS17683B900'           | 'R0603'             | '(SMR0603AW)'                  | '768'     | '0.1%'  | '1/10W'  | 'IO'       | 'RES CHIP 768 1/10W +-0.1%(0603)'                  | 'CHIP0603'     | ''          | ''            | '20120325'
 '180K'       | '1%'      | '1/16W'  | '0402LF'  | 'CHIP'   | 'CS41802FB19'(!)        = 'End of Design' | 'Comp-Approve'     | 'CS41802FB19'           | 'R0402'             | '(R0402-0201)'                 | '180K'    | '1%'    | '1/16W'  | 'DISCRETE' | 'RES CHIP 180K 1/16W +-1%(0402)'                   | 'CHIP0402'     | ''          | ''            | '20120326'
 '180K'       | '1%'      | '1/16W'  | '0402LF'  | 'EMPTY'  | 'CS41802FB19'(!)        = 'End of Design' | 'Comp-Approve'     | 'CS41802FB19'           | 'R0402'             | '(R0402-0201)'                 | '180K'    | '1%'    | '1/16W'  | 'IO'       | 'RES CHIP 180K 1/16W +-1%(0402)'                   | 'CHIP0402'     | ''          | ''            | '20120326'
 '174'        | '1%'      | '1/16W'  | '0402LF'  | 'CHIP'   | 'CS11742FB00'(!)        = 'End of Design' | 'Comp-Approve'     | 'CS11742FB00'           | 'R0402'             | '(R0402-0201)'                 | '174'     | '1%'    | '1/16W'  | 'DISCRETE' | 'RES CHIP 174 1/16W +-1%(0402)'                    | 'CHIP0402'     | ''          | ''            | '20120326'
 '174'        | '1%'      | '1/16W'  | '0402LF'  | 'EMPTY'  | 'CS11742FB00'(!)        = 'End of Design' | 'Comp-Approve'     | 'CS11742FB00'           | 'R0402'             | '(R0402-0201)'                 | '174'     | '1%'    | '1/16W'  | 'IO'       | 'RES CHIP 174 1/16W +-1%(0402)'                    | 'CHIP0402'     | ''          | ''            | '20120326'
 '0.002'      | '1%'      | '2W'     | '2512LF'  | 'CHIP'   | 'CS+002AFR00'(!)        = ''              | ''                 | 'CS+002AFR00'           | 'R2512A'            | '(SMR2512AW)'                  | '0.002'   | '1%'    | '2W'     | 'DISCRETE' | 'RES CHIP 0.002 2W +-1%(2512)'                     | 'CHIP2512'     | ''          | ''            | '20120326'
 '0.002'      | '1%'      | '2W'     | '2512LF'  | 'EMPTY'  | 'CS+002AFR00'(!)        = ''              | ''                 | 'CS+002AFR00'           | 'R2512A'            | '(SMR2512AW)'                  | '0.002'   | '1%'    | '2W'     | 'IO'       | 'RES CHIP 0.002 2W +-1%(2512)'                     | 'CHIP2512'     | ''          | ''            | '20120326'
 '3.48M'      | '1%'      | '1/16W'  | '0402LF'  | 'CHIP'   | 'CS53482FB00'(!)        = ''              | ''                 | 'CS53482FB00'           | 'R0402'             | '(R0402-0201)'                 | '3.48M'   | '1%'    | '1/16W'  | 'DISCRETE' | 'RES CHIP 3.48M 1/16W +-1%(0402)'                  | 'CHIP0402'     | ''          | ''            | '20120329'
 '3.48M'      | '1%'      | '1/16W'  | '0402LF'  | 'EMPTY'  | 'CS53482FB00'(!)        = ''              | ''                 | 'CS53482FB00'           | 'R0402'             | '(R0402-0201)'                 | '3.48M'   | '1%'    | '1/16W'  | 'IO'       | 'RES CHIP 3.48M 1/16W +-1%(0402)'                  | 'CHIP0402'     | ''          | ''            | '20120329'
 '3.65M'      | '1%'      | '1/16W'  | '0402LF'  | 'CHIP'   | 'CS53652FB00'(!)        = ''              | ''                 | 'CS53652FB00'           | 'R0402'             | '(R0402-0201)'                 | '3.65M'   | '1%'    | '1/16W'  | 'DISCRETE' | 'RES CHIP 3.65M 1/16W +-1%(0402)'                  | 'CHIP0402'     | ''          | ''            | '20120329'
 '3.65M'      | '1%'      | '1/16W'  | '0402LF'  | 'EMPTY'  | 'CS53652FB00'(!)        = ''              | ''                 | 'CS53652FB00'           | 'R0402'             | '(R0402-0201)'                 | '3.65M'   | '1%'    | '1/16W'  | 'IO'       | 'RES CHIP 3.65M 1/16W +-1%(0402)'                  | 'CHIP0402'     | ''          | ''            | '20120329'
 '0.5'        | '10%'     | '15W'    | 'THLF'    | 'CHIP'   | 'TMP_T6M_KOOL_0405_1'(!) = ''              | ''                 | 'TMP_T6M_KOOL_0405_1'   | 'R18947D'           | '(R18947D)'                    | '0.5'     | '10%'   | '15W'    | 'DISCRETE' | 'RESISTOR CEMENT 0.5 15W +-10%'                    | 'R18947D'      | ''          | ''            | '20120405'
 '0.5'        | '10%'     | '15W'    | 'THLF'    | 'EMPTY'  | 'TMP_T6M_KOOL_0405_1'(!) = ''              | ''                 | 'TMP_T6M_KOOL_0405_1'   | 'R18947D'           | '(R18947D)'                    | '0.5'     | '10%'   | '15W'    | 'IO'       | 'RESISTOR CEMENT 0.5 15W +-10%'                    | 'R18947D'      | ''          | ''            | '20120405'
 '0.39'       | '10%'     | '15W'    | 'THLF'    | 'CHIP'   | 'TMP_T6M_KOOL_0405_2'(!) = ''              | ''                 | 'TMP_T6M_KOOL_0405_2'   | 'R18947D'           | '(R18947D)'                    | '0.39'    | '10%'   | '15W'    | 'DISCRETE' | 'RESISTOR CEMENT 0.39 15W +-10%'                   | 'R18947D'      | ''          | ''            | '20120405'
 '0.39'       | '10%'     | '15W'    | 'THLF'    | 'EMPTY'  | 'TMP_T6M_KOOL_0405_2'(!) = ''              | ''                 | 'TMP_T6M_KOOL_0405_2'   | 'R18947D'           | '(R18947D)'                    | '0.39'    | '10%'   | '15W'    | 'IO'       | 'RESISTOR CEMENT 0.39 15W +-10%'                   | 'R18947D'      | ''          | ''            | '20120405'
 '5.76'       | '10%'     | '50W'    | 'THLF'    | 'CHIP'   | 'TMP_T6M_KOOL_0405_3'(!) = ''              | ''                 | 'TMP_T6M_KOOL_0405_3'   | 'R35475D'           | '(R35475D)'                    | '5.76'    | '10%'   | '50W'    | 'DISCRETE' | 'RESISTOR CEMENT 5.76 50W +-10%'                   | 'R35475D'      | ''          | ''            | '20120405'
 '5.76'       | '10%'     | '50W'    | 'THLF'    | 'EMPTY'  | 'TMP_T6M_KOOL_0405_3'(!) = ''              | ''                 | 'TMP_T6M_KOOL_0405_3'   | 'R35475D'           | '(R35475D)'                    | '5.76'    | '10%'   | '50W'    | 'IO'       | 'RESISTOR CEMENT 5.76 50W +-10%'                   | 'R35475D'      | ''          | ''            | '20120405'
 '2.88'       | '10%'     | '60W'    | 'THLF'    | 'CHIP'   | 'TMP_T6M_KOOL_0405_4'(!) = ''              | ''                 | 'TMP_T6M_KOOL_0405_4'   | 'R35475D'           | '(R35475D)'                    | '2.88'    | '10%'   | '60W'    | 'DISCRETE' | 'RESISTOR CEMENT 2.88 60W +-10%'                   | 'R35475D'      | ''          | ''            | '20120405'
 '2.88'       | '10%'     | '60W'    | 'THLF'    | 'EMPTY'  | 'TMP_T6M_KOOL_0405_4'(!) = ''              | ''                 | 'TMP_T6M_KOOL_0405_4'   | 'R35475D'           | '(R35475D)'                    | '2.88'    | '10%'   | '60W'    | 'IO'       | 'RESISTOR CEMENT 2.88 60W +-10%'                   | 'R35475D'      | ''          | ''            | '20120405'
 '1.5'        | '5%'      | '25W'    | 'THLF'    | 'CHIP'   | 'TMP_T6M_KOOL_0406_1'(!) = ''              | ''                 | 'TMP_T6M_KOOL_0406_1'   | 'R23655D'           | '(R23655D)'                    | '1.5'     | '5%'    | '25W'    | 'DISCRETE' | 'RESISTOR CEMENT 1.5 25W +-5%'                     | 'R23655D'      | ''          | ''            | '20120406'
 '1.5'        | '5%'      | '25W'    | 'THLF'    | 'EMPTY'  | 'TMP_T6M_KOOL_0406_1'(!) = ''              | ''                 | 'TMP_T6M_KOOL_0406_1'   | 'R23655D'           | '(R23655D)'                    | '1.5'     | '5%'    | '25W'    | 'IO'       | 'RESISTOR CEMENT 1.5 25W +-5%'                     | 'R23655D'      | ''          | ''            | '20120406'
 '97.6K'      | '1%'      | '1/16W'  | '0402LF'  | 'CHIP'   | 'CS39762FB12'(!)        = 'End of Design' | 'Comp-Approve'     | 'CS39762FB12'           | 'R0402'             | '(R0402-0201)'                 | '97.6K'   | '1%'    | '1/16W'  | 'DISCRETE' | 'RES CHIP 97.6K 1/16W +-1%(0402)'                  | 'CHIP0402'     | ''          | ''            | '20120406'
 '97.6K'      | '1%'      | '1/16W'  | '0402LF'  | 'EMPTY'  | 'CS39762FB12'(!)        = 'End of Design' | 'Comp-Approve'     | 'CS39762FB12'           | 'R0402'             | '(R0402-0201)'                 | '97.6K'   | '1%'    | '1/16W'  | 'IO'       | 'RES CHIP 97.6K 1/16W +-1%(0402)'                  | 'CHIP0402'     | ''          | ''            | '20120406'
 '510'        | '1%'      | '1/16W'  | '0402LF'  | 'CHIP'   | 'CS15102FB19'(!)        = 'End of Design' | 'Comp-Approve'     | 'CS15102FB19'           | 'R0402'             | '(R0402-0201)'                 | '510'     | '1%'    | '1/16W'  | 'DISCRETE' | 'RES CHIP 510 1/16W +-1%(0402)'                    | 'CHIP0402'     | ''          | ''            | '20120414'
 '510'        | '1%'      | '1/16W'  | '0402LF'  | 'EMPTY'  | 'CS15102FB19'(!)        = 'End of Design' | 'Comp-Approve'     | 'CS15102FB19'           | 'R0402'             | '(R0402-0201)'                 | '510'     | '1%'    | '1/16W'  | 'IO'       | 'RES CHIP 510 1/16W +-1%(0402)'                    | 'CHIP0402'     | ''          | ''            | '20120414'
 '24.9'       | '0.5%'    | '1/16W'  | '0402LF'  | 'CHIP'   | 'CS02492DB01'(!)        = 'End of Design' | 'Comp-Approve'     | 'CS02492DB01'           | 'R0402'             | '(R0402-0201)'                 | '24.9'    | '0.5%'  | '1/16W'  | 'DISCRETE' | 'RES CHIP 24.9 1/16W +-0.5%(0402)'                 | 'CHIP0402'     | ''          | ''            | '20120416'
 '24.9'       | '0.5%'    | '1/16W'  | '0402LF'  | 'EMPTY'  | 'CS02492DB01'(!)        = 'End of Design' | 'Comp-Approve'     | 'CS02492DB01'           | 'R0402'             | '(R0402-0201)'                 | '24.9'    | '0.5%'  | '1/16W'  | 'IO'       | 'RES CHIP 24.9 1/16W +-0.5%(0402)'                 | 'CHIP0402'     | ''          | ''            | '20120416'
 '604'        | '1%'      | '1/8W'   | '0805LF'  | 'CHIP'   | 'CS16044FA00'(!)        = ''              | ''                 | 'CS16044FA00'           | 'R0805'             | '(SMR0805AW)'                  | '604'     | '1%'    | '1/8W'   | 'DISCRETE' | 'RES CHIP 604 1/8W +-1%(0805)'                     | 'CHIP0805'     | ''          | ''            | '20120424'
 '604'        | '1%'      | '1/8W'   | '0805LF'  | 'EMPTY'  | 'CS16044FA00'(!)        = ''              | ''                 | 'CS16044FA00'           | 'R0805'             | '(SMR0805AW)'                  | '604'     | '1%'    | '1/8W'   | 'IO'       | 'RES CHIP 604 1/8W +-1%(0805)'                     | 'CHIP0805'     | ''          | ''            | '20120424'
 '115'        | '1%'      | '1/16W'  | '0402LF'  | 'CHIP'   | 'CS11152FB11'(!)        = 'End of Design' | 'Comp-Release Qty' | 'CS11152FB11'           | 'R0402'             | '(R0402-0201)'                 | '115'     | '1%'    | '1/16W'  | 'DISCRETE' | 'RES CHIP 115 1/16W +-1% (0402)'                   | 'CHIP0402'     | ''          | ''            | '20120426'
 '115'        | '1%'      | '1/16W'  | '0402LF'  | 'EMPTY'  | 'CS11152FB11'(!)        = 'End of Design' | 'Comp-Release Qty' | 'CS11152FB11'           | 'R0402'             | '(R0402-0201)'                 | '115'     | '1%'    | '1/16W'  | 'IO'       | 'RES CHIP 115 1/16W +-1% (0402)'                   | 'CHIP0402'     | ''          | ''            | '20120426'
 '49.9'       | '1%'      | '1/8W'   | '0805LF'  | 'CHIP'   | 'CS04994FA01'(!)        = ''              | ''                 | 'CS04994FA01'           | 'R0805'             | '(SMR0805AW)'                  | '49.9'    | '1%'    | '1/8W'   | 'DISCRETE' | 'RES CHIP 49.9 1/8W +-1%(0805)'                    | 'CHIP0805'     | ''          | ''            | '20120427'
 '49.9'       | '1%'      | '1/8W'   | '0805LF'  | 'EMPTY'  | 'CS04994FA01'(!)        = ''              | ''                 | 'CS04994FA01'           | 'R0805'             | '(SMR0805AW)'                  | '49.9'    | '1%'    | '1/8W'   | 'IO'       | 'RES CHIP 49.9 1/8W +-1%(0805)'                    | 'CHIP0805'     | ''          | ''            | '20120427'
 '13.3K'      | '1%'      | '1/16W'  | '0402LF'  | 'CHIP'   | 'CS21332FB02'(!)        = 'End of Design' | 'Comp-Approve'     | 'CS21332FB02'           | 'R0402'             | '(R0402-0201)'                 | '13.3K'   | '1%'    | '1/16W'  | 'DISCRETE' | 'RES CHIP 13.3K 1/16W +-1%(0402)'                  | 'CHIP0402'     | ''          | ''            | '20120502'
 '13.3K'      | '1%'      | '1/16W'  | '0402LF'  | 'EMPTY'  | 'CS21332FB02'(!)        = 'End of Design' | 'Comp-Approve'     | 'CS21332FB02'           | 'R0402'             | '(R0402-0201)'                 | '13.3K'   | '1%'    | '1/16W'  | 'IO'       | 'RES CHIP 13.3K 1/16W +-1%(0402)'                  | 'CHIP0402'     | ''          | ''            | '20120502'
 '332K'       | '1%'      | '1/16W'  | '0402LF'  | 'CHIP'   | 'CS43322FB15'(!)        = 'End of Design' | 'Comp-Approve'     | 'CS43322FB15'           | 'R0402'             | '(R0402-0201)'                 | '332K'    | '1%'    | '1/16W'  | 'DISCRETE' | 'RES CHIP 332K 1/16W +-1%(0402)'                   | 'CHIP0402'     | ''          | ''            | '20120516'
 '332K'       | '1%'      | '1/16W'  | '0402LF'  | 'EMPTY'  | 'CS43322FB15'(!)        = 'End of Design' | 'Comp-Approve'     | 'CS43322FB15'           | 'R0402'             | '(R0402-0201)'                 | '332K'    | '1%'    | '1/16W'  | 'IO'       | 'RES CHIP 332K 1/16W +-1%(0402)'                   | 'CHIP0402'     | ''          | ''            | '20120516'
 '95.3K'      | '1%'      | '1/8W'   | '0805LF'  | 'CHIP'   | 'CS39534FA00'(!)        = ''              | ''                 | 'CS39534FA00'           | 'R0805'             | '(SMR0805AW)'                  | '95.3K '  | '1%'    | '1/8W'   | 'DISCRETE' | 'RES CHIP 95.3K 1/8W +-1%(0805)'                   | 'CHIP0805'     | ''          | ''            | '20120524'
 '95.3K'      | '1%'      | '1/8W'   | '0805LF'  | 'EMPTY'  | 'CS39534FA00'(!)        = ''              | ''                 | 'CS39534FA00'           | 'R0805'             | '(SMR0805AW)'                  | '95.3K '  | '1%'    | '1/8W'   | 'IO'       | 'RES CHIP 95.3K 1/8W +-1%(0805)'                   | 'CHIP0805'     | ''          | ''            | '20120524'
 '453K'       | '1%'      | '1/8W'   | '0805LF'  | 'CHIP'   | 'CS44534FA00'(!)        = ''              | ''                 | 'CS44534FA00'           | 'R0805'             | '(SMR0805AW)'                  | '453K'    | '1%'    | '1/8W'   | 'DISCRETE' | 'RES CHIP 453K 1/8W +-1%(0805)'                    | 'CHIP0805'     | ''          | ''            | '20120524'
 '453K'       | '1%'      | '1/8W'   | '0805LF'  | 'EMPTY'  | 'CS44534FA00'(!)        = ''              | ''                 | 'CS44534FA00'           | 'R0805'             | '(SMR0805AW)'                  | '453K'    | '1%'    | '1/8W'   | 'IO'       | 'RES CHIP 453K 1/8W +-1%(0805)'                    | 'CHIP0805'     | ''          | ''            | '20120524'
 '174K'       | '1%'      | '1/8W'   | '0805LF'  | 'CHIP'   | 'CS41744FA00'(!)        = ''              | ''                 | 'CS41744FA00'           | 'R0805'             | '(SMR0805AW)'                  | '174K'    | '1%'    | '1/8W'   | 'DISCRETE' | 'RES CHIP 174K 1/8W +-1%(0805)'                    | 'CHIP0805'     | ''          | ''            | '20120524'
 '174K'       | '1%'      | '1/8W'   | '0805LF'  | 'EMPTY'  | 'CS41744FA00'(!)        = ''              | ''                 | 'CS41744FA00'           | 'R0805'             | '(SMR0805AW)'                  | '174K'    | '1%'    | '1/8W'   | 'IO'       | 'RES CHIP 174K 1/8W +-1%(0805)'                    | 'CHIP0805'     | ''          | ''            | '20120524'
 '10'         | '5%'      | '1/20W'  | '0201LF'  | 'CHIP'   | 'CS01001JE00'(!)        = ''              | ''                 | 'CS01001JE00'           | 'R0201'             | '(SMR0201AW)'                  | '10'      | '5%'    | '1/20W'  | 'DISCRETE' | 'RES CHIP 10(1/20W,+-5%,0201)HF'                   | 'CHIP0201'     | ''          | ''            | '20120524'
 '10'         | '5%'      | '1/20W'  | '0201LF'  | 'EMPTY'  | 'CS01001JE00'(!)        = ''              | ''                 | 'CS01001JE00'           | 'R0201'             | '(SMR0201AW)'                  | '10'      | '5%'    | '1/20W'  | 'IO'       | 'RES CHIP 10(1/20W,+-5%,0201)HF'                   | 'CHIP0201'     | ''          | ''            | '20120524'
 '1K'         | '5%'      | '1/20W'  | '0201LF'  | 'CHIP'   | 'CS21001JE00'(!)        = ''              | ''                 | 'CS21001JE00'           | 'R0201'             | '(SMR0201AW)'                  | '1K'      | '5%'    | '1/20W'  | 'DISCRETE' | 'RES CHIP 1K 1/20W +-5%(0201)HF'                   | 'CHIP0201'     | ''          | ''            | '20120524'
 '1K'         | '5%'      | '1/20W'  | '0201LF'  | 'EMPTY'  | 'CS21001JE00'(!)        = ''              | ''                 | 'CS21001JE00'           | 'R0201'             | '(SMR0201AW)'                  | '1K'      | '5%'    | '1/20W'  | 'IO'       | 'RES CHIP 1K 1/20W +-5%(0201)HF'                   | 'CHIP0201'     | ''          | ''            | '20120524'
 '27K'        | '5%'      | '1/20W'  | '0201LF'  | 'CHIP'   | 'CS32701JE00'(!)        = ''              | ''                 | 'CS32701JE00'           | 'R0201'             | '(SMR0201AW)'                  | '27K'     | '5%'    | '1/20W'  | 'DISCRETE' | 'RES CHIP 27K 1/20W +-5%(0201)'                    | 'CHIP0201'     | ''          | ''            | '20120524'
 '27K'        | '5%'      | '1/20W'  | '0201LF'  | 'EMPTY'  | 'CS32701JE00'(!)        = ''              | ''                 | 'CS32701JE00'           | 'R0201'             | '(SMR0201AW)'                  | '27K'     | '5%'    | '1/20W'  | 'IO'       | 'RES CHIP 27K 1/20W +-5%(0201)'                    | 'CHIP0201'     | ''          | ''            | '20120524'
 '100K'       | '5%'      | '1/20W'  | '0201LF'  | 'CHIP'   | 'CS41001JE00'(!)        = ''              | ''                 | 'CS41001JE00'           | 'R0201'             | '(SMR0201AW)'                  | '100K'    | '5%'    | '1/20W'  | 'DISCRETE' | 'RES CHIP 100K(1/20W,+-5%,0201)'                   | 'CHIP0201'     | ''          | ''            | '20120524'
 '100K'       | '5%'      | '1/20W'  | '0201LF'  | 'EMPTY'  | 'CS41001JE00'(!)        = ''              | ''                 | 'CS41001JE00'           | 'R0201'             | '(SMR0201AW)'                  | '100K'    | '5%'    | '1/20W'  | 'IO'       | 'RES CHIP 100K(1/20W,+-5%,0201)'                   | 'CHIP0201'     | ''          | ''            | '20120524'
 '499K'       | '1%'      | '1/8W'   | '0805LF'  | 'CHIP'   | 'CS44994FA00'(!)        = ''              | ''                 | 'CS44994FA00'           | 'R0805'             | '(SMR0805AW)'                  | '499K'    | '1%'    | '1/8W'   | 'DISCRETE' | 'RES CHIP 499K 1/8W+-1%(0805)'                     | 'CHIP0805'     | ''          | ''            | '20120528'
 '499K'       | '1%'      | '1/8W'   | '0805LF'  | 'EMPTY'  | 'CS44994FA00'(!)        = ''              | ''                 | 'CS44994FA00'           | 'R0805'             | '(SMR0805AW)'                  | '499K'    | '1%'    | '1/8W'   | 'IO'       | 'RES CHIP 499K 1/8W+-1%(0805)'                     | 'CHIP0805'     | ''          | ''            | '20120528'
 '0'          | '5%'      | '1/20W'  | '0201LF'  | 'CHIP'   | 'CS00001JE02'(!)        = 'End of Design' | 'Comp-Approve'     | 'CS00001JE02'           | 'R0201'             | '(SMR0201AW)'                  | '0'       | '5%'    | '1/20W'  | 'DISCRETE' | 'RES CHIP 0(1/20W,+-5%,0201)HF'                    | 'CHIP0201'     | ''          | ''            | '20120528'
 '0'          | '5%'      | '1/20W'  | '0201LF'  | 'EMPTY'  | 'CS00001JE02'(!)        = 'End of Design' | 'Comp-Approve'     | 'CS00001JE02'           | 'R0201'             | '(SMR0201AW)'                  | '0'       | '5%'    | '1/20W'  | 'IO'       | 'RES CHIP 0(1/20W,+-5%,0201)HF'                    | 'CHIP0201'     | ''          | ''            | '20120528'
 '4.7K'       | '5%'      | '1/20W'  | '0201LF'  | 'CHIP'   | 'CS24701JE00'(!)        = ''              | ''                 | 'CS24701JE00'           | 'R0201'             | '(SMR0201AW)'                  | '4.7K'    | '5%'    | '1/20W'  | 'DISCRETE' | 'RES CHIP 4.7K(1/20W,+-5%,0201)'                   | 'CHIP0201'     | ''          | ''            | '20120528'
 '4.7K'       | '5%'      | '1/20W'  | '0201LF'  | 'EMPTY'  | 'CS24701JE00'(!)        = ''              | ''                 | 'CS24701JE00'           | 'R0201'             | '(SMR0201AW)'                  | '4.7K'    | '5%'    | '1/20W'  | 'IO'       | 'RES CHIP 4.7K(1/20W,+-5%,0201)'                   | 'CHIP0201'     | ''          | ''            | '20120528'
 '33'         | '1%'      | '1/20W'  | '0201LF'  | 'CHIP'   | 'CS03301FE01'(!)        = ''              | ''                 | 'CS03301FE01'           | 'R0201'             | '(SMR0201AW)'                  | '33'      | '1%'    | '1/20W'  | 'DISCRETE' | 'RES CHIP 33 1/20W +-1%(0201)'                     | 'CHIP0201'     | ''          | ''            | '20120528'
 '33'         | '1%'      | '1/20W'  | '0201LF'  | 'EMPTY'  | 'CS03301FE01'(!)        = ''              | ''                 | 'CS03301FE01'           | 'R0201'             | '(SMR0201AW)'                  | '33'      | '1%'    | '1/20W'  | 'IO'       | 'RES CHIP 33 1/20W +-1%(0201)'                     | 'CHIP0201'     | ''          | ''            | '20120528'
 '49.9'       | '1%'      | '1/20W'  | '0201LF'  | 'CHIP'   | 'CS04991FE00'(!)        = ''              | ''                 | 'CS04991FE00'           | 'R0201'             | '(SMR0201AW)'                  | '49.9'    | '1%'    | '1/20W'  | 'DISCRETE' | 'RES CHIP 49.9 1/20W +-1%(0201)'                   | 'CHIP0201'     | ''          | ''            | '20120528'
 '49.9'       | '1%'      | '1/20W'  | '0201LF'  | 'EMPTY'  | 'CS04991FE00'(!)        = ''              | ''                 | 'CS04991FE00'           | 'R0201'             | '(SMR0201AW)'                  | '49.9'    | '1%'    | '1/20W'  | 'IO'       | 'RES CHIP 49.9 1/20W +-1%(0201)'                   | 'CHIP0201'     | ''          | ''            | '20120528'
 '6.04K'      | '1%'      | '1/20W'  | '0201LF'  | 'CHIP'   | 'CS26041FE06'(!)        = ''              | ''                 | 'CS26041FE06'           | 'R0201'             | '(SMR0201AW)'                  | '6.04K'   | '1%'    | '1/20W'  | 'DISCRETE' | 'RES CHIP 6.04K 1/20W +-1%(0201)'                  | 'CHIP0201'     | ''          | ''            | '20120528'
 '6.04K'      | '1%'      | '1/20W'  | '0201LF'  | 'EMPTY'  | 'CS26041FE06'(!)        = ''              | ''                 | 'CS26041FE06'           | 'R0201'             | '(SMR0201AW)'                  | '6.04K'   | '1%'    | '1/20W'  | 'IO'       | 'RES CHIP 6.04K 1/20W +-1%(0201)'                  | 'CHIP0201'     | ''          | ''            | '20120528'
 '100'        | '1%'      | '1/20W'  | '0201LF'  | 'CHIP'   | 'CS11001FE00'(!)        = ''              | ''                 | 'CS11001FE00'           | 'R0201'             | '(SMR0201AW)'                  | '100'     | '1%'    | '1/20W'  | 'DISCRETE' | 'RES CHIP 100 1/20W +-1%(0201)'                    | 'CHIP0201'     | ''          | ''            | '20120528'
 '100'        | '1%'      | '1/20W'  | '0201LF'  | 'EMPTY'  | 'CS11001FE00'(!)        = ''              | ''                 | 'CS11001FE00'           | 'R0201'             | '(SMR0201AW)'                  | '100'     | '1%'    | '1/20W'  | 'IO'       | 'RES CHIP 100 1/20W +-1%(0201)'                    | 'CHIP0201'     | ''          | ''            | '20120528'
 '15K'        | '1%'      | '1/20W'  | '0201LF'  | 'CHIP'   | 'CS31501FE01'(!)        = ''              | ''                 | 'CS31501FE01'           | 'R0201'             | '(SMR0201AW)'                  | '15K'     | '1%'    | '1/20W'  | 'DISCRETE' | 'RES CHIP 15K 1/20W +-1%(0201)HF'                  | 'CHIP0201'     | ''          | ''            | '20120528'
 '15K'        | '1%'      | '1/20W'  | '0201LF'  | 'EMPTY'  | 'CS31501FE01'(!)        = ''              | ''                 | 'CS31501FE01'           | 'R0201'             | '(SMR0201AW)'                  | '15K'     | '1%'    | '1/20W'  | 'IO'       | 'RES CHIP 15K 1/20W +-1%(0201)HF'                  | 'CHIP0201'     | ''          | ''            | '20120528'
 '240'        | '1%'      | '1/20W'  | '0201LF'  | 'CHIP'   | 'CS12401FE00'(!)        = ''              | ''                 | 'CS12401FE00'           | 'R0201'             | '(SMR0201AW)'                  | '240'     | '1%'    | '1/20W'  | 'DISCRETE' | 'RES CHIP 240 1/20W +-1%(0201)'                    | 'CHIP0201'     | ''          | ''            | '20120528'
 '240'        | '1%'      | '1/20W'  | '0201LF'  | 'EMPTY'  | 'CS12401FE00'(!)        = ''              | ''                 | 'CS12401FE00'           | 'R0201'             | '(SMR0201AW)'                  | '240'     | '1%'    | '1/20W'  | 'IO'       | 'RES CHIP 240 1/20W +-1%(0201)'                    | 'CHIP0201'     | ''          | ''            | '20120528'
 '30.1K'      | '1%'      | '1/10W'  | '0603LF'  | 'CHIP'   | 'CS33013F914'(!)        = ''              | ''                 | 'CS33013F914'           | 'R0603'             | '(SMR0603AW)'                  | '30.1K'   | '1%'    | '1/10W'  | 'DISCRETE' | 'RESISTOR CHIP 30.1K 1/10W+-1%(0603)'              | 'CHIP0603'     | ''          | ''            | '20120529'
 '30.1K'      | '1%'      | '1/10W'  | '0603LF'  | 'EMPTY'  | 'CS33013F914'(!)        = ''              | ''                 | 'CS33013F914'           | 'R0603'             | '(SMR0603AW)'                  | '30.1K'   | '1%'    | '1/10W'  | 'IO'       | 'RESISTOR CHIP 30.1K 1/10W+-1%(0603)'              | 'CHIP0603'     | ''          | ''            | '20120529'
 '9.76K'      | '0.10%'   | '1/10W'  | '0603LF'  | 'CHIP'   | 'CS29763B903'(!)        = ''              | ''                 | 'CS29763B903'           | 'R0603'             | '(SMR0603AW)'                  | '9.76K'   | '0.10%' | '1/10W'  | 'DISCRETE' | 'RES CHIP 9.76K 1/10W +-0.1%(0603)'                | 'CHIP0603'     | ''          | ''            | '20120529'
 '9.76K'      | '0.10%'   | '1/10W'  | '0603LF'  | 'EMPTY'  | 'CS29763B903'(!)        = ''              | ''                 | 'CS29763B903'           | 'R0603'             | '(SMR0603AW)'                  | '9.76K'   | '0.10%' | '1/10W'  | 'IO'       | 'RES CHIP 9.76K 1/10W +-0.1%(0603)'                | 'CHIP0603'     | ''          | ''            | '20120529'
 '1K'         | '5%'      | '1/8W'   | '0805LF'  | 'CHIP'   | 'CS21004JA38'(!)        = ''              | ''                 | 'CS21004JA38'           | 'R0805'             | '(SMR0805AW)'                  | '1K'      | '5%'    | '1/8W'   | 'DISCRETE' | 'RES CHIP 1K 1/8W +-5%(0805)L-F'                   | 'CHIP0805'     | ''          | ''            | '20120529'
 '1K'         | '5%'      | '1/8W'   | '0805LF'  | 'EMPTY'  | 'CS21004JA38'(!)        = ''              | ''                 | 'CS21004JA38'           | 'R0805'             | '(SMR0805AW)'                  | '1K'      | '5%'    | '1/8W'   | 'IO'       | 'RES CHIP 1K 1/8W +-5%(0805)L-F'                   | 'CHIP0805'     | ''          | ''            | '20120529'
 '22K'        | '1%'      | '1/10W'  | '0603LF'  | 'CHIP'   | 'CS32203F914'(!)        = ''              | ''                 | 'CS32203F914'           | 'R0603'             | '(SMR0603AW)'                  | '22K'     | '1%'    | '1/10W'  | 'DISCRETE' | 'RES CHIP 22K 1/10W +-1%(0603)'                    | 'CHIP0603'     | ''          | ''            | '20120529'
 '22K'        | '1%'      | '1/10W'  | '0603LF'  | 'EMPTY'  | 'CS32203F914'(!)        = ''              | ''                 | 'CS32203F914'           | 'R0603'             | '(SMR0603AW)'                  | '22K'     | '1%'    | '1/10W'  | 'IO'       | 'RES CHIP 22K 1/10W +-1%(0603)'                    | 'CHIP0603'     | ''          | ''            | '20120529'
 '510K'       | '5%'      | '1/16W'  | '0402LF'  | 'CHIP'   | 'CS45102JB16'(!)        = 'End of Design' | 'Comp-Approve'     | 'CS45102JB16'           | 'R0402'             | '(R0402-0201)'                 | '510K'    | '5%'    | '1/16W'  | 'DISCRETE' | 'RES CHIP 510K(1/16W,+-5%,0402)'                   | 'CHIP0402'     | ''          | ''            | '20120614'
 '510K'       | '5%'      | '1/16W'  | '0402LF'  | 'EMPTY'  | 'CS45102JB16'(!)        = 'End of Design' | 'Comp-Approve'     | 'CS45102JB16'           | 'R0402'             | '(R0402-0201)'                 | '510K'    | '5%'    | '1/16W'  | 'IO'       | 'RES CHIP 510K(1/16W,+-5%,0402)'                   | 'CHIP0402'     | ''          | ''            | '20120614'
 '130K'       | '5%'      | '1/16W'  | '0402LF'  | 'CHIP'   | 'CS41302JB12'(!)        = 'End of Design' | 'Comp-Approve'     | 'CS41302JB12'           | 'R0402'             | '(R0402-0201)'                 | '130K'    | '5%'    | '1/16W'  | 'DISCRETE' | 'RES CHIP 130K 1/16W +-5%(0402)'                   | 'CHIP0402'     | ''          | ''            | '20120614'
 '130K'       | '5%'      | '1/16W'  | '0402LF'  | 'EMPTY'  | 'CS41302JB12'(!)        = 'End of Design' | 'Comp-Approve'     | 'CS41302JB12'           | 'R0402'             | '(R0402-0201)'                 | '130K'    | '5%'    | '1/16W'  | 'IO'       | 'RES CHIP 130K 1/16W +-5%(0402)'                   | 'CHIP0402'     | ''          | ''            | '20120614'
 '56.2'       | '1%'      | '1/16W'  | '0402LF'  | 'CHIP'   | 'CS05622FB22'(!)        = 'End of Design' | 'Comp-Approve'     | 'CS05622FB22'           | 'R0402'             | '(R0402-0201)'                 | '56.2'    | '1%'    | '1/16W'  | 'DISCRETE' | 'RESISTOR CHIP 56.2 1/16W +-1% (0402)'             | 'CHIP0402'     | ''          | ''            | '20120614'
 '56.2'       | '1%'      | '1/16W'  | '0402LF'  | 'EMPTY'  | 'CS05622FB22'(!)        = 'End of Design' | 'Comp-Approve'     | 'CS05622FB22'           | 'R0402'             | '(R0402-0201)'                 | '56.2'    | '1%'    | '1/16W'  | 'IO'       | 'RESISTOR CHIP 56.2 1/16W +-1% (0402)'             | 'CHIP0402'     | ''          | ''            | '20120614'
 '20'         | '5%'      | '1/4W'   | '1206LF'  | 'CHIP'   | 'CS02006J201'(!)        = ''              | ''                 | 'CS02006J201'           | 'R1206'             | '(SMR1206AW)'                  | '20'      | '5%'    | '1/4W'   | 'DISCRETE' | 'RES CHIP 20 1/4W +-5% (1206)'                     | 'CHIP1206'     | ''          | ''            | '20120614'
 '20'         | '5%'      | '1/4W'   | '1206LF'  | 'EMPTY'  | 'CS02006J201'(!)        = ''              | ''                 | 'CS02006J201'           | 'R1206'             | '(SMR1206AW)'                  | '20'      | '5%'    | '1/4W'   | 'IO'       | 'RES CHIP 20 1/4W +-5% (1206)'                     | 'CHIP1206'     | ''          | ''            | '20120614'
 '5.1'        | '5%'      | '1/4W'   | '1206LF'  | 'CHIP'   | 'CS-5106J205'(!)        = ''              | ''                 | 'CS-5106J205'           | 'R1206'             | '(SMR1206AW)'                  | '5.1'     | '5%'    | '1/4W'   | 'DISCRETE' | 'RES CHIP 5.1 1/4W +-5% (1206)'                    | 'CHIP1206'     | ''          | ''            | '20120614'
 '5.1'        | '5%'      | '1/4W'   | '1206LF'  | 'EMPTY'  | 'CS-5106J205'(!)        = ''              | ''                 | 'CS-5106J205'           | 'R1206'             | '(SMR1206AW)'                  | '5.1'     | '5%'    | '1/4W'   | 'IO'       | 'RES CHIP 5.1 1/4W +-5% (1206)'                    | 'CHIP1206'     | ''          | ''            | '20120614'
 '3.3'        | '5%'      | '1/20W'  | '0201LF'  | 'CHIP'   | 'CS-3301JE00'(!)        = ''              | ''                 | 'CS-3301JE00'           | 'R0201'             | '(SMR0201AW)'                  | '3.3'     | '5%'    | '1/20W'  | 'DISCRETE' | 'RES CHIP 3.3 1/20W +-5%(0201)'                    | 'CHIP0201'     | ''          | ''            | '20120615'
 '3.3'        | '5%'      | '1/20W'  | '0201LF'  | 'EMPTY'  | 'CS-3301JE00'(!)        = ''              | ''                 | 'CS-3301JE00'           | 'R0201'             | '(SMR0201AW)'                  | '3.3'     | '5%'    | '1/20W'  | 'IO'       | 'RES CHIP 3.3 1/20W +-5%(0201)'                    | 'CHIP0201'     | ''          | ''            | '20120615'
 '4.99'       | '1%'      | '1/20W'  | '0201LF'  | 'CHIP'   | 'CS-4991FE00'(!)        = ''              | ''                 | 'CS-4991FE00'           | 'R0201'             | '(SMR0201AW)'                  | '4.99'    | '1%'    | '1/20W'  | 'DISCRETE' | 'RES CHIP 4.99 1/20W +-1%(0201)'                   | 'CHIP0201'     | ''          | ''            | '20120615'
 '4.99'       | '1%'      | '1/20W'  | '0201LF'  | 'EMPTY'  | 'CS-4991FE00'(!)        = ''              | ''                 | 'CS-4991FE00'           | 'R0201'             | '(SMR0201AW)'                  | '4.99'    | '1%'    | '1/20W'  | 'IO'       | 'RES CHIP 4.99 1/20W +-1%(0201)'                   | 'CHIP0201'     | ''          | ''            | '20120615'
 '301'        | '1%'      | '1/20W'  | '0201LF'  | 'CHIP'   | 'CS13011FE01'(!)        = ''              | ''                 | 'CS13011FE01'           | 'R0201'             | '(SMR0201AW)'                  | '301'     | '1%'    | '1/20W'  | 'DISCRETE' | 'RES CHIP 301 1/20W +-1%(0201)'                    | 'CHIP0201'     | ''          | ''            | '20120615'
 '301'        | '1%'      | '1/20W'  | '0201LF'  | 'EMPTY'  | 'CS13011FE01'(!)        = ''              | ''                 | 'CS13011FE01'           | 'R0201'             | '(SMR0201AW)'                  | '301'     | '1%'    | '1/20W'  | 'IO'       | 'RES CHIP 301 1/20W +-1%(0201)'                    | 'CHIP0201'     | ''          | ''            | '20120615'
 '1.6K'       | '5%'      | '1/20W'  | '0201LF'  | 'CHIP'   | 'CS21601JE00'(!)        = ''              | ''                 | 'CS21601JE00'           | 'R0201'             | '(SMR0201AW)'                  | '1.6K'    | '5%'    | '1/20W'  | 'DISCRETE' | 'RES CHIP 1.6K 1/20W +-5%(0201)'                   | 'CHIP0201'     | ''          | ''            | '20120615'
 '1.6K'       | '5%'      | '1/20W'  | '0201LF'  | 'EMPTY'  | 'CS21601JE00'(!)        = ''              | ''                 | 'CS21601JE00'           | 'R0201'             | '(SMR0201AW)'                  | '1.6K'    | '5%'    | '1/20W'  | 'IO'       | 'RES CHIP 1.6K 1/20W +-5%(0201)'                   | 'CHIP0201'     | ''          | ''            | '20120615'
 '47K'        | '1%'      | '1/20W'  | '0201LF'  | 'CHIP'   | 'CS34701FE00'(!)        = ''              | ''                 | 'CS34701FE00'           | 'R0201'             | '(SMR0201AW)'                  | '47K'     | '1%'    | '1/20W'  | 'DISCRETE' | 'RES CHIP 47K 1/20W +-1%(0201)'                    | 'CHIP0201'     | ''          | ''            | '20120618'
 '47K'        | '1%'      | '1/20W'  | '0201LF'  | 'EMPTY'  | 'CS34701FE00'(!)        = ''              | ''                 | 'CS34701FE00'           | 'R0201'             | '(SMR0201AW)'                  | '47K'     | '1%'    | '1/20W'  | 'IO'       | 'RES CHIP 47K 1/20W +-1%(0201)'                    | 'CHIP0201'     | ''          | ''            | '20120618'
 '4.99K'      | '1%'      | '1/20W'  | '0201LF'  | 'CHIP'   | 'CS24991FE00'(!)        = ''              | ''                 | 'CS24991FE00'           | 'R0201'             | '(SMR0201AW)'                  | '4.99K'   | '1%'    | '1/20W'  | 'DISCRETE' | 'RES CHIP 4.99K(1/20W,+-1%,0201)'                  | 'CHIP0201'     | ''          | ''            | '20120622'
 '4.99K'      | '1%'      | '1/20W'  | '0201LF'  | 'EMPTY'  | 'CS24991FE00'(!)        = ''              | ''                 | 'CS24991FE00'           | 'R0201'             | '(SMR0201AW)'                  | '4.99K'   | '1%'    | '1/20W'  | 'IO'       | 'RES CHIP 4.99K(1/20W,+-1%,0201)'                  | 'CHIP0201'     | ''          | ''            | '20120622'
 '5.1K'       | '1%'      | '1/20W'  | '0201LF'  | 'CHIP'   | 'CS25101FE00'(!)        = 'End of Design' | 'Comp-Approve'     | 'CS25101FE00'           | 'R0201'             | '(SMR0201AW)'                  | '5.1K'    | '1%'    | '1/20W'  | 'DISCRETE' | 'RES CHIP 5.1K 1/20W +-1%(0201)'                   | 'CHIP0201'     | ''          | ''            | '20120622'
 '5.1K'       | '1%'      | '1/20W'  | '0201LF'  | 'EMPTY'  | 'CS25101FE00'(!)        = 'End of Design' | 'Comp-Approve'     | 'CS25101FE00'           | 'R0201'             | '(SMR0201AW)'                  | '5.1K'    | '1%'    | '1/20W'  | 'IO'       | 'RES CHIP 5.1K 1/20W +-1%(0201)'                   | 'CHIP0201'     | ''          | ''            | '20120622'
 '39.2'       | '1%'      | '1/16W'  | '0402LF'  | 'CHIP'   | 'CS03922FB01'(!)        = ''              | ''                 | 'CS03922FB01'           | 'R0402'             | '(R0402-0201)'                 | '39.2'    | '1%'    | '1/16W'  | 'DISCRETE' | 'RES CHIP 39.2 1/16W +-1%(0402)'                   | 'CHIP0402'     | ''          | ''            | '20120717'
 '39.2'       | '1%'      | '1/16W'  | '0402LF'  | 'EMPTY'  | 'CS03922FB01'(!)        = ''              | ''                 | 'CS03922FB01'           | 'R0402'             | '(R0402-0201)'                 | '39.2'    | '1%'    | '1/16W'  | 'IO'       | 'RES CHIP 39.2 1/16W +-1%(0402)'                   | 'CHIP0402'     | ''          | ''            | '20120717'
 '562K'       | '1%'      | '1/16W'  | '0402LF'  | 'CHIP'   | 'CS45622FB11'(!)        = 'End of Design' | 'Comp-Approve'     | 'CS45622FB11'           | 'R0402'             | '(R0402-0201)'                 | '562K'    | '1%'    | '1/16W'  | 'DISCRETE' | 'RES CHIP 562K 1/16W +-1%(0402)'                   | 'CHIP0402'     | ''          | ''            | '20120717'
 '562K'       | '1%'      | '1/16W'  | '0402LF'  | 'EMPTY'  | 'CS45622FB11'(!)        = 'End of Design' | 'Comp-Approve'     | 'CS45622FB11'           | 'R0402'             | '(R0402-0201)'                 | '562K'    | '1%'    | '1/16W'  | 'IO'       | 'RES CHIP 562K 1/16W +-1%(0402)'                   | 'CHIP0402'     | ''          | ''            | '20120717'
 '3.09K'      | '1%'      | '1/16W'  | '0402LF'  | 'CHIP'   | 'CS23092FB00'(!)        = 'End of Design' | 'Comp-Approve'     | 'CS23092FB00'           | 'R0402'             | '(R0402-0201)'                 | '3.09K'   | '1%'    | '1/16W'  | 'DISCRETE' | 'RES CHIP 3.09K 1/16W +-1%(0402)'                  | 'CHIP0402'     | ''          | ''            | '20120717'
 '3.09K'      | '1%'      | '1/16W'  | '0402LF'  | 'EMPTY'  | 'CS23092FB00'(!)        = 'End of Design' | 'Comp-Approve'     | 'CS23092FB00'           | 'R0402'             | '(R0402-0201)'                 | '3.09K'   | '1%'    | '1/16W'  | 'IO'       | 'RES CHIP 3.09K 1/16W +-1%(0402)'                  | 'CHIP0402'     | ''          | ''            | '20120717'
 '1.8K'       | '5%'      | '1/16W'  | '0402LF'  | 'CHIP'   | 'CS21802JB17'(!)        = 'End of Design' | 'Comp-Approve'     | 'CS21802JB17'           | 'R0402'             | '(R0402-0201)'                 | '1.8K'    | '5%'    | '1/16W'  | 'DISCRETE' | 'RES CHIP 1.8K 1/16W +-5%(0402)'                   | 'CHIP0402'     | ''          | ''            | '20120717'
 '1.8K'       | '5%'      | '1/16W'  | '0402LF'  | 'EMPTY'  | 'CS21802JB17'(!)        = 'End of Design' | 'Comp-Approve'     | 'CS21802JB17'           | 'R0402'             | '(R0402-0201)'                 | '1.8K'    | '5%'    | '1/16W'  | 'IO'       | 'RES CHIP 1.8K 1/16W +-5%(0402)'                   | 'CHIP0402'     | ''          | ''            | '20120717'
 '1M'         | '1%'      | '1/10W'  | '0603LF'  | 'CHIP'   | 'CS51003F934'(!)        = ''              | ''                 | 'CS51003F934'           | 'R0603'             | '(SMR0603AW)'                  | '1M'      | '1%'    | '1/10W'  | 'DISCRETE' | 'RESISTOR CHIP 1M 1/10W+-1%(0603)'                 | 'CHIP0603'     | ''          | ''            | '20120717'
 '1M'         | '1%'      | '1/10W'  | '0603LF'  | 'EMPTY'  | 'CS51003F934'(!)        = ''              | ''                 | 'CS51003F934'           | 'R0603'             | '(SMR0603AW)'                  | '1M'      | '1%'    | '1/10W'  | 'IO'       | 'RESISTOR CHIP 1M 1/10W+-1%(0603)'                 | 'CHIP0603'     | ''          | ''            | '20120717'
 '910'        | '1%'      | '1/16W'  | '0402LF'  | 'CHIP'   | 'CS19102FB01'(!)        = ''              | ''                 | 'CS19102FB01'           | 'R0402'             | '(R0402-0201)'                 | '910'     | '1%'    | '1/16W'  | 'DISCRETE' | 'RES CHIP 910(1/16W,1%,0402)'                      | 'CHIP0402'     | ''          | ''            | '20120724'
 '910'        | '1%'      | '1/16W'  | '0402LF'  | 'EMPTY'  | 'CS19102FB01'(!)        = ''              | ''                 | 'CS19102FB01'           | 'R0402'             | '(R0402-0201)'                 | '910'     | '1%'    | '1/16W'  | 'IO'       | 'RES CHIP 910(1/16W,1%,0402)'                      | 'CHIP0402'     | ''          | ''            | '20120724'
 '4.87K'      | '1%'      | '1/16W'  | '0402LF'  | 'CHIP'   | 'CS24872FB07'(!)        = 'End of Design' | 'Comp-Approve'     | 'CS24872FB07'           | 'R0402'             | '(R0402-0201)'                 | '4.87K'   | '1%'    | '1/16W'  | 'DISCRETE' | 'RES CHIP 4.87K 1/16W+-1%(0402)'                   | 'CHIP0402'     | ''          | ''            | '20120730'
 '4.87K'      | '1%'      | '1/16W'  | '0402LF'  | 'EMPTY'  | 'CS24872FB07'(!)        = 'End of Design' | 'Comp-Approve'     | 'CS24872FB07'           | 'R0402'             | '(R0402-0201)'                 | '4.87K'   | '1%'    | '1/16W'  | 'IO'       | 'RES CHIP 4.87K 1/16W+-1%(0402)'                   | 'CHIP0402'     | ''          | ''            | '20120730'
 '590'        | '1%'      | '1/16W'  | '0402LF'  | 'CHIP'   | 'CS15902FB00'(!)        = 'End of Design' | 'Comp-Approve'     | 'CS15902FB00'           | 'R0402'             | '(R0402-0201)'                 | '590'     | '1%'    | '1/16W'  | 'DISCRETE' | 'RES CHIP 590 1/16W +-1%(0402)'                    | 'CHIP0402'     | ''          | ''            | '20120801'
 '590'        | '1%'      | '1/16W'  | '0402LF'  | 'EMPTY'  | 'CS15902FB00'(!)        = 'End of Design' | 'Comp-Approve'     | 'CS15902FB00'           | 'R0402'             | '(R0402-0201)'                 | '590'     | '1%'    | '1/16W'  | 'IO'       | 'RES CHIP 590 1/16W +-1%(0402)'                    | 'CHIP0402'     | ''          | ''            | '20120801'
 '147K'       | '1%'      | '1/16W'  | '0402LF'  | 'CHIP'   | 'CS41472FB16'(!)        = 'End of Design' | 'Comp-Approve'     | 'CS41472FB16'           | 'R0402'             | '(R0402-0201)'                 | '147K'    | '1%'    | '1/16W'  | 'DISCRETE' | 'RES CHIP 147K 1/16W +-1%(0402)'                   | 'CHIP0402'     | ''          | ''            | '20120801'
 '147K'       | '1%'      | '1/16W'  | '0402LF'  | 'EMPTY'  | 'CS41472FB16'(!)        = 'End of Design' | 'Comp-Approve'     | 'CS41472FB16'           | 'R0402'             | '(R0402-0201)'                 | '147K'    | '1%'    | '1/16W'  | 'IO'       | 'RES CHIP 147K 1/16W +-1%(0402)'                   | 'CHIP0402'     | ''          | ''            | '20120801'
 '510K'       | '5%'      | '1/16W'  | '0402LF'  | 'CHIP'   | 'CS45102JB08'(!)        = ''              | ''                 | 'CS45102JB08'           | 'R0402'             | '(R0402-0201)'                 | '510K'    | '5%'    | '1/16W'  | 'DISCRETE' | 'RES CHIP 510K(1/16W.+-5%.0402)'                   | 'CHIP0402'     | ''          | ''            | '20120801'
 '510K'       | '5%'      | '1/16W'  | '0402LF'  | 'EMPTY'  | 'CS45102JB08'(!)        = ''              | ''                 | 'CS45102JB08'           | 'R0402'             | '(R0402-0201)'                 | '510K'    | '5%'    | '1/16W'  | 'IO'       | 'RES CHIP 510K(1/16W.+-5%.0402)'                   | 'CHIP0402'     | ''          | ''            | '20120801'
 '6.8K'       | '1%'      | '1/16W'  | '0402LF'  | 'CHIP'   | 'CS26802FB19'(!)        = 'End of Design' | 'Comp-Approve'     | 'CS26802FB19'           | 'R0402'             | '(R0402-0201)'                 | '6.8K'    | '1%'    | '1/16W'  | 'DISCRETE' | 'RES CHIP 6.8K 1/16W +-1%(0402)'                   | 'CHIP0402'     | ''          | ''            | '20120801'
 '6.8K'       | '1%'      | '1/16W'  | '0402LF'  | 'EMPTY'  | 'CS26802FB19'(!)        = 'End of Design' | 'Comp-Approve'     | 'CS26802FB19'           | 'R0402'             | '(R0402-0201)'                 | '6.8K'    | '1%'    | '1/16W'  | 'IO'       | 'RES CHIP 6.8K 1/16W +-1%(0402)'                   | 'CHIP0402'     | ''          | ''            | '20120801'
 '619'        | '1%'      | '1/16W'  | '0402LF'  | 'CHIP'   | 'CS16192FB04'(!)        = ''              | ''                 | 'CS16192FB04'           | 'R0402'             | '(R0402-0201)'                 | '619'     | '1%'    | '1/16W'  | 'DISCRETE' | ' RES CHIP 619 1/16W +-1%(0402)'                   | 'CHIP0402'     | ''          | ''            | '20120807'
 '619'        | '1%'      | '1/16W'  | '0402LF'  | 'EMPTY'  | 'CS16192FB04'(!)        = ''              | ''                 | 'CS16192FB04'           | 'R0402'             | '(R0402-0201)'                 | '619'     | '1%'    | '1/16W'  | 'IO'       | ' RES CHIP 619 1/16W +-1%(0402)'                   | 'CHIP0402'     | ''          | ''            | '20120807'
 '11'         | '1%'      | '1/16W'  | '0402LF'  | 'CHIP'   | 'CS01102FB08'(!)        = 'End of Design' | 'Comp-Approve'     | 'CS01102FB08'           | 'R0402'             | '(R0402-0201)'                 | '11'      | '1%'    | '1/16W'  | 'DISCRETE' | 'RES CHIP 11 1/16W +-1%(0402)'                     | 'CHIP0402'     | ''          | ''            | '20120808'
 '11'         | '1%'      | '1/16W'  | '0402LF'  | 'EMPTY'  | 'CS01102FB08'(!)        = 'End of Design' | 'Comp-Approve'     | 'CS01102FB08'           | 'R0402'             | '(R0402-0201)'                 | '11'      | '1%'    | '1/16W'  | 'IO'       | 'RES CHIP 11 1/16W +-1%(0402)'                     | 'CHIP0402'     | ''          | ''            | '20120808'
 '191'        | '1%'      | '1/16W'  | '0402LF'  | 'CHIP'   | 'CS11912FB00'(!)        = 'End of Design' | 'Comp-Approve'     | 'CS11912FB00'           | 'R0402'             | '(R0402-0201)'                 | '191'     | '1%'    | '1/16W'  | 'DISCRETE' | 'RES CHIP 191 1/16W +-1%(0402)'                    | 'CHIP0402'     | ''          | ''            | '20120813'
 '191'        | '1%'      | '1/16W'  | '0402LF'  | 'EMPTY'  | 'CS11912FB00'(!)        = 'End of Design' | 'Comp-Approve'     | 'CS11912FB00'           | 'R0402'             | '(R0402-0201)'                 | '191'     | '1%'    | '1/16W'  | 'IO'       | 'RES CHIP 191 1/16W +-1%(0402)'                    | 'CHIP0402'     | ''          | ''            | '20120813'
 '27K'        | '1%'      | '1/16W'  | '0402LF'  | 'CHIP'   | 'CS32702FB16'(!)        = 'End of Design' | 'Comp-Approve'     | 'CS32702FB16'           | 'R0402'             | '(R0402-0201)'                 | '27K'     | '1%'    | '1/16W'  | 'DISCRETE' | 'RES CHIP 27K 1/16W +-1%(0402)'                    | 'CHIP0402'     | ''          | ''            | '20120816'
 '27K'        | '1%'      | '1/16W'  | '0402LF'  | 'EMPTY'  | 'CS32702FB16'(!)        = 'End of Design' | 'Comp-Approve'     | 'CS32702FB16'           | 'R0402'             | '(R0402-0201)'                 | '27K'     | '1%'    | '1/16W'  | 'IO'       | 'RES CHIP 27K 1/16W +-1%(0402)'                    | 'CHIP0402'     | ''          | ''            | '20120816'
 '255K'       | '1%'      | '1/16W'  | '0402LF'  | 'CHIP'   | 'CS42552FB05'(!)        = 'End of Design' | 'Comp-Approve'     | 'CS42552FB05'           | 'R0402'             | '(R0402-0201)'                 | '255K'    | '1%'    | '1/16W'  | 'DISCRETE' | 'RES CHIP 255K 1/16W +-1%(0402)'                   | 'CHIP0402'     | ''          | ''            | '20120816'
 '255K'       | '1%'      | '1/16W'  | '0402LF'  | 'EMPTY'  | 'CS42552FB05'(!)        = 'End of Design' | 'Comp-Approve'     | 'CS42552FB05'           | 'R0402'             | '(R0402-0201)'                 | '255K'    | '1%'    | '1/16W'  | 'IO'       | 'RES CHIP 255K 1/16W +-1%(0402)'                   | 'CHIP0402'     | ''          | ''            | '20120816'
 '226'        | '1%'      | '1/16W'  | '0402LF'  | 'CHIP'   | 'CS12262FB11'(!)        = 'End of Design' | 'Comp-Approve'     | 'CS12262FB11'           | 'R0402'             | '(R0402-0201)'                 | '226'     | '1%'    | '1/16W'  | 'DISCRETE' | 'RES CHIP 226. 1/16W. +-1% (0402)'                 | 'CHIP0402'     | ''          | ''            | '20120829'
 '226'        | '1%'      | '1/16W'  | '0402LF'  | 'EMPTY'  | 'CS12262FB11'(!)        = 'End of Design' | 'Comp-Approve'     | 'CS12262FB11'           | 'R0402'             | '(R0402-0201)'                 | '226'     | '1%'    | '1/16W'  | 'IO'       | 'RES CHIP 226. 1/16W. +-1% (0402)'                 | 'CHIP0402'     | ''          | ''            | '20120829'
 '52.3K'      | '1%'      | '1/16W'  | '0402LF'  | 'CHIP'   | 'CS35232FB01'(!)        = ''              | ''                 | 'CS35232FB01'           | 'R0402'             | '(R0402-0201)'                 | '52.3K'   | '1%'    | '1/16W'  | 'DISCRETE' | 'RES CHIP 52.3K 1/16W +-1% (0402)'                 | 'CHIP0402'     | ''          | ''            | '20120904'
 '52.3K'      | '1%'      | '1/16W'  | '0402LF'  | 'EMPTY'  | 'CS35232FB01'(!)        = ''              | ''                 | 'CS35232FB01'           | 'R0402'             | '(R0402-0201)'                 | '52.3K'   | '1%'    | '1/16W'  | 'IO'       | 'RES CHIP 52.3K 1/16W +-1% (0402)'                 | 'CHIP0402'     | ''          | ''            | '20120904'
 '274K'       | '1%'      | '1/16W'  | '0402LF'  | 'CHIP'   | 'CS42742FB00'(!)        = 'End of Design' | 'Comp-Approve'     | 'CS42742FB00'           | 'R0402'             | '(R0402-0201)'                 | '274K'    | '1%'    | '1/16W'  | 'DISCRETE' | 'RES CHP 274K 1/16W +-1%(0402)'                    | 'CHIP0402'     | ''          | ''            | '20120904'
 '274K'       | '1%'      | '1/16W'  | '0402LF'  | 'EMPTY'  | 'CS42742FB00'(!)        = 'End of Design' | 'Comp-Approve'     | 'CS42742FB00'           | 'R0402'             | '(R0402-0201)'                 | '274K'    | '1%'    | '1/16W'  | 'IO'       | 'RES CHP 274K 1/16W +-1%(0402)'                    | 'CHIP0402'     | ''          | ''            | '20120904'
 '487K'       | '1%'      | '1/16W'  | '0402LF'  | 'CHIP'   | 'CS44872FB19'(!)        = 'End of Design' | 'Comp-Approve'     | 'CS44872FB19'           | 'R0402'             | '(R0402-0201)'                 | '487K'    | '1%'    | '1/16W'  | 'DISCRETE' | 'RES CHIP 487K 1/16W +-1%( 0402)L-F'               | 'CHIP0402'     | ''          | ''            | '20120904'
 '487K'       | '1%'      | '1/16W'  | '0402LF'  | 'EMPTY'  | 'CS44872FB19'(!)        = 'End of Design' | 'Comp-Approve'     | 'CS44872FB19'           | 'R0402'             | '(R0402-0201)'                 | '487K'    | '1%'    | '1/16W'  | 'IO'       | 'RES CHIP 487K 1/16W +-1%( 0402)L-F'               | 'CHIP0402'     | ''          | ''            | '20120904'
 '2.87K'      | '1%'      | '1/16W'  | '0402LF'  | 'CHIP'   | 'CS22872FB10'(!)        = 'End of Design' | 'Comp-Approve'     | 'CS22872FB10'           | 'R0402'             | '(R0402-0201)'                 | '2.87K'   | '1%'    | '1/16W'  | 'DISCRETE' | 'RES CHIP 2.87K 1/16W +-1%(0402)'                  | 'CHIP0402'     | ''          | ''            | '20120904'
 '2.87K'      | '1%'      | '1/16W'  | '0402LF'  | 'EMPTY'  | 'CS22872FB10'(!)        = 'End of Design' | 'Comp-Approve'     | 'CS22872FB10'           | 'R0402'             | '(R0402-0201)'                 | '2.87K'   | '1%'    | '1/16W'  | 'IO'       | 'RES CHIP 2.87K 1/16W +-1%(0402)'                  | 'CHIP0402'     | ''          | ''            | '20120904'
 '316K'       | '1%'      | '1/16W'  | '0402LF'  | 'CHIP'   | 'CS43162FB00'(!)        = 'End of Design' | 'Comp-Approve'     | 'CS43162FB00'           | 'R0402'             | '(R0402-0201)'                 | '316K'    | '1%'    | '1/16W'  | 'DISCRETE' | 'RES CHIP 316K 1/16W +-1%(0402)'                   | 'CHIP0402'     | ''          | ''            | '20120906'
 '316K'       | '1%'      | '1/16W'  | '0402LF'  | 'EMPTY'  | 'CS43162FB00'(!)        = 'End of Design' | 'Comp-Approve'     | 'CS43162FB00'           | 'R0402'             | '(R0402-0201)'                 | '316K'    | '1%'    | '1/16W'  | 'IO'       | 'RES CHIP 316K 1/16W +-1%(0402)'                   | 'CHIP0402'     | ''          | ''            | '20120906'
 '348K'       | '1%'      | '1/16W'  | '0402LF'  | 'CHIP'   | 'CS43482FB16'(!)        = 'End of Design' | 'Comp-Approve'     | 'CS43482FB16'           | 'R0402'             | '(R0402-0201)'                 | '348K'    | '1%'    | '1/16W'  | 'DISCRETE' | 'RES CHIP 348K 1/16W +-1%( 0402)'                  | 'CHIP0402'     | ''          | ''            | '20120906'
 '348K'       | '1%'      | '1/16W'  | '0402LF'  | 'EMPTY'  | 'CS43482FB16'(!)        = 'End of Design' | 'Comp-Approve'     | 'CS43482FB16'           | 'R0402'             | '(R0402-0201)'                 | '348K'    | '1%'    | '1/16W'  | 'IO'       | 'RES CHIP 348K 1/16W +-1%( 0402)'                  | 'CHIP0402'     | ''          | ''            | '20120906'
 '360K'       | '1%'      | '1/16W'  | '0402LF'  | 'CHIP'   | 'CS43602FB00'(!)        = 'End of Design' | 'Comp-Approve'     | 'CS43602FB00'           | 'R0402'             | '(R0402-0201)'                 | '360K'    | '1%'    | '1/16W'  | 'DISCRETE' | 'RES CHIP 360K 1/16W +-1%(0402)'                   | 'CHIP0402'     | ''          | ''            | '20120906'
 '360K'       | '1%'      | '1/16W'  | '0402LF'  | 'EMPTY'  | 'CS43602FB00'(!)        = 'End of Design' | 'Comp-Approve'     | 'CS43602FB00'           | 'R0402'             | '(R0402-0201)'                 | '360K'    | '1%'    | '1/16W'  | 'IO'       | 'RES CHIP 360K 1/16W +-1%(0402)'                   | 'CHIP0402'     | ''          | ''            | '20120906'
 '499'        | '1%'      | '1/16W'  | '0402LF'  | 'CHIP'   | 'CS14992FB24'(!)        = 'End of Design' | 'Comp-Approve'     | 'CS14992FB24'           | 'R0402'             | '(R0402-0201)'                 | '499'     | '1%'    | '1/16W'  | 'DISCRETE' | 'RES CHIP 499 1/16W +-1%(0402)'                    | 'CHIP0402'     | ''          | ''            | '20120913'
 '499'        | '1%'      | '1/16W'  | '0402LF'  | 'EMPTY'  | 'CS14992FB24'(!)        = 'End of Design' | 'Comp-Approve'     | 'CS14992FB24'           | 'R0402'             | '(R0402-0201)'                 | '499'     | '1%'    | '1/16W'  | 'IO'       | 'RES CHIP 499 1/16W +-1%(0402)'                    | 'CHIP0402'     | ''          | ''            | '20120913'
 '1.82K'      | '1%'      | '1/16W'  | '0402LF'  | 'CHIP'   | 'CS21822FB14'(!)        = 'End of Design' | 'Comp-Approve'     | 'CS21822FB14'           | 'R0402'             | '(R0402-0201)'                 | '1.82K'   | '1%'    | '1/16W'  | 'DISCRETE' | 'RES CHIP 1.82K 1/16W +-1%(0402)'                  | 'CHIP0402'     | ''          | ''            | '20120913'
 '1.82K'      | '1%'      | '1/16W'  | '0402LF'  | 'EMPTY'  | 'CS21822FB14'(!)        = 'End of Design' | 'Comp-Approve'     | 'CS21822FB14'           | 'R0402'             | '(R0402-0201)'                 | '1.82K'   | '1%'    | '1/16W'  | 'IO'       | 'RES CHIP 1.82K 1/16W +-1%(0402)'                  | 'CHIP0402'     | ''          | ''            | '20120913'
 '3.24K'      | '1%'      | '1/16W'  | '0402LF'  | 'CHIP'   | 'CS23242FB17'(!)        = 'End of Design' | 'Comp-Approve'     | 'CS23242FB17'           | 'R0402'             | '(R0402-0201)'                 | '3.24K'   | '1%'    | '1/16W'  | 'DISCRETE' | 'RES CHIP 3.24K +-1% 1/16W(0402) EP'               | 'CHIP0402'     | ''          | ''            | '20120913'
 '3.24K'      | '1%'      | '1/16W'  | '0402LF'  | 'EMPTY'  | 'CS23242FB17'(!)        = 'End of Design' | 'Comp-Approve'     | 'CS23242FB17'           | 'R0402'             | '(R0402-0201)'                 | '3.24K'   | '1%'    | '1/16W'  | 'IO'       | 'RES CHIP 3.24K +-1% 1/16W(0402) EP'               | 'CHIP0402'     | ''          | ''            | '20120913'
 '2.0'        | '1%'      | '1/16W'  | '0402LF'  | 'CHIP'   | 'CS-2002FB00'(!)        = 'End of Design' | 'Comp-Approve'     | 'CS-2002FB00'           | 'R0402'             | '(R0402-0201)'                 | '2.0'     | '1%'    | '1/16W'  | 'DISCRETE' | 'RES CHIP 2.0 1/16W +1%(0402)'                     | 'CHIP0402'     | ''          | ''            | '20120919'
 '2.0'        | '1%'      | '1/16W'  | '0402LF'  | 'EMPTY'  | 'CS-2002FB00'(!)        = 'End of Design' | 'Comp-Approve'     | 'CS-2002FB00'           | 'R0402'             | '(R0402-0201)'                 | '2.0'     | '1%'    | '1/16W'  | 'IO'       | 'RES CHIP 2.0 1/16W +1%(0402)'                     | 'CHIP0402'     | ''          | ''            | '20120919'
 '32.4K'      | '1%'      | '1/16W'  | '0402LF'  | 'CHIP'   | 'CS33242FB19'(!)        = 'End of Design' | 'Comp-Approve'     | 'CS33242FB19'           | 'R0402'             | '(R0402-0201)'                 | '32.4K'   | '1%'    | '1/16W'  | 'DISCRETE' | 'RES CHIP 32.4K 1/16W +-1%(0402)'                  | 'CHIP0402'     | ''          | ''            | '20120925'
 '32.4K'      | '1%'      | '1/16W'  | '0402LF'  | 'EMPTY'  | 'CS33242FB19'(!)        = 'End of Design' | 'Comp-Approve'     | 'CS33242FB19'           | 'R0402'             | '(R0402-0201)'                 | '32.4K'   | '1%'    | '1/16W'  | 'IO'       | 'RES CHIP 32.4K 1/16W +-1%(0402)'                  | 'CHIP0402'     | ''          | ''            | '20120925'
 '1.4K'       | '1%'      | '1/16W'  | '0402LF'  | 'CHIP'   | 'CS21402FB02'(!)        = 'End of Design' | 'Comp-Approve'     | 'CS21402FB02'           | 'R0402'             | '(R0402-0201)'                 | '1.4K'    | '1%'    | '1/16W'  | 'DISCRETE' | 'RES CHIP 1.4K 1/16W +-1%(0402)'                   | 'CHIP0402'     | ''          | ''            | '20120925'
 '1.4K'       | '1%'      | '1/16W'  | '0402LF'  | 'EMPTY'  | 'CS21402FB02'(!)        = 'End of Design' | 'Comp-Approve'     | 'CS21402FB02'           | 'R0402'             | '(R0402-0201)'                 | '1.4K'    | '1%'    | '1/16W'  | 'IO'       | 'RES CHIP 1.4K 1/16W +-1%(0402)'                   | 'CHIP0402'     | ''          | ''            | '20120925'
 '825'        | '1%'      | '1/16W'  | '0402LF'  | 'CHIP'   | 'CS18252FB00'(!)        = 'End of Design' | 'Comp-Approve'     | 'CS18252FB00'           | 'R0402'             | '(R0402-0201)'                 | '825'     | '1%'    | '1/16W'  | 'DISCRETE' | 'RES CHIP 825 1/16W +-1% (0402)'                   | 'CHIP0402'     | ''          | ''            | '20121003'
 '825'        | '1%'      | '1/16W'  | '0402LF'  | 'EMPTY'  | 'CS18252FB00'(!)        = 'End of Design' | 'Comp-Approve'     | 'CS18252FB00'           | 'R0402'             | '(R0402-0201)'                 | '825'     | '1%'    | '1/16W'  | 'IO'       | 'RES CHIP 825 1/16W +-1% (0402)'                   | 'CHIP0402'     | ''          | ''            | '20121003'
 '61.9'       | '1%'      | '1/16W'  | '0402LF'  | 'CHIP'   | 'CS06192FB02'(!)        = 'End of Design' | 'Comp-Approve'     | 'CS06192FB02'           | 'R0402'             | '(R0402-0201)'                 | '61.9'    | '1%'    | '1/16W'  | 'DISCRETE' | 'RES CHIP 61.9 1/16W 1%(0402)'                     | 'CHIP0402'     | ''          | ''            | '20121017'
 '61.9'       | '1%'      | '1/16W'  | '0402LF'  | 'EMPTY'  | 'CS06192FB02'(!)        = 'End of Design' | 'Comp-Approve'     | 'CS06192FB02'           | 'R0402'             | '(R0402-0201)'                 | '61.9'    | '1%'    | '1/16W'  | 'IO'       | 'RES CHIP 61.9 1/16W 1%(0402)'                     | 'CHIP0402'     | ''          | ''            | '20121017'
 '0'          | '1%'      | '1/2W'   | '1206LF'  | 'CHIP'   | 'CS00007F200'(!)        = ''              | ''                 | 'CS00007F200'           | 'R1206'             | '(SMR1206AW)'                  | '0'       | '1%'    | '1/2W'   | 'DISCRETE' | 'RES CHIP 0 1/2W +-1%(1206)'                       | 'CHIP1206'     | ''          | ''            | '20121023'
 '0'          | '1%'      | '1/2W'   | '1206LF'  | 'EMPTY'  | 'CS00007F200'(!)        = ''              | ''                 | 'CS00007F200'           | 'R1206'             | '(SMR1206AW)'                  | '0'       | '1%'    | '1/2W'   | 'IO'       | 'RES CHIP 0 1/2W +-1%(1206)'                       | 'CHIP1206'     | ''          | ''            | '20121023'
 '0.001'      | '1%'      | '1W'     | '3720LF'  | 'CHIP'   | 'CS+0018FL00'(!)        = ''              | ''                 | 'CS+0018FL00'           | 'R3720'             | '(SMR3720AW)'                  | '0.001'   | '1%'    | '1W'     | 'DISCRETE' | 'RES CHIP 0.001 1W +-1%(3720)'                     | 'CHIP3720'     | ''          | ''            | '20121023'
 '0.001'      | '1%'      | '1W'     | '3720LF'  | 'EMPTY'  | 'CS+0018FL00'(!)        = ''              | ''                 | 'CS+0018FL00'           | 'R3720'             | '(SMR3720AW)'                  | '0.001'   | '1%'    | '1W'     | 'IO'       | 'RES CHIP 0.001 1W +-1%(3720)'                     | 'CHIP3720'     | ''          | ''            | '20121023'
 '6.8M'       | '5%'      | '1/16W'  | '0402LF'  | 'CHIP'   | 'CS56802JB00'(!)        = ''              | ''                 | 'CS56802JB00'           | 'R0402'             | '(R0402-0201)'                 | '6.8M'    | '5%'    | '1/16W'  | 'DISCRETE' | 'RESISTOR CHIP 6.8M 1/16W +-5%(0402)'              | 'CHIP0402'     | ''          | ''            | '20121024'
 '6.8M'       | '5%'      | '1/16W'  | '0402LF'  | 'EMPTY'  | 'CS56802JB00'(!)        = ''              | ''                 | 'CS56802JB00'           | 'R0402'             | '(R0402-0201)'                 | '6.8M'    | '5%'    | '1/16W'  | 'IO'       | 'RESISTOR CHIP 6.8M 1/16W +-5%(0402)'              | 'CHIP0402'     | ''          | ''            | '20121024'
 '0.004'      | '1%'      | '1W'     | '1206LF'  | 'CHIP'   | 'CS+0048F200'(!)        = ''              | ''                 | 'CS+0048F200'           | 'R1206XA'           | '(SMR1206AW)'                  | '0.004'   | '1%'    | '1W'     | 'DISCRETE' | 'RES CHIP 0.004 1W +-1%(1206)'                     | 'CHIP1206'     | ''          | ''            | '20121029'
 '0.004'      | '1%'      | '1W'     | '1206LF'  | 'EMPTY'  | 'CS+0048F200'(!)        = ''              | ''                 | 'CS+0048F200'           | 'R1206XA'           | '(SMR1206AW)'                  | '0.004'   | '1%'    | '1W'     | 'IO'       | 'RES CHIP 0.004 1W +-1%(1206)'                     | 'CHIP1206'     | ''          | ''            | '20121029'
 '255'        | '1%'      | '1/16W'  | '0402LF'  | 'CHIP'   | 'CS12552FB18'(!)        = 'End of Design' | 'Comp-Approve'     | 'CS12552FB18'           | 'R0402'             | '(R0402-0201)'                 | '255'     | '1%'    | '1/16W'  | 'DISCRETE' | 'RES CHIP 255 1/16W +-1%(0402)'                    | 'CHIP0402'     | ''          | ''            | '20121031'
 '255'        | '1%'      | '1/16W'  | '0402LF'  | 'EMPTY'  | 'CS12552FB18'(!)        = 'End of Design' | 'Comp-Approve'     | 'CS12552FB18'           | 'R0402'             | '(R0402-0201)'                 | '255'     | '1%'    | '1/16W'  | 'IO'       | 'RES CHIP 255 1/16W +-1%(0402)'                    | 'CHIP0402'     | ''          | ''            | '20121031'
 '261K'       | '1%'      | '1/16'   | '0402LF'  | 'CHIP'   | 'CS42612FB00'(!)        = 'End of Design' | 'Comp-Approve'     | 'CS42612FB00'           | 'R0402'             | '(R0402-0201)'                 | '261K'    | '1%'    | '1/16'   | 'DISCRETE' | 'RES CHIP 261K 1/16 +-1%(0402)'                    | 'CHIP0402'     | ''          | ''            | '20121114'
 '261K'       | '1%'      | '1/16'   | '0402LF'  | 'EMPTY'  | 'CS42612FB00'(!)        = 'End of Design' | 'Comp-Approve'     | 'CS42612FB00'           | 'R0402'             | '(R0402-0201)'                 | '261K'    | '1%'    | '1/16'   | 'IO'       | 'RES CHIP 261K 1/16 +-1%(0402)'                    | 'CHIP0402'     | ''          | ''            | '20121114'
 '680K'       | '1%'      | '1/16'   | '0402LF'  | 'CHIP'   | 'CS46802FB00'(!)        = 'End of Design' | 'Comp-Approve'     | 'CS46802FB00'           | 'R0402'             | '(R0402-0201)'                 | '680K'    | '1%'    | '1/16'   | 'DISCRETE' | 'RES CHIP 680K 1/16W +-1%(0402)'                   | 'CHIP0402'     | ''          | ''            | '20121115'
 '680K'       | '1%'      | '1/16'   | '0402LF'  | 'EMPTY'  | 'CS46802FB00'(!)        = 'End of Design' | 'Comp-Approve'     | 'CS46802FB00'           | 'R0402'             | '(R0402-0201)'                 | '680K'    | '1%'    | '1/16'   | 'IO'       | 'RES CHIP 680K 1/16W +-1%(0402)'                   | 'CHIP0402'     | ''          | ''            | '20121115'
 '649'        | '1%'      | '1/16W'  | '0402LF'  | 'CHIP'   | 'CS16492FB13'(!)        = 'End of Design' | 'Comp-Approve'     | 'CS16492FB13'           | 'R0402'             | '(R0402-0201)'                 | '649'     | '1%'    | '1/16W'  | 'DISCRETE' | 'RES CHIP 649 1/16W +-1%(0402) -EP'                | 'CHIP0402'     | ''          | ''            | '20121120'
 '649'        | '1%'      | '1/16W'  | '0402LF'  | 'EMPTY'  | 'CS16492FB13'(!)        = 'End of Design' | 'Comp-Approve'     | 'CS16492FB13'           | 'R0402'             | '(R0402-0201)'                 | '649'     | '1%'    | '1/16W'  | 'IO'       | 'RES CHIP 649 1/16W +-1%(0402) -EP'                | 'CHIP0402'     | ''          | ''            | '20121120'
 '160'        | '1%'      | '1/16W'  | '0402LF'  | 'CHIP'   | 'CS11602FB00'(!)        = 'End of Design' | 'Comp-Approve'     | 'CS11602FB00'           | 'R0402'             | '(R0402-0201)'                 | '160'     | '1%'    | '1/16W'  | 'DISCRETE' | 'RES CHIP 160 1/16W +-1%(0402)'                    | 'CHIP0402'     | ''          | ''            | '20121122'
 '160'        | '1%'      | '1/16W'  | '0402LF'  | 'EMPTY'  | 'CS11602FB00'(!)        = 'End of Design' | 'Comp-Approve'     | 'CS11602FB00'           | 'R0402'             | '(R0402-0201)'                 | '160'     | '1%'    | '1/16W'  | 'IO'       | 'RES CHIP 160 1/16W +-1%(0402)'                    | 'CHIP0402'     | ''          | ''            | '20121122'
 '390'        | '1%'      | '1/10W'  | '0603LF'  | 'CHIP'   | 'CS13903F919'(!)        = ''              | ''                 | 'CS13903F919'           | 'R0603'             | '(SMR0603AW)'                  | '390'     | '1%'    | '1/10W'  | 'DISCRETE' | 'RES CHIP 390 1/10W +-1%(0603)'                    | 'CHIP0603'     | ''          | ''            | '20121128'
 '390'        | '1%'      | '1/10W'  | '0603LF'  | 'EMPTY'  | 'CS13903F919'(!)        = ''              | ''                 | 'CS13903F919'           | 'R0603'             | '(SMR0603AW)'                  | '390'     | '1%'    | '1/10W'  | 'IO'       | 'RES CHIP 390 1/10W +-1%(0603)'                    | 'CHIP0603'     | ''          | ''            | '20121128'
 '82.5K'      | '1%'      | '1/16W'  | '0402LF'  | 'CHIP'   | 'CS38252FB17'(!)        = 'End of Design' | 'Comp-Approve'     | 'CS38252FB17'           | 'R0402'             | '(R0402-0201)'                 | '82.5K'   | '1%'    | '1/16W'  | 'DISCRETE' | 'RES CHIP 82.5K 1/16W +-1%(0402)'                  | 'CHIP0402'     | ''          | ''            | '20121128'
 '82.5K'      | '1%'      | '1/16W'  | '0402LF'  | 'EMPTY'  | 'CS38252FB17'(!)        = 'End of Design' | 'Comp-Approve'     | 'CS38252FB17'           | 'R0402'             | '(R0402-0201)'                 | '82.5K'   | '1%'    | '1/16W'  | 'IO'       | 'RES CHIP 82.5K 1/16W +-1%(0402)'                  | 'CHIP0402'     | ''          | ''            | '20121128'
 '604K'       | '1%'      | '1/16W'  | '0402LF'  | 'CHIP'   | 'CS46042FB11'(!)        = 'End of Design' | 'Comp-Approve'     | 'CS46042FB11'           | 'R0402'             | '(R0402-0201)'                 | '604K'    | '1%'    | '1/16W'  | 'DISCRETE' | 'RES CHIP 604K 1/16W +-1%(0402)'                   | 'CHIP0402'     | ''          | ''            | '20121128'
 '604K'       | '1%'      | '1/16W'  | '0402LF'  | 'EMPTY'  | 'CS46042FB11'(!)        = 'End of Design' | 'Comp-Approve'     | 'CS46042FB11'           | 'R0402'             | '(R0402-0201)'                 | '604K'    | '1%'    | '1/16W'  | 'IO'       | 'RES CHIP 604K 1/16W +-1%(0402)'                   | 'CHIP0402'     | ''          | ''            | '20121128'
 '10.5K'      | '1%'      | '1/16W'  | '0402LF'  | 'CHIP'   | 'CS31052FB02'(!)        = 'End of Design' | 'Comp-Approve'     | 'CS31052FB02'           | 'R0402'             | '(R0402-0201)'                 | '10.5K'   | '1%'    | '1/16W'  | 'DISCRETE' | 'RES CHIP 10.5K 1/16W +-1%( 0402)'                 | 'CHIP0402'     | ''          | ''            | '20121204'
 '10.5K'      | '1%'      | '1/16W'  | '0402LF'  | 'EMPTY'  | 'CS31052FB02'(!)        = 'End of Design' | 'Comp-Approve'     | 'CS31052FB02'           | 'R0402'             | '(R0402-0201)'                 | '10.5K'   | '1%'    | '1/16W'  | 'IO'       | 'RES CHIP 10.5K 1/16W +-1%( 0402)'                 | 'CHIP0402'     | ''          | ''            | '20121204'
 '34.8K'      | '1%'      | '1/16W'  | '0402LF'  | 'CHIP'   | 'CS33482FB22'(!)        = 'End of Design' | 'Comp-Approve'     | 'CS33482FB22'           | 'R0402'             | '(R0402-0201)'                 | '34.8K'   | '1%'    | '1/16W'  | 'DISCRETE' | 'RES CHIP 34.8K 1/16W +-1% (0402)EP'               | 'CHIP0402'     | ''          | ''            | '20121204'
 '34.8K'      | '1%'      | '1/16W'  | '0402LF'  | 'EMPTY'  | 'CS33482FB22'(!)        = 'End of Design' | 'Comp-Approve'     | 'CS33482FB22'           | 'R0402'             | '(R0402-0201)'                 | '34.8K'   | '1%'    | '1/16W'  | 'IO'       | 'RES CHIP 34.8K 1/16W +-1% (0402)EP'               | 'CHIP0402'     | ''          | ''            | '20121204'
 '2.2'        | '5%'      | '1/2W'   | '1210LF'  | 'CHIP'   | 'CS-2207J311'(!)        = ''              | ''                 | 'CS-2207J311'           | 'R1210'             | '(SMR1210AW)'                  | '2.2'     | '5%'    | '1/2W'   | 'DISCRETE' | 'RES CHIP 2.2 1/2W +-5%(1210)'                     | 'CHIP1210'     | ''          | ''            | '20121210'
 '2.2'        | '5%'      | '1/2W'   | '1210LF'  | 'EMPTY'  | 'CS-2207J311'(!)        = ''              | ''                 | 'CS-2207J311'           | 'R1210'             | '(SMR1210AW)'                  | '2.2'     | '5%'    | '1/2W'   | 'IO'       | 'RES CHIP 2.2 1/2W +-5%(1210)'                     | 'CHIP1210'     | ''          | ''            | '20121210'
 '62'         | '1%'      | '1/16W'  | '0402LF'  | 'CHIP'   | 'CS06202FB13'(!)        = 'End of Design' | 'Comp-Approve'     | 'CS06202FB13'           | 'R0402'             | '(R0402-0201)'                 | '62'      | '1%'    | '1/16W'  | 'DISCRETE' | 'RES CHIP 62 1/16W +-1%(0402)'                     | 'CHIP0402'     | ''          | ''            | '20121216'
 '62'         | '1%'      | '1/16W'  | '0402LF'  | 'EMPTY'  | 'CS06202FB13'(!)        = 'End of Design' | 'Comp-Approve'     | 'CS06202FB13'           | 'R0402'             | '(R0402-0201)'                 | '62'      | '1%'    | '1/16W'  | 'IO'       | 'RES CHIP 62 1/16W +-1%(0402)'                     | 'CHIP0402'     | ''          | ''            | '20121216'
 '62'         | '5%'      | '1/16W'  | '0402LF'  | 'CHIP'   | 'CS06202JB15'(!)        = ''              | ''                 | 'CS06202JB15'           | 'R0402'             | '(R0402-0201)'                 | '62'      | '5%'    | '1/16W'  | 'DISCRETE' | 'RES CHIP 62 1/16W +-5%(0402)'                     | 'CHIP0402'     | ''          | ''            | '20121216'
 '62'         | '5%'      | '1/16W'  | '0402LF'  | 'EMPTY'  | 'CS06202JB15'(!)        = ''              | ''                 | 'CS06202JB15'           | 'R0402'             | '(R0402-0201)'                 | '62'      | '5%'    | '1/16W'  | 'IO'       | 'RES CHIP 62 1/16W +-5%(0402)'                     | 'CHIP0402'     | ''          | ''            | '20121216'
 '33.2K'      | '1%'      | '1/16W'  | '0402LF'  | 'CHIP'   | 'CS33322FB13'(!)        = 'End of Design' | 'Comp-Approve'     | 'CS33322FB13'           | 'R0402'             | '(R0402-0201)'                 | '33.2K'   | '1%'    | '1/16W'  | 'DISCRETE' | 'RES CHIP 33.2K 1/16W +-1% (0402)'                 | 'CHIP0402'     | ''          | ''            | '20121216'
 '33.2K'      | '1%'      | '1/16W'  | '0402LF'  | 'EMPTY'  | 'CS33322FB13'(!)        = 'End of Design' | 'Comp-Approve'     | 'CS33322FB13'           | 'R0402'             | '(R0402-0201)'                 | '33.2K'   | '1%'    | '1/16W'  | 'IO'       | 'RES CHIP 33.2K 1/16W +-1% (0402)'                 | 'CHIP0402'     | ''          | ''            | '20121216'
 '51'         | '5%'      | '1/8W'   | '0805LF'  | 'CHIP'   | 'CS05104JA12'(!)        = ''              | ''                 | 'CS05104JA12'           | 'R0805'             | '(SMR0805AW)'                  | '51'      | '5%'    | '1/8W'   | 'DISCRETE' | 'RES CHIP 51 1/8W +-5% (0805)'                     | 'CHIP0805'     | ''          | ''            | '20121216'
 '51'         | '5%'      | '1/8W'   | '0805LF'  | 'EMPTY'  | 'CS05104JA12'(!)        = ''              | ''                 | 'CS05104JA12'           | 'R0805'             | '(SMR0805AW)'                  | '51'      | '5%'    | '1/8W'   | 'IO'       | 'RES CHIP 51 1/8W +-5% (0805)'                     | 'CHIP0805'     | ''          | ''            | '20121216'
 '0.2'        | '1%'      | '1/10W'  | '0603LF'  | 'CHIP'   | 'CS+0203F900'(!)        = ''              | ''                 | 'CS+0203F900'           | 'R0603'             | '(SMR0603AW)'                  | '0.2'     | '1%'    | '1/10W'  | 'DISCRETE' | 'RES CHIP 0.2 1/10W +-1%(0603)'                    | 'CHIP0603'     | ''          | ''            | '20121216'
 '0.2'        | '1%'      | '1/10W'  | '0603LF'  | 'EMPTY'  | 'CS+0203F900'(!)        = ''              | ''                 | 'CS+0203F900'           | 'R0603'             | '(SMR0603AW)'                  | '0.2'     | '1%'    | '1/10W'  | 'IO'       | 'RES CHIP 0.2 1/10W +-1%(0603)'                    | 'CHIP0603'     | ''          | ''            | '20121216'
 '510'        | '5%'      | '1/10W'  | '0603LF'  | 'CHIP'   | 'CS15103J933'(!)        = ''              | ''                 | 'CS15103J933'           | 'R0603'             | '(SMR0603AW)'                  | '510'     | '5%'    | '1/10W'  | 'DISCRETE' | 'RES CHIP 510 1/10W +-5%(0603)'                    | 'CHIP0603'     | ''          | ''            | '20121218'
 '510'        | '5%'      | '1/10W'  | '0603LF'  | 'EMPTY'  | 'CS15103J933'(!)        = ''              | ''                 | 'CS15103J933'           | 'R0603'             | '(SMR0603AW)'                  | '510'     | '5%'    | '1/10W'  | 'IO'       | 'RES CHIP 510 1/10W +-5%(0603)'                    | 'CHIP0603'     | ''          | ''            | '20121218'
 '0.01'       | '1%'      | '1W'     | '2010LF'  | 'CHIP'   | 'CS+0108FJ00'(!)        = ''              | ''                 | 'CS+0108FJ00'           | 'R2010'             | '(SMR2010AW)'                  | '0.01'    | '1%'    | '1W'     | 'DISCRETE' | 'RES CHIP 0.01 1W +-1%(2010)'                      | 'CHIP2010'     | ''          | ''            | '20121221'
 '0.01'       | '1%'      | '1W'     | '2010LF'  | 'EMPTY'  | 'CS+0108FJ00'(!)        = ''              | ''                 | 'CS+0108FJ00'           | 'R2010'             | '(SMR2010AW)'                  | '0.01'    | '1%'    | '1W'     | 'IO'       | 'RES CHIP 0.01 1W +-1%(2010)'                      | 'CHIP2010'     | ''          | ''            | '20121221'
 '0.015'      | '1%'      | '3/4W'   | '2010LF'  | 'CHIP'   | 'CS+015BFJ21'(!)        = ''              | ''                 | 'CS+015BFJ21'           | 'R2010'             | '(SMR2010AW)'                  | '0.015'   | '1%'    | '3/4W'   | 'DISCRETE' | 'RES CHIP 0.015 3/4W +-1%(2010)'                   | 'CHIP2010'     | ''          | ''            | '20121221'
 '0.015'      | '1%'      | '3/4W'   | '2010LF'  | 'EMPTY'  | 'CS+015BFJ21'(!)        = ''              | ''                 | 'CS+015BFJ21'           | 'R2010'             | '(SMR2010AW)'                  | '0.015'   | '1%'    | '3/4W'   | 'IO'       | 'RES CHIP 0.015 3/4W +-1%(2010)'                   | 'CHIP2010'     | ''          | ''            | '20121221'
 '64.9'       | '1%'      | '1/16W'  | '0402LF'  | 'CHIP'   | 'CS06492FB03'(!)        = ''              | ''                 | 'CS06492FB03'           | 'R0402'             | '(R0402-0201)'                 | '64.9'    | '1%'    | '1/16W'  | 'DISCRETE' | 'RES CHIP 64.9 1/16W +-1%(0402)'                   | 'CHIP0402'     | ''          | ''            | '20121222'
 '64.9'       | '1%'      | '1/16W'  | '0402LF'  | 'EMPTY'  | 'CS06492FB03'(!)        = ''              | ''                 | 'CS06492FB03'           | 'R0402'             | '(R0402-0201)'                 | '64.9'    | '1%'    | '1/16W'  | 'IO'       | 'RES CHIP 64.9 1/16W +-1%(0402)'                   | 'CHIP0402'     | ''          | ''            | '20121222'
 '665'        | '1%'      | '1/16W'  | '0402LF'  | 'CHIP'   | 'CS16652FB04'(!)        = 'End of Design' | 'Comp-Approve'     | 'CS16652FB04'           | 'R0402'             | '(R0402-0201)'                 | '665'     | '1%'    | '1/16W'  | 'DISCRETE' | 'RES CHIP 665 1/16W +-1%(0402) L-F'                | 'CHIP0402'     | ''          | ''            | '20121222'
 '665'        | '1%'      | '1/16W'  | '0402LF'  | 'EMPTY'  | 'CS16652FB04'(!)        = 'End of Design' | 'Comp-Approve'     | 'CS16652FB04'           | 'R0402'             | '(R0402-0201)'                 | '665'     | '1%'    | '1/16W'  | 'IO'       | 'RES CHIP 665 1/16W +-1%(0402) L-F'                | 'CHIP0402'     | ''          | ''            | '20121222'
 '30.1'       | '1%'      | '1/16W'  | '0402LF'  | 'CHIP'   | 'CS03012FB21'(!)        = 'End of Design' | 'Comp-Approve'     | 'CS03012FB21'           | 'R0402'             | '(R0402-0201)'                 | '30.1'    | '1%'    | '1/16W'  | 'DISCRETE' | 'RES CHIP 30.1 1/16W +-1%(0402)'                   | 'CHIP0402'     | ''          | ''            | '20121224'
 '30.1'       | '1%'      | '1/16W'  | '0402LF'  | 'EMPTY'  | 'CS03012FB21'(!)        = 'End of Design' | 'Comp-Approve'     | 'CS03012FB21'           | 'R0402'             | '(R0402-0201)'                 | '30.1'    | '1%'    | '1/16W'  | 'IO'       | 'RES CHIP 30.1 1/16W +-1%(0402)'                   | 'CHIP0402'     | ''          | ''            | '20121224'
 '0.002'      | '1%'      | '1W'     | '2512LF'  | 'CHIP'   | 'CS+0028F115'(!)        = ''              | ''                 | 'CS+0028F115'           | 'R2512XC'           | '(SMR2512AW)'                  | '0.002'   | '1%'    | '1W'     | 'DISCRETE' | 'RES CHIP 0.002 1W +-1%(2512)'                     | 'CHIP2512'     | ''          | ''            | '20121225'
 '0.002'      | '1%'      | '1W'     | '2512LF'  | 'EMPTY'  | 'CS+0028F115'(!)        = ''              | ''                 | 'CS+0028F115'           | 'R2512XC'           | '(SMR2512AW)'                  | '0.002'   | '1%'    | '1W'     | 'IO'       | 'RES CHIP 0.002 1W +-1%(2512)'                     | 'CHIP2512'     | ''          | ''            | '20121225'
 '4.99'       | '1%'      | '1/16W'  | '0402LF'  | 'CHIP'   | 'CS-4992FB25'(!)        = 'End of Design' | 'Comp-Approve'     | 'CS-4992FB25'           | 'R0402'             | '(R0402-0201)'                 | '4.99'    | '1%'    | '1/16W'  | 'DISCRETE' | 'RES CHIP 4.99 1/16W +-1% (0402)'                  | 'CHIP0402'     | ''          | ''            | '20121228'
 '4.99'       | '1%'      | '1/16W'  | '0402LF'  | 'EMPTY'  | 'CS-4992FB25'(!)        = 'End of Design' | 'Comp-Approve'     | 'CS-4992FB25'           | 'R0402'             | '(R0402-0201)'                 | '4.99'    | '1%'    | '1/16W'  | 'IO'       | 'RES CHIP 4.99 1/16W +-1% (0402)'                  | 'CHIP0402'     | ''          | ''            | '20121228'
 '64.9'       | '1%'      | '1/16W'  | '0402LF'  | 'CHIP'   | 'CS06492FB11'(!)        = 'End of Design' | 'Comp-Approve'     | 'CS06492FB11'           | 'R0402'             | '(R0402-0201)'                 | '64.9'    | '1%'    | '1/16W'  | 'DISCRETE' | 'RES CHIP 64.9 1/16W +-1% (0402)'                  | 'CHIP0402'     | ''          | ''            | '20130105'
 '64.9'       | '1%'      | '1/16W'  | '0402LF'  | 'EMPTY'  | 'CS06492FB11'(!)        = 'End of Design' | 'Comp-Approve'     | 'CS06492FB11'           | 'R0402'             | '(R0402-0201)'                 | '64.9'    | '1%'    | '1/16W'  | 'IO'       | 'RES CHIP 64.9 1/16W +-1% (0402)'                  | 'CHIP0402'     | ''          | ''            | '20130105'
 '160K'       | '1%'      | '1/16W'  | '0402LF'  | 'CHIP'   | 'CS41602FB00'(!)        = 'End of Design' | 'Comp-Approve'     | 'CS41602FB00'           | 'R0402'             | '(R0402-0201)'                 | '160K'    | '1%'    | '1/16W'  | 'DISCRETE' | 'RES CHIP 160K (1/16W,+-1%,0402)'                  | 'CHIP0402'     | ''          | ''            | '20130108'
 '160K'       | '1%'      | '1/16W'  | '0402LF'  | 'EMPTY'  | 'CS41602FB00'(!)        = 'End of Design' | 'Comp-Approve'     | 'CS41602FB00'           | 'R0402'             | '(R0402-0201)'                 | '160K'    | '1%'    | '1/16W'  | 'IO'       | 'RES CHIP 160K (1/16W,+-1%,0402)'                  | 'CHIP0402'     | ''          | ''            | '20130108'
 '35.7'       | '1%'      | '1/16W'  | '0402LF'  | 'CHIP'   | 'CS03572FB01'(!)        = 'End of Design' | 'Comp-Approve'     | 'CS03572FB01'           | 'R0402'             | '(R0402-0201)'                 | '35.7'    | '1%'    | '1/16W'  | 'DISCRETE' | 'RES CHIP 35.7 1/16W +-1%(0402)'                   | 'CHIP0402'     | ''          | ''            | '20130108'
 '35.7'       | '1%'      | '1/16W'  | '0402LF'  | 'EMPTY'  | 'CS03572FB01'(!)        = 'End of Design' | 'Comp-Approve'     | 'CS03572FB01'           | 'R0402'             | '(R0402-0201)'                 | '35.7'    | '1%'    | '1/16W'  | 'IO'       | 'RES CHIP 35.7 1/16W +-1%(0402)'                   | 'CHIP0402'     | ''          | ''            | '20130108'
 '140K'       | '1%'      | '1/16W'  | '0402LF'  | 'CHIP'   | 'CS41402FB14'(!)        = 'End of Design' | 'Comp-Approve'     | 'CS41402FB14'           | 'R0402'             | '(R0402-0201)'                 | '140K'    | '1%'    | '1/16W'  | 'DISCRETE' | 'RES CHIP 140K 1/16W +-1%(0402)'                   | 'CHIP0402'     | ''          | ''            | '20130108'
 '140K'       | '1%'      | '1/16W'  | '0402LF'  | 'EMPTY'  | 'CS41402FB14'(!)        = 'End of Design' | 'Comp-Approve'     | 'CS41402FB14'           | 'R0402'             | '(R0402-0201)'                 | '140K'    | '1%'    | '1/16W'  | 'IO'       | 'RES CHIP 140K 1/16W +-1%(0402)'                   | 'CHIP0402'     | ''          | ''            | '20130108'
 '69.8K'      | '1%'      | '1/10W'  | '0603LF'  | 'CHIP'   | 'CS36983F917'(!)        = 'End of Design' | 'Comp-Approve'     | 'CS36983F917'           | 'R0603'             | '(SMR0603AW)'                  | '69.8K'   | '1%'    | '1/10W'  | 'DISCRETE' | 'RESISTOR CHIP 69.8K 1/10W +-1% (0603)'            | 'CHIP0603'     | ''          | ''            | '20130114'
 '69.8K'      | '1%'      | '1/10W'  | '0603LF'  | 'EMPTY'  | 'CS36983F917'(!)        = 'End of Design' | 'Comp-Approve'     | 'CS36983F917'           | 'R0603'             | '(SMR0603AW)'                  | '69.8K'   | '1%'    | '1/10W'  | 'IO'       | 'RESISTOR CHIP 69.8K 1/10W +-1% (0603)'            | 'CHIP0603'     | ''          | ''            | '20130114'
 '6.65K'      | '1%'      | '1/16W'  | '0402LF'  | 'CHIP'   | 'TMP_QCS26652FB06'(!)   = 'End of Design' | 'Comp-Approve'     | 'CS26652FB06'           | 'R0402'             | '(R0402-0201)'                 | '6.65K'   | '1%'    | '1/16W'  | 'DISCRETE' | '6.65Kohm 0402'                                    | 'CHIP0402'     | ''          | ''            | ''        
 '6.65K'      | '1%'      | '1/16W'  | '0402LF'  | 'EMPTY'  | 'TMP_QCS26652FB06'(!)   = 'End of Design' | 'Comp-Approve'     | 'CS26652FB06'           | 'R0402'             | '(R0402-0201)'                 | '6.65K'   | '1%'    | '1/16W'  | 'DISCRETE' | '6.65Kohm 0402'                                    | 'CHIP0402'     | ''          | ''            | ''        
 '5.23K'      | '1%'      | '1/16W'  | '0402LF'  | 'CHIP'   | 'CS25232FB18'(!)        = 'End of Design' | 'Comp-Approve'     | 'CS25232FB18'           | 'R0402'             | '(R0402-0201)'                 | '5.23K'   | '1%'    | '1/16W'  | 'DISCRETE' | 'RES CHIP 5.23K 1/16W +-1%(0402)'                  | 'CHIP0402'     | ''          | ''            | '20130123'
 '5.23K'      | '1%'      | '1/16W'  | '0402LF'  | 'EMPTY'  | 'CS25232FB18'(!)        = 'End of Design' | 'Comp-Approve'     | 'CS25232FB18'           | 'R0402'             | '(R0402-0201)'                 | '5.23K'   | '1%'    | '1/16W'  | 'IO'       | 'RES CHIP 5.23K 1/16W +-1%(0402)'                  | 'CHIP0402'     | ''          | ''            | '20130123'
 '120K'       | '1%'      | '1/16W'  | '0402LF'  | 'CHIP'   | 'CS41202FB17'(!)        = 'End of Design' | 'Comp-Approve'     | 'CS41202FB17'           | 'R0402'             | '(R0402-0201)'                 | '120K'    | '1%'    | '1/16W'  | 'DISCRETE' | 'RES CHIP 120K 1/16W +-1%( 0402)'                  | 'CHIP0402'     | ''          | ''            | '20130218'
 '120K'       | '1%'      | '1/16W'  | '0402LF'  | 'EMPTY'  | 'CS41202FB17'(!)        = 'End of Design' | 'Comp-Approve'     | 'CS41202FB17'           | 'R0402'             | '(R0402-0201)'                 | '120K'    | '1%'    | '1/16W'  | 'IO'       | 'RES CHIP 120K 1/16W +-1%( 0402)'                  | 'CHIP0402'     | ''          | ''            | '20130218'
 '2.2K'       | '1%'      | '1/10W'  | '0603LF'  | 'CHIP'   | 'CS22203F912'(!)        = 'End of Design' | 'Comp-Approve'     | 'CS22203F912'           | 'R0603'             | '(SMR0603AW)'                  | '2.2K'    | '1%'    | '1/10W'  | 'DISCRETE' | 'RES CHIP 2.2K 1/10W.+-1%(0603)'                   | 'CHIP0603'     | ''          | ''            | '20130228'
 '2.2K'       | '1%'      | '1/10W'  | '0603LF'  | 'EMPTY'  | 'CS22203F912'(!)        = 'End of Design' | 'Comp-Approve'     | 'CS22203F912'           | 'R0603'             | '(SMR0603AW)'                  | '2.2K'    | '1%'    | '1/10W'  | 'IO'       | 'RES CHIP 2.2K 1/10W.+-1%(0603)'                   | 'CHIP0603'     | ''          | ''            | '20130228'
 '2.26K'      | '1%'      | '1/10W'  | '0603LF'  | 'CHIP'   | 'CS22263F928'(!)        = 'End of Design' | 'Comp-Approve'     | 'CS22263F928'           | 'R0603'             | '(SMR0603AW)'                  | '2.26K'   | '1%'    | '1/10W'  | 'DISCRETE' | 'RES CHIP 2.26K 1/10W +-1%(0603)'                  | 'CHIP0603'     | ''          | ''            | '20130228'
 '2.26K'      | '1%'      | '1/10W'  | '0603LF'  | 'EMPTY'  | 'CS22263F928'(!)        = 'End of Design' | 'Comp-Approve'     | 'CS22263F928'           | 'R0603'             | '(SMR0603AW)'                  | '2.26K'   | '1%'    | '1/10W'  | 'IO'       | 'RES CHIP 2.26K 1/10W +-1%(0603)'                  | 'CHIP0603'     | ''          | ''            | '20130228'
 '1.43K'      | '1%'      | '1/16W'  | '0402LF'  | 'CHIP'   | 'CS21432FB00'(!)        = 'End of Design' | 'Comp-Approve'     | 'CS21432FB00'           | 'R0402'             | '(R0402-0201)'                 | '1.43K'   | '1%'    | '1/16W'  | 'DISCRETE' | 'RES CHIP 1.43K 1/16W +-1%(0402)'                  | 'CHIP0402'     | ''          | ''            | '20130306'
 '1.43K'      | '1%'      | '1/16W'  | '0402LF'  | 'EMPTY'  | 'CS21432FB00'(!)        = 'End of Design' | 'Comp-Approve'     | 'CS21432FB00'           | 'R0402'             | '(R0402-0201)'                 | '1.43K'   | '1%'    | '1/16W'  | 'IO'       | 'RES CHIP 1.43K 1/16W +-1%(0402)'                  | 'CHIP0402'     | ''          | ''            | '20130306'
 '60.4'       | '1%'      | '1/16W'  | '0402LF'  | 'CHIP'   | 'CS06042FB14'(!)        = 'End of Design' | 'Comp-Approve'     | 'CS06042FB14'           | 'R0402'             | '(R0402-0201)'                 | '60.4'    | '1%'    | '1/16W'  | 'DISCRETE' | 'RES CHIP 1.43K 1/16W +-1%(0402)'                  | 'CHIP0402'     | ''          | ''            | '20130319'
 '60.4'       | '1%'      | '1/16W'  | '0402LF'  | 'EMPTY'  | 'CS06042FB14'(!)        = 'End of Design' | 'Comp-Approve'     | 'CS06042FB14'           | 'R0402'             | '(R0402-0201)'                 | '60.4'    | '1%'    | '1/16W'  | 'IO'       | 'RES CHIP 1.43K 1/16W +-1%(0402)'                  | 'CHIP0402'     | ''          | ''            | '20130319'
 '0.0002'     | '1%'      | '5W'     | '5931LF'  | 'CHIP'   | 'TMP_TU1J_LJ_0322_1'(!) = ''              | ''                 | 'TMP_TU1J_LJ_0322_1'    | 'R5931'             | '(SMR5931AW)'                  | '0.0002'  | '1%'    | '5W'     | 'DISCRETE' | 'RES CHIP 0.0002 5W +-1%(5931)'                    | 'CHIP5931'     | ''          | ''            | '20130322'
 '0.0002'     | '1%'      | '5W'     | '5931LF'  | 'EMPTY'  | 'TMP_TU1J_LJ_0322_1'(!) = ''              | ''                 | 'TMP_TU1J_LJ_0322_1'    | 'R5931'             | '(SMR5931AW)'                  | '0.0002'  | '1%'    | '5W'     | 'IO'       | 'RES CHIP 0.0002 5W +-1%(5931)'                    | 'CHIP5931'     | ''          | ''            | '20130322'
 '221'        | '1%'      | '1/16W'  | '0402LF'  | 'CHIP'   | 'CS12212FB19'(!)        = 'End of Design' | 'Comp-Approve'     | 'CS12212FB19'           | 'R0402'             | '(R0402-0201)'                 | '221'     | '1%'    | '1/16W'  | 'DISCRETE' | 'RES CHIP 221 1/16W +-1%(0402)'                    | 'CHIP0402'     | ''          | ''            | '20130323'
 '221'        | '1%'      | '1/16W'  | '0402LF'  | 'EMPTY'  | 'CS12212FB19'(!)        = 'End of Design' | 'Comp-Approve'     | 'CS12212FB19'           | 'R0402'             | '(R0402-0201)'                 | '221'     | '1%'    | '1/16W'  | 'IO'       | 'RES CHIP 221 1/16W +-1%(0402)'                    | 'CHIP0402'     | ''          | ''            | '20130323'
 '243'        | '1%'      | '1/16W'  | '0402LF'  | 'CHIP'   | 'CS12432FB15'(!)        = 'End of Design' | 'Comp-Approve'     | 'CS12432FB15'           | 'R0402'             | '(R0402-0201)'                 | '243'     | '1%'    | '1/16W'  | 'DISCRETE' | 'RES CHIP 243 1/16W +-1% (0402)'                   | 'CHIP0402'     | ''          | ''            | '20130327'
 '243'        | '1%'      | '1/16W'  | '0402LF'  | 'EMPTY'  | 'CS12432FB15'(!)        = 'End of Design' | 'Comp-Approve'     | 'CS12432FB15'           | 'R0402'             | '(R0402-0201)'                 | '243'     | '1%'    | '1/16W'  | 'IO'       | 'RES CHIP 243 1/16W +-1% (0402)'                   | 'CHIP0402'     | ''          | ''            | '20130327'
 '10'         | '5%'      | '1/8W'   | '0805LF'  | 'CHIP'   | 'CS01004JA42'(!)        = ''              | ''                 | 'CS01004JA42'           | 'R0805'             | '(SMR0805AW)'                  | '10'      | '5%'    | '1/8W'   | 'DISCRETE' | 'RES CHIP 10 1/8W +-5%(0805)'                      | 'CHIP0805'     | ''          | ''            | '20130401'
 '10'         | '5%'      | '1/8W'   | '0805LF'  | 'EMPTY'  | 'CS01004JA42'(!)        = ''              | ''                 | 'CS01004JA42'           | 'R0805'             | '(SMR0805AW)'                  | '10'      | '5%'    | '1/8W'   | 'IO'       | 'RES CHIP 10 1/8W +-5%(0805)'                      | 'CHIP0805'     | ''          | ''            | '20130401'
 '1.5K'       | '5%'      | '1/8W'   | '0805LF'  | 'CHIP'   | 'CS21504JA10'(!)        = 'End of Design' | 'End of Life'      | 'CS21504JA10'           | 'R0805_EOL'         | '(SMR0805AW)'                  | '1.5K'    | '5%'    | '1/8W'   | 'DISCRETE' | 'RES CHIP 1.5K 1/8W +-5%(0805)'                    | 'CHIP0805'     | ''          | ''            | '20130401'
 '1.5K'       | '5%'      | '1/8W'   | '0805LF'  | 'EMPTY'  | 'CS21504JA10'(!)        = 'End of Design' | 'End of Life'      | 'CS21504JA10'           | 'R0805_EOL'         | '(SMR0805AW)'                  | '1.5K'    | '5%'    | '1/8W'   | 'IO'       | 'RES CHIP 1.5K 1/8W +-5%(0805)'                    | 'CHIP0805'     | ''          | ''            | '20130401'
 '1.5M'       | '1%'      | '1/16W'  | '0402LF'  | 'CHIP'   | 'CS51502FB00'(!)        = 'End of Design' | 'Comp-Approve'     | 'CS51502FB00'           | 'R0402'             | '(R0402-0201)'                 | '1.5M'    | '1%'    | '1/16W'  | 'DISCRETE' | 'RES CHIP 1.5M 1/16W +-1%(0402)'                   | 'CHIP0402'     | ''          | ''            | '20130411'
 '1.5M'       | '1%'      | '1/16W'  | '0402LF'  | 'EMPTY'  | 'CS51502FB00'(!)        = 'End of Design' | 'Comp-Approve'     | 'CS51502FB00'           | 'R0402'             | '(R0402-0201)'                 | '1.5M'    | '1%'    | '1/16W'  | 'IO'       | 'RES CHIP 1.5M 1/16W +-1%(0402)'                   | 'CHIP0402'     | ''          | ''            | '20130411'
 '3.0M'       | '1%'      | '1/16W'  | '0402LF'  | 'CHIP'   | 'CS53002FB00'(!)        = 'End of Design' | 'Comp-Release Qty' | 'CS53002FB00'           | 'R0402'             | '(R0402-0201)'                 | '3.0M'    | '1%'    | '1/16W'  | 'DISCRETE' | 'RES CHIP 3.0M 1/16W +-1%(0402)'                   | 'CHIP0402'     | ''          | ''            | '20130411'
 '3.0M'       | '1%'      | '1/16W'  | '0402LF'  | 'EMPTY'  | 'CS53002FB00'(!)        = 'End of Design' | 'Comp-Release Qty' | 'CS53002FB00'           | 'R0402'             | '(R0402-0201)'                 | '3.0M'    | '1%'    | '1/16W'  | 'IO'       | 'RES CHIP 3.0M 1/16W +-1%(0402)'                   | 'CHIP0402'     | ''          | ''            | '20130411'
 '2.94K'      | '1%'      | '1/16W'  | '0402LF'  | 'CHIP'   | 'CS22942FB01'(!)        = 'End of Design' | 'Comp-Approve'     | 'CS22942FB01'           | 'R0402'             | '(R0402-0201)'                 | '2.94K'   | '1%'    | '1/16W'  | 'DISCRETE' | 'RES CHIP 2.94K 1/16W +-1%(0402)'                  | 'CHIP0402'     | ''          | ''            | '20130411'
 '2.94K'      | '1%'      | '1/16W'  | '0402LF'  | 'EMPTY'  | 'CS22942FB01'(!)        = 'End of Design' | 'Comp-Approve'     | 'CS22942FB01'           | 'R0402'             | '(R0402-0201)'                 | '2.94K'   | '1%'    | '1/16W'  | 'IO'       | 'RES CHIP 2.94K 1/16W +-1%(0402)'                  | 'CHIP0402'     | ''          | ''            | '20130411'
 '44.2'       | '1%'      | '1/16W'  | '0402LF'  | 'CHIP'   | 'CS04422FB14'(!)        = 'End of Design' | 'Comp-Approve'     | 'CS04422FB14'           | 'R0402'             | '(R0402-0201)'                 | '44.2'    | '1%'    | '1/16W'  | 'DISCRETE' | 'RES CHIP 44.2 1/16W +-1%(0402)'                   | 'CHIP0402'     | ''          | ''            | '20130425'
 '44.2'       | '1%'      | '1/16W'  | '0402LF'  | 'EMPTY'  | 'CS04422FB14'(!)        = 'End of Design' | 'Comp-Approve'     | 'CS04422FB14'           | 'R0402'             | '(R0402-0201)'                 | '44.2'    | '1%'    | '1/16W'  | 'IO'       | 'RES CHIP 44.2 1/16W +-1%(0402)'                   | 'CHIP0402'     | ''          | ''            | '20130425'
 '3'          | '5%'      | '3/4W'   | '2010LF'  | 'CHIP'   | 'CS0030BJJ00'(!)        = ''              | ''                 | 'CS0030BJJ00'           | 'R2010'             | '(SMR2010AW)'                  | '3'       | '5%'    | '3/4W'   | 'DISCRETE' | 'RES CHIP 3 3/4W.+-5%(2010)'                       | 'CHIP2010'     | ''          | ''            | '20130429'
 '3'          | '5%'      | '3/4W'   | '2010LF'  | 'EMPTY'  | 'CS0030BJJ00'(!)        = ''              | ''                 | 'CS0030BJJ00'           | 'R2010'             | '(SMR2010AW)'                  | '3'       | '5%'    | '3/4W'   | 'IO'       | 'RES CHIP 3 3/4W.+-5%(2010)'                       | 'CHIP2010'     | ''          | ''            | '20130429'
 '1'          | '5%'      | '3/4W'   | '2010LF'  | 'CHIP'   | 'CS-100BJJ04'(!)        = ''              | ''                 | 'CS-100BJJ04'           | 'R2010'             | '(SMR2010AW)'                  | '1'       | '5%'    | '3/4W'   | 'DISCRETE' | 'RES CHIP 1 3/4W +5%(2010)L-F'                     | 'CHIP2010'     | ''          | ''            | '20130429'
 '1'          | '5%'      | '3/4W'   | '2010LF'  | 'EMPTY'  | 'CS-100BJJ04'(!)        = ''              | ''                 | 'CS-100BJJ04'           | 'R2010'             | '(SMR2010AW)'                  | '1'       | '5%'    | '3/4W'   | 'IO'       | 'RES CHIP 1 3/4W +5%(2010)L-F'                     | 'CHIP2010'     | ''          | ''            | '20130429'
 '432'        | '1%'      | '1/16W'  | '0402LF'  | 'CHIP'   | 'CS14322FB00'(!)        = 'End of Design' | 'Comp-Approve'     | 'CS14322FB00'           | 'R0402'             | '(R0402-0201)'                 | '432'     | '1%'    | '1/16W'  | 'DISCRETE' | 'RES CHIP 432 1/16W +-1%(0402)'                    | 'CHIP0402'     | ''          | ''            | '20130503'
 '432'        | '1%'      | '1/16W'  | '0402LF'  | 'EMPTY'  | 'CS14322FB00'(!)        = 'End of Design' | 'Comp-Approve'     | 'CS14322FB00'           | 'R0402'             | '(R0402-0201)'                 | '432'     | '1%'    | '1/16W'  | 'IO'       | 'RES CHIP 432 1/16W +-1%(0402)'                    | 'CHIP0402'     | ''          | ''            | '20130503'
 '348'        | '1%'      | '1/16W'  | '0402LF'  | 'CHIP'   | 'CS13482FB00'(!)        = 'End of Design' | 'Comp-Approve'     | 'CS13482FB00'           | 'R0402'             | '(R0402-0201)'                 | '348'     | '1%'    | '1/16W'  | 'DISCRETE' | 'RES CHIP 348 1/16W +-1%(0402)'                    | 'CHIP0402'     | ''          | ''            | '20130509'
 '348'        | '1%'      | '1/16W'  | '0402LF'  | 'EMPTY'  | 'CS13482FB00'(!)        = 'End of Design' | 'Comp-Approve'     | 'CS13482FB00'           | 'R0402'             | '(R0402-0201)'                 | '348'     | '1%'    | '1/16W'  | 'IO'       | 'RES CHIP 348 1/16W +-1%(0402)'                    | 'CHIP0402'     | ''          | ''            | '20130509'
 '2.7K'       | '5%'      | '1/16W'  | '0402LF'  | 'CHIP'   | 'CS22702JB16'(!)        = 'End of Design' | 'Comp-Approve'     | 'CS22702JB16'           | 'R0402'             | '(R0402-0201)'                 | '2.7K'    | '5%'    | '1/16W'  | 'DISCRETE' | 'RES CHIP 2.7K 1/16W +-5%(0402)'                   | 'CHIP0402'     | ''          | ''            | '20130509'
 '2.7K'       | '5%'      | '1/16W'  | '0402LF'  | 'EMPTY'  | 'CS22702JB16'(!)        = 'End of Design' | 'Comp-Approve'     | 'CS22702JB16'           | 'R0402'             | '(R0402-0201)'                 | '2.7K'    | '5%'    | '1/16W'  | 'IO'       | 'RES CHIP 2.7K 1/16W +-5%(0402)'                   | 'CHIP0402'     | ''          | ''            | '20130509'
 '3.01'       | '1%'      | '1/4W'   | '1206LF'  | 'CHIP'   | 'CS-3016F200'(!)        = ''              | ''                 | 'CS-3016F200'           | 'R1206'             | '(SMR1206AW)'                  | '3.01'    | '1%'    | '1/4W'   | 'DISCRETE' | 'RES CHIP 3.01 OHM 1/4W +-1%(1206)'                | 'CHIP1206'     | ''          | ''            | '20130521'
 '3.01'       | '1%'      | '1/4W'   | '1206LF'  | 'EMPTY'  | 'CS-3016F200'(!)        = ''              | ''                 | 'CS-3016F200'           | 'R1206'             | '(SMR1206AW)'                  | '3.01'    | '1%'    | '1/4W'   | 'IO'       | 'RES CHIP 3.01 OHM 1/4W +-1%(1206)'                | 'CHIP1206'     | ''          | ''            | '20130521'
 '196'        | '1%'      | '1/10W'  | '0603LF'  | 'CHIP'   | 'CS11963F911'(!)        = 'End of Design' | 'Comp-Approve'     | 'CS11963F911'           | 'R0603'             | '(SMR0603AW)'                  | '196'     | '1%'    | '1/10W'  | 'DISCRETE' | 'RES CHIP 196 1/10W +-1% (0603)'                   | 'CHIP0603'     | ''          | ''            | '20130529'
 '196'        | '1%'      | '1/10W'  | '0603LF'  | 'EMPTY'  | 'CS11963F911'(!)        = 'End of Design' | 'Comp-Approve'     | 'CS11963F911'           | 'R0603'             | '(SMR0603AW)'                  | '196'     | '1%'    | '1/10W'  | 'IO'       | 'RES CHIP 196 1/10W +-1% (0603)'                   | 'CHIP0603'     | ''          | ''            | '20130529'
 '0.001'      | '1%'      | '4W'     | '2725LF'  | 'CHIP'   | 'CS+001FFT00'(!)        = 'End of Design' | 'P/N Release'      | 'CS+001FFT00'           | 'R2725'             | '(SMR2725AW)'                  | '0.001'   | '1%'    | '4W'     | 'DISCRETE' | 'RES CHIP 0.001OHM 4W +-1% (2725)'                 | 'CHIP2725'     | ''          | ''            | '20130606'
 '0.001'      | '1%'      | '4W'     | '2725LF'  | 'EMPTY'  | 'CS+001FFT00'(!)        = 'End of Design' | 'P/N Release'      | 'CS+001FFT00'           | 'R2725'             | '(SMR2725AW)'                  | '0.001'   | '1%'    | '4W'     | 'IO'       | 'RES CHIP 0.001OHM 4W +-1% (2725)'                 | 'CHIP2725'     | ''          | ''            | '20130606'
 '240K'       | '1%'      | '1/16W'  | '0402LF'  | 'CHIP'   | 'CS42402FB17'(!)        = 'End of Design' | 'Comp-Approve'     | 'CS42402FB17'           | 'R0402'             | '(R0402-0201)'                 | '240K'    | '1%'    | '1/16W'  | 'DISCRETE' | 'RES CHIP 240K 1/16W +-1%(0402)'                   | 'CHIP0402'     | ''          | ''            | '20130611'
 '240K'       | '1%'      | '1/16W'  | '0402LF'  | 'EMPTY'  | 'CS42402FB17'(!)        = 'End of Design' | 'Comp-Approve'     | 'CS42402FB17'           | 'R0402'             | '(R0402-0201)'                 | '240K'    | '1%'    | '1/16W'  | 'IO'       | 'RES CHIP 240K 1/16W +-1%(0402)'                   | 'CHIP0402'     | ''          | ''            | '20130611'
 '1'          | '1%'      | '1/4W'   | '1206LF'  | 'CHIP'   | 'CS-1006F217'(!)        = ''              | ''                 | 'CS-1006F217'           | 'R1206'             | '(SMR1206AW)'                  | '1'       | '1%'    | '1/4W'   | 'DISCRETE' | 'RES CHIP 1 1/4W +-1%(1206) L-F'                   | 'CHIP1206'     | ''          | ''            | '20130611'
 '1'          | '1%'      | '1/4W'   | '1206LF'  | 'EMPTY'  | 'CS-1006F217'(!)        = ''              | ''                 | 'CS-1006F217'           | 'R1206'             | '(SMR1206AW)'                  | '1'       | '1%'    | '1/4W'   | 'IO'       | 'RES CHIP 1 1/4W +-1%(1206) L-F'                   | 'CHIP1206'     | ''          | ''            | '20130611'
 '0.0002'     | '1%'      | '4W'     | '2725LF'  | 'CHIP'   | 'CS0000FFT01'(!)        = ''              | ''                 | 'CS0000FFT01'           | 'R2725'             | '(SMR2725AW)'                  | '0.0002'  | '1%'    | '4W'     | 'DISCRETE' | 'RES CHIP 0.0002 4W +-1%(2725)H1.131'              | 'CHIP2725'     | ''          | ''            | '20130627'
 '0.0002'     | '1%'      | '4W'     | '2725LF'  | 'EMPTY'  | 'CS0000FFT01'(!)        = ''              | ''                 | 'CS0000FFT01'           | 'R2725'             | '(SMR2725AW)'                  | '0.0002'  | '1%'    | '4W'     | 'IO'       | 'RES CHIP 0.0002 4W +-1%(2725)H1.131'              | 'CHIP2725'     | ''          | ''            | '20130627'
 '91'         | '1%'      | '1/16W'  | '0402LF'  | 'CHIP'   | 'CS09102FB00'(!)        = 'End of Design' | 'Comp-Approve'     | 'CS09102FB00'           | 'R0402'             | '(R0402-0201)'                 | '91'      | '1%'    | '1/16W'  | 'DISCRETE' | 'RES CHIP 91 1/16W +-1%(0402)'                     | 'CHIP0402'     | ''          | ''            | '20130702'
 '91'         | '1%'      | '1/16W'  | '0402LF'  | 'EMPTY'  | 'CS09102FB00'(!)        = 'End of Design' | 'Comp-Approve'     | 'CS09102FB00'           | 'R0402'             | '(R0402-0201)'                 | '91'      | '1%'    | '1/16W'  | 'IO'       | 'RES CHIP 91 1/16W +-1%(0402)'                     | 'CHIP0402'     | ''          | ''            | '20130702'
 '499'        | '1%'      | '1/8W'   | '0805LF'  | 'CHIP'   | 'CS14994FA00'(!)        = ''              | ''                 | 'CS14994FA00'           | 'R0805'             | '(SMR0805AW)'                  | '499'     | '1%'    | '1/8W'   | 'DISCRETE' | 'RES CHIP 499 1/8W +-1%(0805)'                     | 'CHIP0805'     | ''          | ''            | '20130705'
 '499'        | '1%'      | '1/8W'   | '0805LF'  | 'EMPTY'  | 'CS14994FA00'(!)        = ''              | ''                 | 'CS14994FA00'           | 'R0805'             | '(SMR0805AW)'                  | '499'     | '1%'    | '1/8W'   | 'IO'       | 'RES CHIP 499 1/8W +-1%(0805)'                     | 'CHIP0805'     | ''          | ''            | '20130705'
 '510'        | '1%'      | '1/8W'   | '0805LF'  | 'CHIP'   | 'CS15104FA00'(!)        = 'End of Design' | 'Comp-Approve'     | 'CS15104FA00'           | 'R0805'             | '(SMR0805AW)'                  | '510'     | '1%'    | '1/8W'   | 'DISCRETE' | 'RES CHIP 510 1/8W +-1%(0805)'                     | 'CHIP0805'     | ''          | ''            | '20130705'
 '510'        | '1%'      | '1/8W'   | '0805LF'  | 'EMPTY'  | 'CS15104FA00'(!)        = 'End of Design' | 'Comp-Approve'     | 'CS15104FA00'           | 'R0805'             | '(SMR0805AW)'                  | '510'     | '1%'    | '1/8W'   | 'IO'       | 'RES CHIP 510 1/8W +-1%(0805)'                     | 'CHIP0805'     | ''          | ''            | '20130705'
 '137K'       | '1%'      | '1/16W'  | '0402LF'  | 'CHIP'   | 'CS41372FB12'(!)        = 'End of Design' | 'Comp-Approve'     | 'CS41372FB12'           | 'R0402'             | '(R0402-0201)'                 | '137K'    | '1%'    | '1/16W'  | 'DISCRETE' | 'RES CHIP 137K 1/16W +-1% (0402)'                  | 'CHIP0402'     | ''          | ''            | '20130729'
 '137K'       | '1%'      | '1/16W'  | '0402LF'  | 'EMPTY'  | 'CS41372FB12'(!)        = 'End of Design' | 'Comp-Approve'     | 'CS41372FB12'           | 'R0402'             | '(R0402-0201)'                 | '137K'    | '1%'    | '1/16W'  | 'IO'       | 'RES CHIP 137K 1/16W +-1% (0402)'                  | 'CHIP0402'     | ''          | ''            | '20130729'
 '162K'       | '1%'      | '1/16W'  | '0402LF'  | 'CHIP'   | 'CS41622FB11'(!)        = 'End of Design' | 'Comp-Approve'     | 'CS41622FB11'           | 'R0402'             | '(R0402-0201)'                 | '162K'    | '1%'    | '1/16W'  | 'DISCRETE' | 'RES CHIP 162K 1/16W +-1% (0402)'                  | 'CHIP0402'     | ''          | ''            | '20130729'
 '162K'       | '1%'      | '1/16W'  | '0402LF'  | 'EMPTY'  | 'CS41622FB11'(!)        = 'End of Design' | 'Comp-Approve'     | 'CS41622FB11'           | 'R0402'             | '(R0402-0201)'                 | '162K'    | '1%'    | '1/16W'  | 'IO'       | 'RES CHIP 162K 1/16W +-1% (0402)'                  | 'CHIP0402'     | ''          | ''            | '20130729'
 '14.3K'      | '1%'      | '1/16W'  | '0402LF'  | 'CHIP'   | 'CS31432FB08'(!)        = 'End of Design' | 'Comp-Approve'     | 'CS31432FB08'           | 'R0402'             | '(R0402-0201)'                 | '14.3K'   | '1%'    | '1/16W'  | 'DISCRETE' | 'RES CHIP 14.3K 1/16W +-1%(0402)'                  | 'CHIP0402'     | ''          | ''            | '20130729'
 '14.3K'      | '1%'      | '1/16W'  | '0402LF'  | 'EMPTY'  | 'CS31432FB08'(!)        = 'End of Design' | 'Comp-Approve'     | 'CS31432FB08'           | 'R0402'             | '(R0402-0201)'                 | '14.3K'   | '1%'    | '1/16W'  | 'IO'       | 'RES CHIP 14.3K 1/16W +-1%(0402)'                  | 'CHIP0402'     | ''          | ''            | '20130729'
 '5.11'       | '1%'      | '1/10W'  | '0603LF'  | 'CHIP'   | 'CS-5113F900'(!)        = 'End of Design' | 'Comp-Approve'     | 'CS-5113F900'           | 'R0603'             | '(SMR0603AW)'                  | '5.11'    | '1%'    | '1/10W'  | 'DISCRETE' | 'RES CHIP 5.11 1/10W +-1%(0603)'                   | 'CHIP0603'     | ''          | ''            | '20130731'
 '5.11'       | '1%'      | '1/10W'  | '0603LF'  | 'EMPTY'  | 'CS-5113F900'(!)        = 'End of Design' | 'Comp-Approve'     | 'CS-5113F900'           | 'R0603'             | '(SMR0603AW)'                  | '5.11'    | '1%'    | '1/10W'  | 'IO'       | 'RES CHIP 5.11 1/10W +-1%(0603)'                   | 'CHIP0603'     | ''          | ''            | '20130731'
 '232'        | '1%'      | '1/16W'  | '0402LF'  | 'CHIP'   | 'CS12322FB09'(!)        = 'End of Design' | 'Comp-Approve'     | 'CS12322FB09'           | 'R0402'             | '(R0402-0201)'                 | '232'     | '1%'    | '1/16W'  | 'DISCRETE' | 'RES CHIP 232 1/16W +-1%(0402)'                    | 'CHIP0402'     | ''          | ''            | '20130731'
 '232'        | '1%'      | '1/16W'  | '0402LF'  | 'EMPTY'  | 'CS12322FB09'(!)        = 'End of Design' | 'Comp-Approve'     | 'CS12322FB09'           | 'R0402'             | '(R0402-0201)'                 | '232'     | '1%'    | '1/16W'  | 'IO'       | 'RES CHIP 232 1/16W +-1%(0402)'                    | 'CHIP0402'     | ''          | ''            | '20130731'
 '511K'       | '1%'      | '1/16W'  | '0402LF'  | 'CHIP'   | 'CS45112FB19'(!)        = 'End of Design' | 'Comp-Approve'     | 'CS45112FB19'           | 'R0402'             | '(R0402-0201)'                 | '511K'    | '1%'    | '1/16W'  | 'DISCRETE' | 'RES CHIP 511K 1/16W +-1%(0402)'                   | 'CHIP0402'     | ''          | ''            | '20130808'
 '511K'       | '1%'      | '1/16W'  | '0402LF'  | 'EMPTY'  | 'CS45112FB19'(!)        = 'End of Design' | 'Comp-Approve'     | 'CS45112FB19'           | 'R0402'             | '(R0402-0201)'                 | '511K'    | '1%'    | '1/16W'  | 'IO'       | 'RES CHIP 511K 1/16W +-1%(0402)'                   | 'CHIP0402'     | ''          | ''            | '20130808'
 '140'        | '1%'      | '1/10W'  | '0603LF'  | 'CHIP'   | 'CS11403F915'(!)        = 'End of Design' | 'Comp-Approve'     | 'CS11403F915'           | 'R0603'             | '(SMR0603AW)'                  | '140'     | '1%'    | '1/10W'  | 'DISCRETE' | 'RESISTOR CHIP 140 1/10W +-1%(0603)'               | 'CHIP0603'     | ''          | ''            | '20130815'
 '140'        | '1%'      | '1/10W'  | '0603LF'  | 'EMPTY'  | 'CS11403F915'(!)        = 'End of Design' | 'Comp-Approve'     | 'CS11403F915'           | 'R0603'             | '(SMR0603AW)'                  | '140'     | '1%'    | '1/10W'  | 'IO'       | 'RESISTOR CHIP 140 1/10W +-1%(0603)'               | 'CHIP0603'     | ''          | ''            | '20130815'
 '4.75K'      | '0.1%'    | '1/16W'  | '0402LF'  | 'CHIP'   | 'CS24752BB00'(!)        = ''              | ''                 | 'CS24752BB00'           | 'R0402'             | '(R0402-0201)'                 | '4.75K'   | '0.1%'  | '1/16W'  | 'DISCRETE' | 'RES CHIP 4.75K 1/16W +-0.1%(0402)'                | 'CHIP0402'     | ''          | ''            | '20130826'
 '4.75K'      | '0.1%'    | '1/16W'  | '0402LF'  | 'EMPTY'  | 'CS24752BB00'(!)        = ''              | ''                 | 'CS24752BB00'           | 'R0402'             | '(R0402-0201)'                 | '4.75K'   | '0.1%'  | '1/16W'  | 'IO'       | 'RES CHIP 4.75K 1/16W +-0.1%(0402)'                | 'CHIP0402'     | ''          | ''            | '20130826'
 '137'        | '1%'      | '1/16W'  | '0402LF'  | 'CHIP'   | 'CS11372FB25'(!)        = 'End of Design' | 'Comp-Approve'     | 'CS11372FB25'           | 'R0402'             | '(R0402-0201)'                 | '137'     | '1%'    | '1/16W'  | 'DISCRETE' | 'RES CHIP 137 1/16W +-1%(0402)'                    | 'CHIP0402'     | ''          | ''            | '20131007'
 '137'        | '1%'      | '1/16W'  | '0402LF'  | 'EMPTY'  | 'CS11372FB25'(!)        = 'End of Design' | 'Comp-Approve'     | 'CS11372FB25'           | 'R0402'             | '(R0402-0201)'                 | '137'     | '1%'    | '1/16W'  | 'IO'       | 'RES CHIP 137 1/16W +-1%(0402)'                    | 'CHIP0402'     | ''          | ''            | '20131007'
 '1'          | '1%'      | '1/10W'  | '0603LF'  | 'CHIP'   | 'CS-1003F920'(!)        = ''              | ''                 | 'CS-1003F920'           | 'R0603'             | '(SMR0603AW)'                  | '1'       | '1%'    | '1/10W'  | 'DISCRETE' | 'RES CHIP 1 1/10W +-1%(0603)'                      | 'CHIP0603'     | ''          | ''            | '20131007'
 '1'          | '1%'      | '1/10W'  | '0603LF'  | 'EMPTY'  | 'CS-1003F920'(!)        = ''              | ''                 | 'CS-1003F920'           | 'R0603'             | '(SMR0603AW)'                  | '1'       | '1%'    | '1/10W'  | 'IO'       | 'RES CHIP 1 1/10W +-1%(0603)'                      | 'CHIP0603'     | ''          | ''            | '20131007'
 '137'        | '1%'      | '1/10W'  | '0603LF'  | 'CHIP'   | 'CS11373F921'(!)        = ''              | ''                 | 'CS11373F921'           | 'R0603'             | '(SMR0603AW)'                  | '137'     | '1%'    | '1/10W'  | 'DISCRETE' | 'RES CHIP 137 1/10W +-1%(0603)'                    | 'CHIP0603'     | ''          | ''            | '20131007'
 '137'        | '1%'      | '1/10W'  | '0603LF'  | 'EMPTY'  | 'CS11373F921'(!)        = ''              | ''                 | 'CS11373F921'           | 'R0603'             | '(SMR0603AW)'                  | '137'     | '1%'    | '1/10W'  | 'IO'       | 'RES CHIP 137 1/10W +-1%(0603)'                    | 'CHIP0603'     | ''          | ''            | '20131007'
 '442'        | '1%'      | '1/16W'  | '0402LF'  | 'CHIP'   | 'CS14422FB16'(!)        = 'End of Design' | 'Comp-Approve'     | 'CS14422FB16'           | 'R0402'             | '(R0402-0201)'                 | '442'     | '1%'    | '1/16W'  | 'DISCRETE' | 'RES CHIP 442 1/16W +-1% (0402)'                   | 'CHIP0402'     | ''          | ''            | '20131022'
 '442'        | '1%'      | '1/16W'  | '0402LF'  | 'EMPTY'  | 'CS14422FB16'(!)        = 'End of Design' | 'Comp-Approve'     | 'CS14422FB16'           | 'R0402'             | '(R0402-0201)'                 | '442'     | '1%'    | '1/16W'  | 'IO'       | 'RES CHIP 442 1/16W +-1% (0402)'                   | 'CHIP0402'     | ''          | ''            | '20131022'
 '0.005'      | '1%'      | '1W'     | '2010LF'  | 'CHIP'   | 'CS+0058FJ03'(!)        = ''              | ''                 | 'CS+0058FJ03'           | 'R2010'             | '(SMR2010AW)'                  | '0.005'   | '1%'    | '1W'     | 'DISCRETE' | 'RES CHIP 0.005 1W +-1%(2010)'                     | 'CHIP2010'     | ''          | ''            | '20131031'
 '0.005'      | '1%'      | '1W'     | '2010LF'  | 'EMPTY'  | 'CS+0058FJ03'(!)        = ''              | ''                 | 'CS+0058FJ03'           | 'R2010'             | '(SMR2010AW)'                  | '0.005'   | '1%'    | '1W'     | 'IO'       | 'RES CHIP 0.005 1W +-1%(2010)'                     | 'CHIP2010'     | ''          | ''            | '20131031'
 '1.3K'       | '1%'      | '1/16W'  | '0402LF'  | 'CHIP'   | 'CS21302FB17'(!)        = 'End of Design' | 'Comp-Approve'     | 'CS21302FB17'           | 'R0402'             | '(R0402-0201)'                 | '1.3K'    | '1%'    | '1/16W'  | 'DISCRETE' | 'RES CHIP 1.3K 1/16W +-1%(0402) L-F'               | 'CHIP0402'     | ''          | ''            | '20131122'
 '1.3K'       | '1%'      | '1/16W'  | '0402LF'  | 'EMPTY'  | 'CS21302FB17'(!)        = 'End of Design' | 'Comp-Approve'     | 'CS21302FB17'           | 'R0402'             | '(R0402-0201)'                 | '1.3K'    | '1%'    | '1/16W'  | 'IO'       | 'RES CHIP 1.3K 1/16W +-1%(0402) L-F'               | 'CHIP0402'     | ''          | ''            | '20131122'
 '2.4K'       | '1%'      | '1/16W'  | '0402LF'  | 'CHIP'   | 'CS22402FB00'(!)        = 'End of Design' | 'Comp-Approve'     | 'CS22402FB00'           | 'R0402'             | '(R0402-0201)'                 | '2.4K'    | '1%'    | '1/16W'  | 'DISCRETE' | 'RES CHIP 2.4K 1/16W+-1%(0402)'                    | 'CHIP0402'     | ''          | ''            | '20131202'
 '2.4K'       | '1%'      | '1/16W'  | '0402LF'  | 'EMPTY'  | 'CS22402FB00'(!)        = 'End of Design' | 'Comp-Approve'     | 'CS22402FB00'           | 'R0402'             | '(R0402-0201)'                 | '2.4K'    | '1%'    | '1/16W'  | 'IO'       | 'RES CHIP 2.4K 1/16W+-1%(0402)'                    | 'CHIP0402'     | ''          | ''            | '20131202'
 '1.33K'      | '1%'      | '1/16W'  | '0402LF'  | 'CHIP'   | 'CS21332FB11'(!)        = 'End of Design' | 'Comp-Approve'     | 'CS21332FB11'           | 'R0402'             | '(R0402-0201)'                 | '1.33K'   | '1%'    | '1/16W'  | 'DISCRETE' | 'RES CHIP 1.33K 1/16W +-1%( 0402)EP'               | 'CHIP0402'     | ''          | ''            | '20131203'
 '1.33K'      | '1%'      | '1/16W'  | '0402LF'  | 'EMPTY'  | 'CS21332FB11'(!)        = 'End of Design' | 'Comp-Approve'     | 'CS21332FB11'           | 'R0402'             | '(R0402-0201)'                 | '1.33K'   | '1%'    | '1/16W'  | 'IO'       | 'RES CHIP 1.33K 1/16W +-1%( 0402)EP'               | 'CHIP0402'     | ''          | ''            | '20131203'
 '1.78K'      | '1%'      | '1/16W'  | '0402LF'  | 'CHIP'   | 'CS21782FB18'(!)        = 'End of Design' | 'Comp-Approve'     | 'CS21782FB18'           | 'R0402'             | '(R0402-0201)'                 | '1.78K'   | '1%'    | '1/16W'  | 'DISCRETE' | 'RES CHIP 1.78K 1/16W +-1% (0402)'                 | 'CHIP0402'     | ''          | ''            | '20131205'
 '1.78K'      | '1%'      | '1/16W'  | '0402LF'  | 'EMPTY'  | 'CS21782FB18'(!)        = 'End of Design' | 'Comp-Approve'     | 'CS21782FB18'           | 'R0402'             | '(R0402-0201)'                 | '1.78K'   | '1%'    | '1/16W'  | 'IO'       | 'RES CHIP 1.78K 1/16W +-1% (0402)'                 | 'CHIP0402'     | ''          | ''            | '20131205'
 '8.45K'      | '1%'      | '1/16W'  | '0402LF'  | 'CHIP'   | 'CS28452FB12'(!)        = 'End of Design' | 'Comp-Approve'     | 'CS28452FB12'           | 'R0402'             | '(R0402-0201)'                 | '8.45K'   | '1%'    | '1/16W'  | 'DISCRETE' | 'RES CHIP 8.45K 1/16W +-1%( 0402)'                 | 'CHIP0402'     | ''          | ''            | '20131211'
 '8.45K'      | '1%'      | '1/16W'  | '0402LF'  | 'EMPTY'  | 'CS28452FB12'(!)        = 'End of Design' | 'Comp-Approve'     | 'CS28452FB12'           | 'R0402'             | '(R0402-0201)'                 | '8.45K'   | '1%'    | '1/16W'  | 'IO'       | 'RES CHIP 8.45K 1/16W +-1%( 0402)'                 | 'CHIP0402'     | ''          | ''            | '20131211'
 '1.58K'      | '1%'      | '1/16W'  | '0402LF'  | 'CHIP'   | 'CS21582FB00'(!)        = 'End of Design' | 'Comp-Approve'     | 'CS21582FB00'           | 'R0402'             | '(R0402-0201)'                 | '1.58K'   | '1%'    | '1/16W'  | 'DISCRETE' | 'RES CHIP 1.58K 1/16W +-1%(0402)'                  | 'CHIP0402'     | ''          | ''            | '20140116'
 '1.58K'      | '1%'      | '1/16W'  | '0402LF'  | 'EMPTY'  | 'CS21582FB00'(!)        = 'End of Design' | 'Comp-Approve'     | 'CS21582FB00'           | 'R0402'             | '(R0402-0201)'                 | '1.58K'   | '1%'    | '1/16W'  | 'IO'       | 'RES CHIP 1.58K 1/16W +-1%(0402)'                  | 'CHIP0402'     | ''          | ''            | '20140116'
 '18'         | '1%'      | '1/16W'  | '0402LF'  | 'CHIP'   | 'CS01802FB11'(!)        = 'End of Design' | 'Comp-Release Qty' | 'CS01802FB11'           | 'R0402'             | '(R0402-0201)'                 | '18'      | '1%'    | '1/16W'  | 'DISCRETE' | 'RES CHIP 18 1/16W +-1% (0402)'                    | 'CHIP0402'     | ''          | ''            | '20140128'
 '18'         | '1%'      | '1/16W'  | '0402LF'  | 'EMPTY'  | 'CS01802FB11'(!)        = 'End of Design' | 'Comp-Release Qty' | 'CS01802FB11'           | 'R0402'             | '(R0402-0201)'                 | '18'      | '1%'    | '1/16W'  | 'IO'       | 'RES CHIP 18 1/16W +-1% (0402)'                    | 'CHIP0402'     | ''          | ''            | '20140128'
 '1.2K'       | '1%'      | '1/8W'   | '0805LF'  | 'CHIP'   | 'CS21204FA17'(!)        = 'End of Design' | 'Comp-Approve'     | 'CS21204FA17'           | 'R0805'             | '(SMR0805AW)'                  | '1.2K'    | '1%'    | '1/8W'   | 'DISCRETE' | 'RES CHIP 1.2K 1/8W +-1%(0805)'                    | 'CHIP0805'     | ''          | ''            | '20140310'
 '1.2K'       | '1%'      | '1/8W'   | '0805LF'  | 'EMPTY'  | 'CS21204FA17'(!)        = 'End of Design' | 'Comp-Approve'     | 'CS21204FA17'           | 'R0805'             | '(SMR0805AW)'                  | '1.2K'    | '1%'    | '1/8W'   | 'IO'       | 'RES CHIP 1.2K 1/8W +-1%(0805)'                    | 'CHIP0805'     | ''          | ''            | '20140310'
 '68'         | '5%'      | '1/4W'   | '0805LF'  | 'CHIP'   | 'CS06806JA00'(!)        = ''              | ''                 | 'CS06806JA00'           | 'R0805'             | '(SMR0805AW)'                  | '68'      | '5%'    | '1/4W'   | 'DISCRETE' | 'RES CHIP 68 1/4W +-5%(0805)'                      | 'CHIP0805'     | ''          | ''            | '20140415'
 '68'         | '5%'      | '1/4W'   | '0805LF'  | 'EMPTY'  | 'CS06806JA00'(!)        = ''              | ''                 | 'CS06806JA00'           | 'R0805'             | '(SMR0805AW)'                  | '68'      | '5%'    | '1/4W'   | 'IO'       | 'RES CHIP 68 1/4W +-5%(0805)'                      | 'CHIP0805'     | ''          | ''            | '20140415'
 '33'         | '5%'      | '1/2W'   | '1206LF'  | 'CHIP'   | 'CS03307J200'(!)        = ''              | ''                 | 'CS03307J200'           | 'R1206'             | '(SMR1206AW)'                  | '33'      | '5%'    | '1/2W'   | 'DISCRETE' | 'RES CHIP 33 1/2W +-5%(1206)'                      | 'CHIP1206'     | ''          | ''            | '20140415'
 '33'         | '5%'      | '1/2W'   | '1206LF'  | 'EMPTY'  | 'CS03307J200'(!)        = ''              | ''                 | 'CS03307J200'           | 'R1206'             | '(SMR1206AW)'                  | '33'      | '5%'    | '1/2W'   | 'IO'       | 'RES CHIP 33 1/2W +-5%(1206)'                      | 'CHIP1206'     | ''          | ''            | '20140415'
 '1K'         | '1%'      | '1/20W'  | '0201LF'  | 'CHIP'   | 'CS21001FE04'(!)        = ''              | ''                 | 'CS21001FE04'           | 'R0201'             | '(SMR0201AW)'                  | '1K'      | '1%'    | '1/20W'  | 'DISCRETE' | 'RES CHIP 1K 1/20W +-1%(0201)'                     | 'CHIP0201'     | ''          | ''            | '20140424'
 '1K'         | '1%'      | '1/20W'  | '0201LF'  | 'EMPTY'  | 'CS21001FE04'(!)        = ''              | ''                 | 'CS21001FE04'           | 'R0201'             | '(SMR0201AW)'                  | '1K'      | '1%'    | '1/20W'  | 'IO'       | 'RES CHIP 1K 1/20W +-1%(0201)'                     | 'CHIP0201'     | ''          | ''            | '20140424'
 '150K'       | '1%'      | '1/10W'  | '0603LF'  | 'CHIP'   | 'CS41503F914'(!)        = 'End of Design' | 'Comp-Approve'     | 'CS41503F914'           | 'R0603'             | '(SMR0603AW)'                  | '150K'    | '1%'    | '1/10W'  | 'DISCRETE' | 'RES CHIP 150K 1/10W +-1%(0603)'                   | 'CHIP0603'     | ''          | ''            | '20140429'
 '150K'       | '1%'      | '1/10W'  | '0603LF'  | 'EMPTY'  | 'CS41503F914'(!)        = 'End of Design' | 'Comp-Approve'     | 'CS41503F914'           | 'R0603'             | '(SMR0603AW)'                  | '150K'    | '1%'    | '1/10W'  | 'IO'       | 'RES CHIP 150K 1/10W +-1%(0603)'                   | 'CHIP0603'     | ''          | ''            | '20140429'
 '0.015'      | '1%'      | '1W'     | '2512LF'  | 'CHIP'   | 'CS+0158FR00'(!)        = 'End of Design' | 'Comp-Approve'     | 'CS+0158FR00'           | 'R2512'             | '(SMR2512AW)'                  | '0.015'   | '1%'    | '1W'     | 'DISCRETE' | 'RES CHIP 0.015 1W +-1%(2512)'                     | 'CHIP2512'     | ''          | ''            | '20140505'
 '0.015'      | '1%'      | '1W'     | '2512LF'  | 'EMPTY'  | 'CS+0158FR00'(!)        = 'End of Design' | 'Comp-Approve'     | 'CS+0158FR00'           | 'R2512'             | '(SMR2512AW)'                  | '0.015'   | '1%'    | '1W'     | 'IO'       | 'RES CHIP 0.015 1W +-1%(2512)'                     | 'CHIP2512'     | ''          | ''            | '20140505'
 '2.2K'       | '1%'      | '1/10W'  | '0603LF'  | 'CHIP'   | 'CS22203F904'(!)        = ''              | ''                 | 'CS22203F904'           | 'R0603'             | '(SMR0603AW)'                  | '2.2K'    | '1%'    | '1/10W'  | 'DISCRETE' | 'RES CHIP 2.2K 1/10W.+-1%(0603)'                   | 'CHIP0603'     | ''          | ''            | '20140505'
 '2.2K'       | '1%'      | '1/10W'  | '0603LF'  | 'EMPTY'  | 'CS22203F904'(!)        = ''              | ''                 | 'CS22203F904'           | 'R0603'             | '(SMR0603AW)'                  | '2.2K'    | '1%'    | '1/10W'  | 'IO'       | 'RES CHIP 2.2K 1/10W.+-1%(0603)'                   | 'CHIP0603'     | ''          | ''            | '20140505'
 '200K'       | '1%'      | '1/8W'   | '0805LF'  | 'CHIP'   | 'CS42004FA00'(!)        = ''              | ''                 | 'CS42004FA00'           | 'R0805'             | '(SMR0805AW)'                  | '200K'    | '1%'    | '1/8W'   | 'DISCRETE' | 'RES CHIP 200K 1/8W +-1%(0805)'                    | 'CHIP0805'     | ''          | ''            | '20140527'
 '200K'       | '1%'      | '1/8W'   | '0805LF'  | 'EMPTY'  | 'CS42004FA00'(!)        = ''              | ''                 | 'CS42004FA00'           | 'R0805'             | '(SMR0805AW)'                  | '200K'    | '1%'    | '1/8W'   | 'IO'       | 'RES CHIP 200K 1/8W +-1%(0805)'                    | 'CHIP0805'     | ''          | ''            | '20140527'
 '23.2K'      | '1%'      | '1/10W'  | '0603LF'  | 'CHIP'   | 'CS32323F917'(!)        = ''              | ''                 | 'CS32323F917'           | 'R0603'             | '(SMR0603AW)'                  | '23.2K'   | '1%'    | '1/10W'  | 'DISCRETE' | 'RES CHIP 23.2K 1/10W +-1%(0603)'                  | 'CHIP0603'     | ''          | ''            | '20140529'
 '23.2K'      | '1%'      | '1/10W'  | '0603LF'  | 'EMPTY'  | 'CS32323F917'(!)        = ''              | ''                 | 'CS32323F917'           | 'R0603'             | '(SMR0603AW)'                  | '23.2K'   | '1%'    | '1/10W'  | 'IO'       | 'RES CHIP 23.2K 1/10W +-1%(0603)'                  | 'CHIP0603'     | ''          | ''            | '20140529'
 '470'        | '1%'      | '1/16W'  | '0402LF'  | 'CHIP'   | 'CS14702FB18'(!)        = 'End of Design' | 'Comp-Approve'     | 'CS14702FB18'           | 'R0402'             | '(R0402-0201)'                 | '470'     | '1%'    | '1/16W'  | 'DISCRETE' | 'RES CHIP 470 1/16W +-1%(0402)'                    | 'CHIP0402'     | ''          | ''            | '20140605'
 '470'        | '1%'      | '1/16W'  | '0402LF'  | 'EMPTY'  | 'CS14702FB18'(!)        = 'End of Design' | 'Comp-Approve'     | 'CS14702FB18'           | 'R0402'             | '(R0402-0201)'                 | '470'     | '1%'    | '1/16W'  | 'IO'       | 'RES CHIP 470 1/16W +-1%(0402)'                    | 'CHIP0402'     | ''          | ''            | '20140605'
 '12K'        | '0.5%'    | '1/16W'  | '0402LF'  | 'CHIP'   | 'CS31202DB00'(!)        = ''              | ''                 | 'CS31202DB00'           | 'R0402'             | '(R0402-0201)'                 | '12K'     | '0.5%'  | '1/16W'  | 'DISCRETE' | 'RES CHIP 12K 1/16W +-0.5%(0402)'                  | 'CHIP0402'     | ''          | ''            | '20140613'
 '12K'        | '0.5%'    | '1/16W'  | '0402LF'  | 'EMPTY'  | 'CS31202DB00'(!)        = ''              | ''                 | 'CS31202DB00'           | 'R0402'             | '(R0402-0201)'                 | '12K'     | '0.5%'  | '1/16W'  | 'IO'       | 'RES CHIP 12K 1/16W +-0.5%(0402)'                  | 'CHIP0402'     | ''          | ''            | '20140613'
 '2.8K'       | '1%'      | '1/16W'  | '0402LF'  | 'CHIP'   | 'CS22802FB02'(!)        = ''              | 'End of Life'      | 'CS22802FB02'           | 'R0402_EOL'         | '(R0402-0201)'                 | '2.8K'    | '1%'    | '1/16W'  | 'DISCRETE' | 'RES CHIP 2.8K 1/16W +-1%(0402)'                   | 'CHIP0402'     | ''          | ''            | '20140616'
 '2.8K'       | '1%'      | '1/16W'  | '0402LF'  | 'EMPTY'  | 'CS22802FB02'(!)        = ''              | 'End of Life'      | 'CS22802FB02'           | 'R0402_EOL'         | '(R0402-0201)'                 | '2.8K'    | '1%'    | '1/16W'  | 'IO'       | 'RES CHIP 2.8K 1/16W +-1%(0402)'                   | 'CHIP0402'     | ''          | ''            | '20140616'
 '1.69K'      | '1%'      | '1/16W'  | '0402LF'  | 'CHIP'   | 'CS21692FB01'(!)        = 'End of Design' | 'Comp-Approve'     | 'CS21692FB01'           | 'R0402'             | '(R0402-0201)'                 | '1.69K'   | '1%'    | '1/16W'  | 'DISCRETE' | 'RES CHIP 1.69K 1/16W +-1%(0402)'                  | 'CHIP0402'     | ''          | ''            | '20140616'
 '1.69K'      | '1%'      | '1/16W'  | '0402LF'  | 'EMPTY'  | 'CS21692FB01'(!)        = 'End of Design' | 'Comp-Approve'     | 'CS21692FB01'           | 'R0402'             | '(R0402-0201)'                 | '1.69K'   | '1%'    | '1/16W'  | 'IO'       | 'RES CHIP 1.69K 1/16W +-1%(0402)'                  | 'CHIP0402'     | ''          | ''            | '20140616'
 '40.2'       | '1%'      | '1/16W'  | '0402LF'  | 'CHIP'   | 'CS04022FB28'(!)        = 'End of Design' | 'Comp-Approve'     | 'CS04022FB28'           | 'R0402'             | '(R0402-0201)'                 | '40.2'    | '1%'    | '1/16W'  | 'DISCRETE' | 'RES CHIP 40.2 1/16W +-1%(0402)'                   | 'CHIP0402'     | ''          | ''            | '20140630'
 '40.2'       | '1%'      | '1/16W'  | '0402LF'  | 'EMPTY'  | 'CS04022FB28'(!)        = 'End of Design' | 'Comp-Approve'     | 'CS04022FB28'           | 'R0402'             | '(R0402-0201)'                 | '40.2'    | '1%'    | '1/16W'  | 'IO'       | 'RES CHIP 40.2 1/16W +-1%(0402)'                   | 'CHIP0402'     | ''          | ''            | '20140630'
 '1.8K'       | '1%'      | '1/16W'  | '0402LF'  | 'CHIP'   | 'CS21802FB10'(!)        = 'End of Design' | 'Comp-Approve'     | 'CS21802FB10'           | 'R0402'             | '(R0402-0201)'                 | '1.8K'    | '1%'    | '1/16W'  | 'DISCRETE' | 'RES CHIP 1.8K 1/16W +-1%(0402)'                   | 'CHIP0402'     | ''          | ''            | '20140630'
 '1.8K'       | '1%'      | '1/16W'  | '0402LF'  | 'EMPTY'  | 'CS21802FB10'(!)        = 'End of Design' | 'Comp-Approve'     | 'CS21802FB10'           | 'R0402'             | '(R0402-0201)'                 | '1.8K'    | '1%'    | '1/16W'  | 'IO'       | 'RES CHIP 1.8K 1/16W +-1%(0402)'                   | 'CHIP0402'     | ''          | ''            | '20140630'
 '1.74K'      | '1%'      | '1/10W'  | '0603LF'  | 'CHIP'   | 'CS21743F916'(!)        = ''              | ''                 | 'CS21743F916'           | 'R0603'             | '(SMR0603AW)'                  | '1.74K'   | '1%'    | '1/10W'  | 'DISCRETE' | 'RESISTER CHIP 1.74K 1/10W +-1%(0603)L-F'          | 'CHIP0603'     | ''          | ''            | '20140724'
 '1.74K'      | '1%'      | '1/10W'  | '0603LF'  | 'EMPTY'  | 'CS21743F916'(!)        = ''              | ''                 | 'CS21743F916'           | 'R0603'             | '(SMR0603AW)'                  | '1.74K'   | '1%'    | '1/10W'  | 'IO'       | 'RESISTER CHIP 1.74K 1/10W +-1%(0603)L-F'          | 'CHIP0603'     | ''          | ''            | '20140724'
 '113K'       | '1%'      | '1/16W'  | '0402LF'  | 'CHIP'   | 'CS41132FB17'(!)        = 'End of Design' | 'Comp-Approve'     | 'CS41132FB17'           | 'R0402'             | '(R0402-0201)'                 | '113K'    | '1%'    | '1/16W'  | 'DISCRETE' | 'RES CHIP 113K 1/16W +-1%(0402)'                   | 'CHIP0402'     | ''          | ''            | '20140729'
 '113K'       | '1%'      | '1/16W'  | '0402LF'  | 'EMPTY'  | 'CS41132FB17'(!)        = 'End of Design' | 'Comp-Approve'     | 'CS41132FB17'           | 'R0402'             | '(R0402-0201)'                 | '113K'    | '1%'    | '1/16W'  | 'IO'       | 'RES CHIP 113K 1/16W +-1%(0402)'                   | 'CHIP0402'     | ''          | ''            | '20140729'
 '82'         | '1%'      | '1/16W'  | '0402LF'  | 'CHIP'   | 'CS08202FB01'(!)        = 'End of Design' | 'Comp-Approve'     | 'CS08202FB01'           | 'R0402'             | '(R0402-0201)'                 | '82'      | '1%'    | '1/16W'  | 'DISCRETE' | 'RES CHIP 82(1/16W,+-1%,0402)EP'                   | 'CHIP0402'     | ''          | ''            | '20140729'
 '82'         | '1%'      | '1/16W'  | '0402LF'  | 'EMPTY'  | 'CS08202FB01'(!)        = 'End of Design' | 'Comp-Approve'     | 'CS08202FB01'           | 'R0402'             | '(R0402-0201)'                 | '82'      | '1%'    | '1/16W'  | 'IO'       | 'RES CHIP 82(1/16W,+-1%,0402)EP'                   | 'CHIP0402'     | ''          | ''            | '20140729'
 '42.2K'      | '1%'      | '1/8W'   | '0805LF'  | 'CHIP'   | 'CS34224FA00'(!)        = ''              | ''                 | 'CS34224FA00'           | 'R0805'             | '(SMR0805AW)'                  | '42.2K'   | '1%'    | '1/8W'   | 'DISCRETE' | 'RES CHIP 42.2K 1/8W +-1%(0805)'                   | 'CHIP0805'     | ''          | ''            | '20140806'
 '42.2K'      | '1%'      | '1/8W'   | '0805LF'  | 'EMPTY'  | 'CS34224FA00'(!)        = ''              | ''                 | 'CS34224FA00'           | 'R0805'             | '(SMR0805AW)'                  | '42.2K'   | '1%'    | '1/8W'   | 'IO'       | 'RES CHIP 42.2K 1/8W +-1%(0805)'                   | 'CHIP0805'     | ''          | ''            | '20140806'
 '0.3'        | '1%'      | '1/2W'   | '1206LF'  | 'CHIP'   | 'CS+3007F200'(!)        = ''              | ''                 | 'CS+3007F200'           | 'R1206'             | '(SMR1206AW)'                  | '0.3'     | '1%'    | '1/2W'   | 'DISCRETE' | 'RES CHIP 0.3 1/2W +-1%(1206)'                     | 'CHIP1206'     | ''          | ''            | '20140806'
 '0.3'        | '1%'      | '1/2W'   | '1206LF'  | 'EMPTY'  | 'CS+3007F200'(!)        = ''              | ''                 | 'CS+3007F200'           | 'R1206'             | '(SMR1206AW)'                  | '0.3'     | '1%'    | '1/2W'   | 'IO'       | 'RES CHIP 0.3 1/2W +-1%(1206)'                     | 'CHIP1206'     | ''          | ''            | '20140806'
 '1.21'       | '1%'      | '1/16W'  | '0402LF'  | 'CHIP'   | 'CS-1212FB00'(!)        = ''              | ''                 | 'CS-1212FB00'           | 'R0402'             | '(R0402-0201)'                 | '1.21'    | '1%'    | '1/16W'  | 'DISCRETE' | 'RES CHIP 1.21 1/16W +-1%(0402)'                   | 'CHIP0402'     | ''          | ''            | '20140807'
 '1.21'       | '1%'      | '1/16W'  | '0402LF'  | 'EMPTY'  | 'CS-1212FB00'(!)        = ''              | ''                 | 'CS-1212FB00'           | 'R0402'             | '(R0402-0201)'                 | '1.21'    | '1%'    | '1/16W'  | 'IO'       | 'RES CHIP 1.21 1/16W +-1%(0402)'                   | 'CHIP0402'     | ''          | ''            | '20140807'
 '0.004'      | '1%'      | '3W'     | '2512LF'  | 'CHIP'   | 'CS+004DFR00'(!)        = ''              | ''                 | 'CS+004DFR00'           | 'R2512XF'           | '(SMR2512AW)'                  | '0.004'   | '1%'    | '3W'     | 'DISCRETE' | 'RES CHIP 0.004 3W +-1%(2512)'                     | 'CHIP2512'     | ''          | ''            | '20140808'
 '0.004'      | '1%'      | '3W'     | '2512LF'  | 'EMPTY'  | 'CS+004DFR00'(!)        = ''              | ''                 | 'CS+004DFR00'           | 'R2512XF'           | '(SMR2512AW)'                  | '0.004'   | '1%'    | '3W'     | 'IO'       | 'RES CHIP 0.004 3W +-1%(2512)'                     | 'CHIP2512'     | ''          | ''            | '20140808'
 '68.1'       | '1%'      | '1/16W'  | '0402LF'  | 'CHIP'   | 'CS06812FB00'(!)        = 'End of Design' | 'Comp-Approve'     | 'CS06812FB00'           | 'R0402'             | '(R0402-0201)'                 | '68.1'    | '1%'    | '1/16W'  | 'DISCRETE' | 'RES CHIP 68.1 1/16W +-1% (0402)'                  | 'CHIP0402'     | ''          | ''            | '20140808'
 '68.1'       | '1%'      | '1/16W'  | '0402LF'  | 'EMPTY'  | 'CS06812FB00'(!)        = 'End of Design' | 'Comp-Approve'     | 'CS06812FB00'           | 'R0402'             | '(R0402-0201)'                 | '68.1'    | '1%'    | '1/16W'  | 'IO'       | 'RES CHIP 68.1 1/16W +-1% (0402)'                  | 'CHIP0402'     | ''          | ''            | '20140808'
 '332'        | '1%'      | '1/16W'  | '0402LF'  | 'CHIP'   | 'CS13322FB10'(!)        = 'End of Design' | 'Comp-Approve'     | 'CS13322FB10'           | 'R0402'             | '(R0402-0201)'                 | '332'     | '1%'    | '1/16W'  | 'DISCRETE' | 'RES CHIP 332 1/16W +-1%(0402)'                    | 'CHIP0402'     | ''          | ''            | '20140808'
 '332'        | '1%'      | '1/16W'  | '0402LF'  | 'EMPTY'  | 'CS13322FB10'(!)        = 'End of Design' | 'Comp-Approve'     | 'CS13322FB10'           | 'R0402'             | '(R0402-0201)'                 | '332'     | '1%'    | '1/16W'  | 'IO'       | 'RES CHIP 332 1/16W +-1%(0402)'                    | 'CHIP0402'     | ''          | ''            | '20140808'
 '5.62K'      | '1%'      | '1/16W'  | '0402LF'  | 'CHIP'   | 'CS25622FB18'(!)        = 'End of Design' | 'Comp-Approve'     | 'CS25622FB18'           | 'R0402'             | '(R0402-0201)'                 | '5.62K'   | '1%'    | '1/16W'  | 'DISCRETE' | 'RES CHIP 5.62K 1/16W +-1%( 0402)'                 | 'CHIP0402'     | ''          | ''            | '20140808'
 '5.62K'      | '1%'      | '1/16W'  | '0402LF'  | 'EMPTY'  | 'CS25622FB18'(!)        = 'End of Design' | 'Comp-Approve'     | 'CS25622FB18'           | 'R0402'             | '(R0402-0201)'                 | '5.62K'   | '1%'    | '1/16W'  | 'IO'       | 'RES CHIP 5.62K 1/16W +-1%( 0402)'                 | 'CHIP0402'     | ''          | ''            | '20140808'
 '205K'       | '1%'      | '1/8W'   | '0805LF'  | 'CHIP'   | 'CS42054FA00'(!)        = ''              | ''                 | 'CS42054FA00'           | 'R0805'             | '(SMR0805AW)'                  | '205K'    | '1%'    | '1/8W'   | 'DISCRETE' | 'RES CHIP 205K 1/8W +-1%(0805)'                    | 'CHIP0805'     | ''          | ''            | '20140808'
 '205K'       | '1%'      | '1/8W'   | '0805LF'  | 'EMPTY'  | 'CS42054FA00'(!)        = ''              | ''                 | 'CS42054FA00'           | 'R0805'             | '(SMR0805AW)'                  | '205K'    | '1%'    | '1/8W'   | 'IO'       | 'RES CHIP 205K 1/8W +-1%(0805)'                    | 'CHIP0805'     | ''          | ''            | '20140808'
 '150K'       | '1%'      | '1/8W'   | '0805LF'  | 'CHIP'   | 'CS41504FA00'(!)        = ''              | ''                 | 'CS41504FA00'           | 'R0805'             | '(SMR0805AW)'                  | '150K'    | '1%'    | '1/8W'   | 'DISCRETE' | 'RES CHIP 150K 1/8W +-1%(0805)'                    | 'CHIP0805'     | ''          | ''            | '20140808'
 '150K'       | '1%'      | '1/8W'   | '0805LF'  | 'EMPTY'  | 'CS41504FA00'(!)        = ''              | ''                 | 'CS41504FA00'           | 'R0805'             | '(SMR0805AW)'                  | '150K'    | '1%'    | '1/8W'   | 'IO'       | 'RES CHIP 150K 1/8W +-1%(0805)'                    | 'CHIP0805'     | ''          | ''            | '20140808'
 '221K'       | '1%'      | '1/16W'  | '0402LF'  | 'CHIP'   | 'CS42212FB22'(!)        = 'End of Design' | 'Comp-Approve'     | 'CS42212FB22'           | 'R0402'             | '(R0402-0201)'                 | '221K'    | '1%'    | '1/16W'  | 'DISCRETE' | 'RES CHIP 221K 1/16W +-1% (0402)'                  | 'CHIP0402'     | ''          | ''            | '20140812'
 '221K'       | '1%'      | '1/16W'  | '0402LF'  | 'EMPTY'  | 'CS42212FB22'(!)        = 'End of Design' | 'Comp-Approve'     | 'CS42212FB22'           | 'R0402'             | '(R0402-0201)'                 | '221K'    | '1%'    | '1/16W'  | 'IO'       | 'RES CHIP 221K 1/16W +-1% (0402)'                  | 'CHIP0402'     | ''          | ''            | '20140812'
 '10K'        | '0.10%'   | '1/16W'  | '0402LF'  | 'CHIP'   | 'CS31002BB00'(!)        = ''              | ''                 | 'CS31002BB00'           | 'R0402'             | '(R0402-0201)'                 | '10K'     | '0.10%' | '1/16W'  | 'DISCRETE' | 'RES CHIP 10K 1/16W +-0.1%(0402)'                  | 'CHIP0402'     | ''          | ''            | '20140812'
 '10K'        | '0.10%'   | '1/16W'  | '0402LF'  | 'EMPTY'  | 'CS31002BB00'(!)        = ''              | ''                 | 'CS31002BB00'           | 'R0402'             | '(R0402-0201)'                 | '10K'     | '0.10%' | '1/16W'  | 'IO'       | 'RES CHIP 10K 1/16W +-0.1%(0402)'                  | 'CHIP0402'     | ''          | ''            | '20140812'
 '470'        | '5%'      | '1/8W'   | '0805LF'  | 'CHIP'   | 'CS14704JA13'(!)        = ''              | ''                 | 'CS14704JA13'           | 'R0805'             | '(SMR0805AW)'                  | '470'     | '5%'    | '1/8W'   | 'DISCRETE' | 'RES CHIP 470 1/8W +-5%(0805)'                     | 'CHIP0805'     | ''          | ''            | '20140812'
 '470'        | '5%'      | '1/8W'   | '0805LF'  | 'EMPTY'  | 'CS14704JA13'(!)        = ''              | ''                 | 'CS14704JA13'           | 'R0805'             | '(SMR0805AW)'                  | '470'     | '5%'    | '1/8W'   | 'IO'       | 'RES CHIP 470 1/8W +-5%(0805)'                     | 'CHIP0805'     | ''          | ''            | '20140812'
 '26.7K'      | '0.1%'    | '1/16W'  | '0402LF'  | 'CHIP'   | 'CS32672BB00'(!)        = ''              | ''                 | 'CS32672BB00'           | 'R0402'             | '(R0402-0201)'                 | '26.7K'   | '0.1%'  | '1/16W'  | 'DISCRETE' | 'RES CHIP 26.7K 1/16W +-0.1%(0402)'                | 'CHIP0402'     | ''          | ''            | '20140813'
 '26.7K'      | '0.1%'    | '1/16W'  | '0402LF'  | 'EMPTY'  | 'CS32672BB00'(!)        = ''              | ''                 | 'CS32672BB00'           | 'R0402'             | '(R0402-0201)'                 | '26.7K'   | '0.1%'  | '1/16W'  | 'IO'       | 'RES CHIP 26.7K 1/16W +-0.1%(0402)'                | 'CHIP0402'     | ''          | ''            | '20140813'
 '4.64K'      | '0.5%'    | '1/16W'  | '0402LF'  | 'CHIP'   | 'CS24642DB00'(!)        = ''              | ''                 | 'CS24642DB00'           | 'R0402'             | '(R0402-0201)'                 | '4.64K'   | '0.5%'  | '1/16W'  | 'DISCRETE' | 'RES CHIP 4.64K 1/16W +-0.5%(0402)'                | 'CHIP0402'     | ''          | ''            | '20140813'
 '4.64K'      | '0.5%'    | '1/16W'  | '0402LF'  | 'EMPTY'  | 'CS24642DB00'(!)        = ''              | ''                 | 'CS24642DB00'           | 'R0402'             | '(R0402-0201)'                 | '4.64K'   | '0.5%'  | '1/16W'  | 'IO'       | 'RES CHIP 4.64K 1/16W +-0.5%(0402)'                | 'CHIP0402'     | ''          | ''            | '20140813'
 '1.78K'      | '0.1%'    | '1/16W'  | '0402LF'  | 'CHIP'   | 'CS21782BB00'(!)        = ''              | ''                 | 'CS21782BB00'           | 'R0402'             | '(R0402-0201)'                 | '1.78K'   | '0.1%'  | '1/16W'  | 'DISCRETE' | 'RES CHIP 1.78K 1/16W +-0.1%(0402)'                | 'CHIP0402'     | ''          | ''            | '20140813'
 '1.78K'      | '0.1%'    | '1/16W'  | '0402LF'  | 'EMPTY'  | 'CS21782BB00'(!)        = ''              | ''                 | 'CS21782BB00'           | 'R0402'             | '(R0402-0201)'                 | '1.78K'   | '0.1%'  | '1/16W'  | 'IO'       | 'RES CHIP 1.78K 1/16W +-0.1%(0402)'                | 'CHIP0402'     | ''          | ''            | '20140813'
 '2.37K'      | '0.1%'    | '1/16W'  | '0402LF'  | 'CHIP'   | 'CS22372BB00'(!)        = ''              | ''                 | 'CS22372BB00'           | 'R0402'             | '(R0402-0201)'                 | '2.37K'   | '0.1%'  | '1/16W'  | 'DISCRETE' | 'RES CHIP 2.37K 1/16W +-0.1%(0402)'                | 'CHIP0402'     | ''          | ''            | '20140813'
 '2.37K'      | '0.1%'    | '1/16W'  | '0402LF'  | 'EMPTY'  | 'CS22372BB00'(!)        = ''              | ''                 | 'CS22372BB00'           | 'R0402'             | '(R0402-0201)'                 | '2.37K'   | '0.1%'  | '1/16W'  | 'IO'       | 'RES CHIP 2.37K 1/16W +-0.1%(0402)'                | 'CHIP0402'     | ''          | ''            | '20140813'
 '11.3K'      | '0.1%'    | '1/16W'  | '0402LF'  | 'CHIP'   | 'CS31132BB00'(!)        = ''              | ''                 | 'CS31132BB00'           | 'R0402'             | '(R0402-0201)'                 | '11.3K'   | '0.1%'  | '1/16W'  | 'DISCRETE' | 'RES CHIP 11.3K 1/16W +-0.1%(0402)'                | 'CHIP0402'     | ''          | ''            | '20140813'
 '11.3K'      | '0.1%'    | '1/16W'  | '0402LF'  | 'EMPTY'  | 'CS31132BB00'(!)        = ''              | ''                 | 'CS31132BB00'           | 'R0402'             | '(R0402-0201)'                 | '11.3K'   | '0.1%'  | '1/16W'  | 'IO'       | 'RES CHIP 11.3K 1/16W +-0.1%(0402)'                | 'CHIP0402'     | ''          | ''            | '20140813'
 '18.2K'      | '0.1%'    | '1/16W'  | '0402LF'  | 'CHIP'   | 'CS31822BB00'(!)        = ''              | ''                 | 'CS31822BB00'           | 'R0402'             | '(R0402-0201)'                 | '18.2K'   | '0.1%'  | '1/16W'  | 'DISCRETE' | 'RES CHIP 18.2K 1/16W +-0.1%(0402)'                | 'CHIP0402'     | ''          | ''            | '20140813'
 '18.2K'      | '0.1%'    | '1/16W'  | '0402LF'  | 'EMPTY'  | 'CS31822BB00'(!)        = ''              | ''                 | 'CS31822BB00'           | 'R0402'             | '(R0402-0201)'                 | '18.2K'   | '0.1%'  | '1/16W'  | 'IO'       | 'RES CHIP 18.2K 1/16W +-0.1%(0402)'                | 'CHIP0402'     | ''          | ''            | '20140813'
 '4.99K'      | '1%'      | '1/8W'   | '0805LF'  | 'CHIP'   | 'CS24994FA00'(!)        = ''              | ''                 | 'CS24994FA00'           | 'R0805'             | '(SMR0805AW)'                  | '4.99K'   | '1%'    | '1/8W'   | 'DISCRETE' | 'RES CHIP 4.99K 1/8W +-1%(0805)'                   | 'CHIP0805'     | ''          | ''            | '20140813'
 '4.99K'      | '1%'      | '1/8W'   | '0805LF'  | 'EMPTY'  | 'CS24994FA00'(!)        = ''              | ''                 | 'CS24994FA00'           | 'R0805'             | '(SMR0805AW)'                  | '4.99K'   | '1%'    | '1/8W'   | 'IO'       | 'RES CHIP 4.99K 1/8W +-1%(0805)'                   | 'CHIP0805'     | ''          | ''            | '20140813'
 '3.65K'      | '1%'      | '1/10W'  | '0603LF'  | 'CHIP'   | 'CS23653F912'(!)        = ''              | ''                 | 'CS23653F912'           | 'R0603'             | '(SMR0603AW)'                  | '3.65K'   | '1%'    | '1/10W'  | 'DISCRETE' | 'RES CHIP 3.65K 1/10W(+-1%.0603)'                  | 'CHIP0603'     | ''          | ''            | '20140813'
 '3.65K'      | '1%'      | '1/10W'  | '0603LF'  | 'EMPTY'  | 'CS23653F912'(!)        = ''              | ''                 | 'CS23653F912'           | 'R0603'             | '(SMR0603AW)'                  | '3.65K'   | '1%'    | '1/10W'  | 'IO'       | 'RES CHIP 3.65K 1/10W(+-1%.0603)'                  | 'CHIP0603'     | ''          | ''            | '20140813'
 '2.21K'      | '1%'      | '1/10W'  | '0603LF'  | 'CHIP'   | 'CS22213F925'(!)        = ''              | ''                 | 'CS22213F925'           | 'R0603'             | '(SMR0603AW)'                  | '2.21K'   | '1%'    | '1/10W'  | 'DISCRETE' | 'RESISTOR CHIP 2.21K 1/10W +-1%(0603)'             | 'CHIP0603'     | ''          | ''            | '20140813'
 '2.21K'      | '1%'      | '1/10W'  | '0603LF'  | 'EMPTY'  | 'CS22213F925'(!)        = ''              | ''                 | 'CS22213F925'           | 'R0603'             | '(SMR0603AW)'                  | '2.21K'   | '1%'    | '1/10W'  | 'IO'       | 'RESISTOR CHIP 2.21K 1/10W +-1%(0603)'             | 'CHIP0603'     | ''          | ''            | '20140813'
 '0.003'      | '1%'      | '1W'     | '3720LF'  | 'CHIP'   | 'CS+0038FL00'(!)        = ''              | ''                 | 'CS+0038FL00'           | 'R3720XA'           | '(SMR3720AW)'                  | '0.003'   | '1%'    | '1W'     | 'DISCRETE' | 'RES CHIP 0.003 1W +-1% (3720)'                    | 'CHIP3720'     | ''          | ''            | '20140814'
 '0.003'      | '1%'      | '1W'     | '3720LF'  | 'EMPTY'  | 'CS+0038FL00'(!)        = ''              | ''                 | 'CS+0038FL00'           | 'R3720XA'           | '(SMR3720AW)'                  | '0.003'   | '1%'    | '1W'     | 'IO'       | 'RES CHIP 0.003 1W +-1% (3720)'                    | 'CHIP3720'     | ''          | ''            | '20140814'
 '43.2K'      | '1%'      | '1/16W'  | '0402LF'  | 'CHIP'   | 'CS34322FB16'(!)        = ''              | 'End of Life'      | 'CS34322FB16'           | 'R0402_EOL'         | '(R0402-0201)'                 | '43.2K'   | '1%'    | '1/16W'  | 'DISCRETE' | 'RES CHIP 43.2K 1/16W +-1%(0402)'                  | 'CHIP0402'     | ''          | ''            | '20140817'
 '43.2K'      | '1%'      | '1/16W'  | '0402LF'  | 'EMPTY'  | 'CS34322FB16'(!)        = ''              | 'End of Life'      | 'CS34322FB16'           | 'R0402_EOL'         | '(R0402-0201)'                 | '43.2K'   | '1%'    | '1/16W'  | 'IO'       | 'RES CHIP 43.2K 1/16W +-1%(0402)'                  | 'CHIP0402'     | ''          | ''            | '20140817'
 '147'        | '0.5%'    | '1/16W'  | '0402LF'  | 'CHIP'   | 'CS11472DB00'(!)        = ''              | ''                 | 'CS11472DB00'           | 'R0402'             | '(R0402-0201)'                 | '147'     | '0.5%'  | '1/16W'  | 'DISCRETE' | 'RES CHIP 147 1/16W +-0.5%(0402)'                  | 'CHIP0402'     | ''          | ''            | '20140817'
 '147'        | '0.5%'    | '1/16W'  | '0402LF'  | 'EMPTY'  | 'CS11472DB00'(!)        = ''              | ''                 | 'CS11472DB00'           | 'R0402'             | '(R0402-0201)'                 | '147'     | '0.5%'  | '1/16W'  | 'IO'       | 'RES CHIP 147 1/16W +-0.5%(0402)'                  | 'CHIP0402'     | ''          | ''            | '20140817'
 '2.61K'      | '0.5%'    | '1/16W'  | '0402LF'  | 'CHIP'   | 'CS22612DB00'(!)        = ''              | ''                 | 'CS22612DB00'           | 'R0402'             | '(R0402-0201)'                 | '2.61K'   | '0.5%'  | '1/16W'  | 'DISCRETE' | 'RES CHIP 2.61K 1/16W +-0.5%(0402)'                | 'CHIP0402'     | ''          | ''            | '20140817'
 '2.61K'      | '0.5%'    | '1/16W'  | '0402LF'  | 'EMPTY'  | 'CS22612DB00'(!)        = ''              | ''                 | 'CS22612DB00'           | 'R0402'             | '(R0402-0201)'                 | '2.61K'   | '0.5%'  | '1/16W'  | 'IO'       | 'RES CHIP 2.61K 1/16W +-0.5%(0402)'                | 'CHIP0402'     | ''          | ''            | '20140817'
 '2.74'       | '1%'      | '1/16W'  | '0402LF'  | 'CHIP'   | 'CS-2742FB00'(!)        = ''              | ''                 | 'CS-2742FB00'           | 'R0402'             | '(R0402-0201)'                 | '2.74'    | '1%'    | '1/16W'  | 'DISCRETE' | 'RES CHIP 2.74 1/16W +-1%(0402)'                   | 'CHIP0402'     | ''          | ''            | '20140817'
 '2.74'       | '1%'      | '1/16W'  | '0402LF'  | 'EMPTY'  | 'CS-2742FB00'(!)        = ''              | ''                 | 'CS-2742FB00'           | 'R0402'             | '(R0402-0201)'                 | '2.74'    | '1%'    | '1/16W'  | 'IO'       | 'RES CHIP 2.74 1/16W +-1%(0402)'                   | 'CHIP0402'     | ''          | ''            | '20140817'
 '10K'        | '1%'      | '1W'     | '2010LF'  | 'CHIP'   | 'CS31008FJ00'(!)        = ''              | ''                 | 'CS31008FJ00'           | 'R2010XB'           | '(SMR2010AW)'                  | '10K'     | '1%'    | '1W'     | 'DISCRETE' | 'RES CHIP 10K 1W +-1%(2010)'                       | 'CHIP2010'     | ''          | ''            | '20140817'
 '10K'        | '1%'      | '1W'     | '2010LF'  | 'EMPTY'  | 'CS31008FJ00'(!)        = ''              | ''                 | 'CS31008FJ00'           | 'R2010XB'           | '(SMR2010AW)'                  | '10K'     | '1%'    | '1W'     | 'IO'       | 'RES CHIP 10K 1W +-1%(2010)'                       | 'CHIP2010'     | ''          | ''            | '20140817'
 '158'        | '1%'      | '1/16W'  | '0402LF'  | 'CHIP'   | 'CS11582FB00'(!)        = ''              | ''                 | 'CS11582FB00'           | 'R0402'             | '(R0402-0201)'                 | '158'     | '1%'    | '1/16W'  | 'DISCRETE' | 'RES CHIP 158 1/16W +-1%(0402)'                    | 'CHIP0402'     | ''          | ''            | '20140817'
 '158'        | '1%'      | '1/16W'  | '0402LF'  | 'EMPTY'  | 'CS11582FB00'(!)        = ''              | ''                 | 'CS11582FB00'           | 'R0402'             | '(R0402-0201)'                 | '158'     | '1%'    | '1/16W'  | 'IO'       | 'RES CHIP 158 1/16W +-1%(0402)'                    | 'CHIP0402'     | ''          | ''            | '20140817'
 '0.007'      | '1%'      | '1W'     | '3720LF'  | 'CHIP'   | 'CS+0078FL00'(!)        = 'End of Design' | 'Comp-Approve'     | 'CS+0078FL00'           | 'R3720XA'           | '(SMR3720AW)'                  | '0.007'   | '1%'    | '1W'     | 'DISCRETE' | 'RES CHIP 0.007 1W +-1%(3720)'                     | 'CHIP3720'     | ''          | ''            | '20140817'
 '0.007'      | '1%'      | '1W'     | '3720LF'  | 'EMPTY'  | 'CS+0078FL00'(!)        = 'End of Design' | 'Comp-Approve'     | 'CS+0078FL00'           | 'R3720XA'           | '(SMR3720AW)'                  | '0.007'   | '1%'    | '1W'     | 'IO'       | 'RES CHIP 0.007 1W +-1%(3720)'                     | 'CHIP3720'     | ''          | ''            | '20140817'
 '2.49K'      | '1%'      | '1/2W'   | '1206LF'  | 'CHIP'   | 'CS22497F200'(!)        = ''              | ''                 | 'CS22497F200'           | 'R1206'             | '(SMR1206AW)'                  | '2.49K'   | '1%'    | '1/2W'   | 'DISCRETE' | 'RES CHIP 2.49K 1/2W +-1%(1206)'                   | 'CHIP1206'     | ''          | ''            | '20140818'
 '2.49K'      | '1%'      | '1/2W'   | '1206LF'  | 'EMPTY'  | 'CS22497F200'(!)        = ''              | ''                 | 'CS22497F200'           | 'R1206'             | '(SMR1206AW)'                  | '2.49K'   | '1%'    | '1/2W'   | 'IO'       | 'RES CHIP 2.49K 1/2W +-1%(1206)'                   | 'CHIP1206'     | ''          | ''            | '20140818'
 '1.1K'       | '0.1%'    | '1/16W'  | '0402LF'  | 'CHIP'   | 'CS21102BB00'(!)        = ''              | ''                 | 'CS21102BB00'           | 'R0402'             | '(R0402-0201)'                 | '1.1K'    | '0.1%'  | '1/16W'  | 'DISCRETE' | 'RES CHIP 1.1K 1/16W +-0.1%(0402)'                 | 'CHIP0402'     | ''          | ''            | '20140818'
 '1.1K'       | '0.1%'    | '1/16W'  | '0402LF'  | 'EMPTY'  | 'CS21102BB00'(!)        = ''              | ''                 | 'CS21102BB00'           | 'R0402'             | '(R0402-0201)'                 | '1.1K'    | '0.1%'  | '1/16W'  | 'IO'       | 'RES CHIP 1.1K 1/16W +-0.1%(0402)'                 | 'CHIP0402'     | ''          | ''            | '20140818'
 '52.3K'      | '1%'      | '1/16W'  | '0402LF'  | 'CHIP'   | 'CS35232FB10'(!)        = 'End of Design' | 'Comp-Approve'     | 'CS35232FB10'           | 'R0402'             | '(R0402-0201)'                 | '52.3K'   | '1%'    | '1/16W'  | 'DISCRETE' | 'RES CHIP 52.3K 1/16W +-1% (0402)'                 | 'CHIP0402'     | ''          | ''            | '20140818'
 '52.3K'      | '1%'      | '1/16W'  | '0402LF'  | 'EMPTY'  | 'CS35232FB10'(!)        = 'End of Design' | 'Comp-Approve'     | 'CS35232FB10'           | 'R0402'             | '(R0402-0201)'                 | '52.3K'   | '1%'    | '1/16W'  | 'IO'       | 'RES CHIP 52.3K 1/16W +-1% (0402)'                 | 'CHIP0402'     | ''          | ''            | '20140818'
 '1'          | '1%'      | '1/16W'  | '0402LF'  | 'CHIP'   | 'CS-1002FB23'(!)        = 'End of Design' | 'Comp-Approve'     | 'CS-1002FB23'           | 'R0402'             | '(R0402-0201)'                 | '1'       | '1%'    | '1/16W'  | 'DISCRETE' | 'RES CHIP 1 1/16W +-1%(0402)'                      | 'CHIP0402'     | ''          | ''            | '20140818'
 '1'          | '1%'      | '1/16W'  | '0402LF'  | 'EMPTY'  | 'CS-1002FB23'(!)        = 'End of Design' | 'Comp-Approve'     | 'CS-1002FB23'           | 'R0402'             | '(R0402-0201)'                 | '1'       | '1%'    | '1/16W'  | 'IO'       | 'RES CHIP 1 1/16W +-1%(0402)'                      | 'CHIP0402'     | ''          | ''            | '20140818'
 '0.5'        | '1%'      | '1/10W'  | '0603LF'  | 'CHIP'   | 'CS+5003F911'(!)        = ''              | ''                 | 'CS+5003F911'           | 'R0603'             | '(SMR0603AW)'                  | '0.5'     | '1%'    | '1/10W'  | 'DISCRETE' | 'RES CHIP 0.5 1/10W +-1%(0603)'                    | 'CHIP0603'     | ''          | ''            | '20140818'
 '0.5'        | '1%'      | '1/10W'  | '0603LF'  | 'EMPTY'  | 'CS+5003F911'(!)        = ''              | ''                 | 'CS+5003F911'           | 'R0603'             | '(SMR0603AW)'                  | '0.5'     | '1%'    | '1/10W'  | 'IO'       | 'RES CHIP 0.5 1/10W +-1%(0603)'                    | 'CHIP0603'     | ''          | ''            | '20140818'
 '1.91K'      | '1%'      | '1/10W'  | '0603LF'  | 'CHIP'   | 'CS21913F910'(!)        = ''              | ''                 | 'CS21913F910'           | 'R0603'             | '(SMR0603AW)'                  | '1.91K'   | '1%'    | '1/10W'  | 'DISCRETE' | 'RESISTER CHIP 1.91K 1/10W +-1%(0603)'             | 'CHIP0603'     | ''          | ''            | '20140818'
 '1.91K'      | '1%'      | '1/10W'  | '0603LF'  | 'EMPTY'  | 'CS21913F910'(!)        = ''              | ''                 | 'CS21913F910'           | 'R0603'             | '(SMR0603AW)'                  | '1.91K'   | '1%'    | '1/10W'  | 'IO'       | 'RESISTER CHIP 1.91K 1/10W +-1%(0603)'             | 'CHIP0603'     | ''          | ''            | '20140818'
 '30K'        | '1%'      | '1/10W'  | '0603LF'  | 'CHIP'   | 'CS33003F910'(!)        = ''              | ''                 | 'CS33003F910'           | 'R0603'             | '(SMR0603AW)'                  | '30K'     | '1%'    | '1/10W'  | 'DISCRETE' | 'RESISTOR CHIP 30K.1/10W.+-1%(0603)'               | 'CHIP0603'     | ''          | ''            | '20140818'
 '30K'        | '1%'      | '1/10W'  | '0603LF'  | 'EMPTY'  | 'CS33003F910'(!)        = ''              | ''                 | 'CS33003F910'           | 'R0603'             | '(SMR0603AW)'                  | '30K'     | '1%'    | '1/10W'  | 'IO'       | 'RESISTOR CHIP 30K.1/10W.+-1%(0603)'               | 'CHIP0603'     | ''          | ''            | '20140818'
 '0'          | '5%'      | '1W'     | '2512LF'  | 'CHIP'   | 'CS00008J125'(!)        = ''              | ''                 | 'CS00008J125'           | 'R2512'             | '(SMR2512AW)'                  | '0'       | '5%'    | '1W'     | 'DISCRETE' | 'RESISTOR CHIP 0 1W +-5% (2512)'                   | 'CHIP2512'     | ''          | ''            | '20140818'
 '0'          | '5%'      | '1W'     | '2512LF'  | 'EMPTY'  | 'CS00008J125'(!)        = ''              | ''                 | 'CS00008J125'           | 'R2512'             | '(SMR2512AW)'                  | '0'       | '5%'    | '1W'     | 'IO'       | 'RESISTOR CHIP 0 1W +-5% (2512)'                   | 'CHIP2512'     | ''          | ''            | '20140818'
 '39.2'       | '1%'      | '1/16W'  | '0402LF'  | 'CHIP'   | 'CS03922FB10'(!)        = 'End of Design' | 'Comp-Approve'     | 'CS03922FB10'           | 'R0402'             | '(R0402-0201)'                 | '39.2'    | '1%'    | '1/16W'  | 'DISCRETE' | 'RES CHIP 39.2 1/16W +-1%(0402)'                   | 'CHIP0402'     | ''          | ''            | '20140818'
 '39.2'       | '1%'      | '1/16W'  | '0402LF'  | 'EMPTY'  | 'CS03922FB10'(!)        = 'End of Design' | 'Comp-Approve'     | 'CS03922FB10'           | 'R0402'             | '(R0402-0201)'                 | '39.2'    | '1%'    | '1/16W'  | 'IO'       | 'RES CHIP 39.2 1/16W +-1%(0402)'                   | 'CHIP0402'     | ''          | ''            | '20140818'
 '191K'       | '1%'      | '1/8W'   | '0805LF'  | 'CHIP'   | 'CS41914FA00'(!)        = ''              | ''                 | 'CS41914FA00'           | 'R0805'             | '(SMR0805AW)'                  | '191K'    | '1%'    | '1/8W'   | 'DISCRETE' | 'RES CHIP 191K 1/8W +-1%(0805)'                    | 'CHIP0805'     | ''          | ''            | '20140819'
 '191K'       | '1%'      | '1/8W'   | '0805LF'  | 'EMPTY'  | 'CS41914FA00'(!)        = ''              | ''                 | 'CS41914FA00'           | 'R0805'             | '(SMR0805AW)'                  | '191K'    | '1%'    | '1/8W'   | 'IO'       | 'RES CHIP 191K 1/8W +-1%(0805)'                    | 'CHIP0805'     | ''          | ''            | '20140819'
 '28'         | '1%'      | '1/10W'  | '0603LF'  | 'CHIP'   | 'CS02803F900'(!)        = ''              | ''                 | 'CS02803F900'           | 'R0603'             | '(SMR0603AW)'                  | '28'      | '1%'    | '1/10W'  | 'DISCRETE' | 'RES CHIP 28 1/10W +-1%(0603)'                     | 'CHIP0603'     | ''          | ''            | '20140819'
 '28'         | '1%'      | '1/10W'  | '0603LF'  | 'EMPTY'  | 'CS02803F900'(!)        = ''              | ''                 | 'CS02803F900'           | 'R0603'             | '(SMR0603AW)'                  | '28'      | '1%'    | '1/10W'  | 'IO'       | 'RES CHIP 28 1/10W +-1%(0603)'                     | 'CHIP0603'     | ''          | ''            | '20140819'
 '52.3'       | '1%'      | '1/10W'  | '0603LF'  | 'CHIP'   | 'CS05233F900'(!)        = ''              | ''                 | 'CS05233F900'           | 'R0603'             | '(SMR0603AW)'                  | '52.3'    | '1%'    | '1/10W'  | 'DISCRETE' | 'RES CHIP 52.3 1/10W +-1%(0603)'                   | 'CHIP0603'     | ''          | ''            | '20140819'
 '52.3'       | '1%'      | '1/10W'  | '0603LF'  | 'EMPTY'  | 'CS05233F900'(!)        = ''              | ''                 | 'CS05233F900'           | 'R0603'             | '(SMR0603AW)'                  | '52.3'    | '1%'    | '1/10W'  | 'IO'       | 'RES CHIP 52.3 1/10W +-1%(0603)'                   | 'CHIP0603'     | ''          | ''            | '20140819'
 '0.008'      | '1%'      | '3W'     | '2512LF'  | 'CHIP'   | 'CS+008DFR00'(!)        = ''              | ''                 | 'CS+008DFR00'           | 'R2512XA'           | '(SMR2512AW)'                  | '0.008'   | '1%'    | '3W'     | 'DISCRETE' | 'RES CHIP 0.008 3W +-1%(2512)'                     | 'CHIP2512'     | ''          | ''            | '20140819'
 '0.008'      | '1%'      | '3W'     | '2512LF'  | 'EMPTY'  | 'CS+008DFR00'(!)        = ''              | ''                 | 'CS+008DFR00'           | 'R2512XA'           | '(SMR2512AW)'                  | '0.008'   | '1%'    | '3W'     | 'IO'       | 'RES CHIP 0.008 3W +-1%(2512)'                     | 'CHIP2512'     | ''          | ''            | '20140819'
 '0.002'      | '1%'      | '3W'     | '2512LF'  | 'CHIP'   | 'CS+002DFR00'(!)        = ''              | ''                 | 'CS+002DFR00'           | 'R2512XJ'           | '(SMR2512AW)'                  | '0.002'   | '1%'    | '3W'     | 'DISCRETE' | 'RES CHIP 0.002 3W +-1%(2512)'                     | 'CHIP2512'     | ''          | ''            | '20140819'
 '0.002'      | '1%'      | '3W'     | '2512LF'  | 'EMPTY'  | 'CS+002DFR00'(!)        = ''              | ''                 | 'CS+002DFR00'           | 'R2512XJ'           | '(SMR2512AW)'                  | '0.002'   | '1%'    | '3W'     | 'IO'       | 'RES CHIP 0.002 3W +-1%(2512)'                     | 'CHIP2512'     | ''          | ''            | '20140819'
 '180'        | '1%'      | '1/4W'   | '1206LF'  | 'CHIP'   | 'CS11806F215'(!)        = ''              | ''                 | 'CS11806F215'           | 'R1206'             | '(SMR1206AW)'                  | '180'     | '1%'    | '1/4W'   | 'DISCRETE' | 'RES CHIP 180 1/4W(+-1%,3216)'                     | 'CHIP1206'     | ''          | ''            | '20140819'
 '180'        | '1%'      | '1/4W'   | '1206LF'  | 'EMPTY'  | 'CS11806F215'(!)        = ''              | ''                 | 'CS11806F215'           | 'R1206'             | '(SMR1206AW)'                  | '180'     | '1%'    | '1/4W'   | 'IO'       | 'RES CHIP 180 1/4W(+-1%,3216)'                     | 'CHIP1206'     | ''          | ''            | '20140819'
 '1'          | '5%'      | '1/2W'   | '2010LF'  | 'CHIP'   | 'CS-1007JJ01'(!)        = ''              | ''                 | 'CS-1007JJ01'           | 'R2010'             | '(SMR2010AW)'                  | '1'       | '5%'    | '1/2W'   | 'DISCRETE' | 'RES CHIP 1 1/2W +-5%(2010)'                       | 'CHIP2010'     | ''          | ''            | '20140826'
 '1'          | '5%'      | '1/2W'   | '2010LF'  | 'EMPTY'  | 'CS-1007JJ01'(!)        = ''              | ''                 | 'CS-1007JJ01'           | 'R2010'             | '(SMR2010AW)'                  | '1'       | '5%'    | '1/2W'   | 'IO'       | 'RES CHIP 1 1/2W +-5%(2010)'                       | 'CHIP2010'     | ''          | ''            | '20140826'
 '28'         | '1%'      | '1/16W'  | '0402LF'  | 'CHIP'   | 'CS02802FB00'(!)        = ''              | ''                 | 'CS02802FB00'           | 'R0402'             | '(R0402-0201)'                 | '28'      | '1%'    | '1/16W'  | 'DISCRETE' | 'RES CHIP 28 1/16W +-1%(0402)'                     | 'CHIP0402'     | ''          | ''            | '20140826'
 '28'         | '1%'      | '1/16W'  | '0402LF'  | 'EMPTY'  | 'CS02802FB00'(!)        = ''              | ''                 | 'CS02802FB00'           | 'R0402'             | '(R0402-0201)'                 | '28'      | '1%'    | '1/16W'  | 'IO'       | 'RES CHIP 28 1/16W +-1%(0402)'                     | 'CHIP0402'     | ''          | ''            | '20140826'
 '3.32K'      | '1%'      | '1/16W'  | '0402LF'  | 'CHIP'   | 'CS23322FB20'(!)        = 'End of Design' | 'Comp-Approve'     | 'CS23322FB20'           | 'R0402'             | '(R0402-0201)'                 | '3.32K'   | '1%'    | '1/16W'  | 'DISCRETE' | 'RES CHIP 3.32K 1/16W +-1% (0402)'                 | 'CHIP0402'     | ''          | ''            | '20140826'
 '3.32K'      | '1%'      | '1/16W'  | '0402LF'  | 'EMPTY'  | 'CS23322FB20'(!)        = 'End of Design' | 'Comp-Approve'     | 'CS23322FB20'           | 'R0402'             | '(R0402-0201)'                 | '3.32K'   | '1%'    | '1/16W'  | 'IO'       | 'RES CHIP 3.32K 1/16W +-1% (0402)'                 | 'CHIP0402'     | ''          | ''            | '20140826'
 '200'        | '5%'      | '1W'     | '2512LF'  | 'CHIP'   | 'CS12008JR00'(!)        = ''              | ''                 | 'CS12008JR00'           | 'R2512'             | '(SMR2512AW)'                  | '200'     | '5%'    | '1W'     | 'DISCRETE' | 'RES CHIP 200 1W +-5%(2512)'                       | 'CHIP2512'     | ''          | ''            | '20140826'
 '200'        | '5%'      | '1W'     | '2512LF'  | 'EMPTY'  | 'CS12008JR00'(!)        = ''              | ''                 | 'CS12008JR00'           | 'R2512'             | '(SMR2512AW)'                  | '200'     | '5%'    | '1W'     | 'IO'       | 'RES CHIP 200 1W +-5%(2512)'                       | 'CHIP2512'     | ''          | ''            | '20140826'
 '300'        | '5%'      | '1/16W'  | '0402LF'  | 'CHIP'   | 'CS13002JB20'(!)        = 'End of Design' | 'Comp-Approve'     | 'CS13002JB20'           | 'R0402'             | '(R0402-0201)'                 | '300'     | '5%'    | '1/16W'  | 'DISCRETE' | 'RES CHIP 300 1/16W +-5% (0402)'                   | 'CHIP0402'     | ''          | ''            | '20140902'
 '300'        | '5%'      | '1/16W'  | '0402LF'  | 'EMPTY'  | 'CS13002JB20'(!)        = 'End of Design' | 'Comp-Approve'     | 'CS13002JB20'           | 'R0402'             | '(R0402-0201)'                 | '300'     | '5%'    | '1/16W'  | 'IO'       | 'RES CHIP 300 1/16W +-5% (0402)'                   | 'CHIP0402'     | ''          | ''            | '20140902'
 '10'         | '5%'      | '1/2W'   | '1210LF'  | 'CHIP'   | 'CS01007J300'(!)        = ''              | ''                 | 'CS01007J300'           | 'R1210'             | '(SMR1210AW)'                  | '10'      | '5%'    | '1/2W'   | 'DISCRETE' | 'RES CHIP 10 1/2W +-5%(1210)'                      | 'CHIP1210'     | ''          | ''            | '20140910'
 '10'         | '5%'      | '1/2W'   | '1210LF'  | 'EMPTY'  | 'CS01007J300'(!)        = ''              | ''                 | 'CS01007J300'           | 'R1210'             | '(SMR1210AW)'                  | '10'      | '5%'    | '1/2W'   | 'IO'       | 'RES CHIP 10 1/2W +-5%(1210)'                      | 'CHIP1210'     | ''          | ''            | '20140910'
 '2.1K'       | '0.1%'    | '1/16W'  | '0402LF'  | 'CHIP'   | 'CS22102BB00'(!)        = ''              | ''                 | 'CS22102BB00'           | 'R0402'             | '(R0402-0201)'                 | '2.1K'    | '0.1%'  | '1/16W'  | 'DISCRETE' | 'RES CHIP 2.1K 1/16W +/-0.1%(0402)'                | 'CHIP0402'     | ''          | ''            | '20140918'
 '2.1K'       | '0.1%'    | '1/16W'  | '0402LF'  | 'EMPTY'  | 'CS22102BB00'(!)        = ''              | ''                 | 'CS22102BB00'           | 'R0402'             | '(R0402-0201)'                 | '2.1K'    | '0.1%'  | '1/16W'  | 'IO'       | 'RES CHIP 2.1K 1/16W +/-0.1%(0402)'                | 'CHIP0402'     | ''          | ''            | '20140918'
 '1.2K'       | '1%'      | '1/16W'  | '0402LF'  | 'CHIP'   | 'CS21202FB13'(!)        = 'End of Design' | 'Comp-Approve'     | 'CS21202FB13'           | 'R0402'             | '(R0402-0201)'                 | '1.2K'    | '1%'    | '1/16W'  | 'DISCRETE' | 'RES CHIP 1.2K 1/16W+-1%(0402)'                    | 'CHIP0402'     | ''          | ''            | '20141003'
 '1.2K'       | '1%'      | '1/16W'  | '0402LF'  | 'EMPTY'  | 'CS21202FB13'(!)        = 'End of Design' | 'Comp-Approve'     | 'CS21202FB13'           | 'R0402'             | '(R0402-0201)'                 | '1.2K'    | '1%'    | '1/16W'  | 'IO'       | 'RES CHIP 1.2K 1/16W+-1%(0402)'                    | 'CHIP0402'     | ''          | ''            | '20141003'
 '10M'        | '1%'      | '1/10W'  | '0603LF'  | 'CHIP'   | 'CS61003F900'(!)        = ''              | ''                 | 'CS61003F900'           | 'R0603'             | '(SMR0603AW)'                  | '10M'     | '1%'    | '1/10W'  | 'DISCRETE' | 'RES CHIP 10M 1/10W +-1%(0603)'                    | 'CHIP0603'     | ''          | ''            | '20141008'
 '10M'        | '1%'      | '1/10W'  | '0603LF'  | 'EMPTY'  | 'CS61003F900'(!)        = ''              | ''                 | 'CS61003F900'           | 'R0603'             | '(SMR0603AW)'                  | '10M'     | '1%'    | '1/10W'  | 'IO'       | 'RES CHIP 10M 1/10W +-1%(0603)'                    | 'CHIP0603'     | ''          | ''            | '20141008'
 '200K'       | '0.1%'    | '1/10W'  | '0603LF'  | 'CHIP'   | 'CS42003B901'(!)        = ''              | ''                 | 'CS42003B901'           | 'R0603'             | '(SMR0603AW)'                  | '200K'    | '0.1%'  | '1/10W'  | 'DISCRETE' | 'RESISTOR CHIP 200K 1/10W +-0.1%(0603)'            | 'CHIP0603'     | ''          | ''            | '20141013'
 '200K'       | '0.1%'    | '1/10W'  | '0603LF'  | 'EMPTY'  | 'CS42003B901'(!)        = ''              | ''                 | 'CS42003B901'           | 'R0603'             | '(SMR0603AW)'                  | '200K'    | '0.1%'  | '1/10W'  | 'IO'       | 'RESISTOR CHIP 200K 1/10W +-0.1%(0603)'            | 'CHIP0603'     | ''          | ''            | '20141013'
 '0.01'       | '1%'      | '3W'     | '2512LF'  | 'CHIP'   | 'CS+100DFR00'(!)        = ''              | ''                 | 'CS+100DFR00'           | 'R2512XA'           | '(SMR2512AW)'                  | '0.01'    | '1%'    | '3W'     | 'DISCRETE' | 'RES CHIP 0.01 3W +-1%(2512)'                      | 'CHIP2512'     | ''          | ''            | '20141013'
 '0.01'       | '1%'      | '3W'     | '2512LF'  | 'EMPTY'  | 'CS+100DFR00'(!)        = ''              | ''                 | 'CS+100DFR00'           | 'R2512XA'           | '(SMR2512AW)'                  | '0.01'    | '1%'    | '3W'     | 'IO'       | 'RES CHIP 0.01 3W +-1%(2512)'                      | 'CHIP2512'     | ''          | ''            | '20141013'
 '113'        | '1%'      | '1/16W'  | '0402LF'  | 'CHIP'   | 'CS11132FB01'(!)        = 'End of Design' | 'Comp-Approve'     | 'CS11132FB01'           | 'R0402'             | '(R0402-0201)'                 | '113'     | '1%'    | '1/16W'  | 'DISCRETE' | 'RES CHIP 113 1/16W +-1%(0402)'                    | 'CHIP0402'     | ''          | ''            | '20141016'
 '113'        | '1%'      | '1/16W'  | '0402LF'  | 'EMPTY'  | 'CS11132FB01'(!)        = 'End of Design' | 'Comp-Approve'     | 'CS11132FB01'           | 'R0402'             | '(R0402-0201)'                 | '113'     | '1%'    | '1/16W'  | 'IO'       | 'RES CHIP 113 1/16W +-1%(0402)'                    | 'CHIP0402'     | ''          | ''            | '20141016'
 '249'        | '1%'      | '1/10W'  | '0603LF'  | 'CHIP'   | 'CS12493F935'(!)        = 'End of Design' | 'Comp-Approve'     | 'CS12493F935'           | 'R0603'             | '(SMR0603AW)'                  | '249'     | '1%'    | '1/10W'  | 'DISCRETE' | 'RES CHIP 249 1/10W +-1%(0603)EP'                  | 'CHIP0603'     | ''          | ''            | '20141016'
 '249'        | '1%'      | '1/10W'  | '0603LF'  | 'EMPTY'  | 'CS12493F935'(!)        = 'End of Design' | 'Comp-Approve'     | 'CS12493F935'           | 'R0603'             | '(SMR0603AW)'                  | '249'     | '1%'    | '1/10W'  | 'IO'       | 'RES CHIP 249 1/10W +-1%(0603)EP'                  | 'CHIP0603'     | ''          | ''            | '20141016'
 '249'        | '0.1%'    | '1/10W'  | '0603LF'  | 'CHIP'   | 'CS12493B900'(!)        = ''              | ''                 | 'CS12493B900'           | 'R0603'             | '(SMR0603AW)'                  | '249'     | '0.1%'  | '1/10W'  | 'DISCRETE' | 'RES CHIP 249 1/10W +-0.1%(0603)'                  | 'CHIP0603'     | ''          | ''            | '20141016'
 '249'        | '0.1%'    | '1/10W'  | '0603LF'  | 'EMPTY'  | 'CS12493B900'(!)        = ''              | ''                 | 'CS12493B900'           | 'R0603'             | '(SMR0603AW)'                  | '249'     | '0.1%'  | '1/10W'  | 'IO'       | 'RES CHIP 249 1/10W +-0.1%(0603)'                  | 'CHIP0603'     | ''          | ''            | '20141016'
 '0.008'      | '1%'      | '1/2W'   | '2010LF'  | 'CHIP'   | 'CS+0087FJ00'(!)        = ''              | ''                 | 'CS+0087FJ00'           | 'R2010XC'           | '(SMR2010AW)'                  | '0.008'   | '1%'    | '1/2W'   | 'DISCRETE' | 'RES CHIP 0.008 1/2W +-1%(2010)'                   | 'CHIP2010'     | ''          | ''            | '20141020'
 '0.008'      | '1%'      | '1/2W'   | '2010LF'  | 'EMPTY'  | 'CS+0087FJ00'(!)        = ''              | ''                 | 'CS+0087FJ00'           | 'R2010XC'           | '(SMR2010AW)'                  | '0.008'   | '1%'    | '1/2W'   | 'IO'       | 'RES CHIP 0.008 1/2W +-1%(2010)'                   | 'CHIP2010'     | ''          | ''            | '20141020'
 '0.005'      | '1%'      | '1W'     | '2512LF'  | 'CHIP'   | 'CS+0058F127'(!)        = ''              | ''                 | 'CS+0058F127'           | 'R2512'             | '(SMR2512AW)'                  | '0.005'   | '1%'    | '1W'     | 'DISCRETE' | 'RES CHIP 0.005 1W +-1%(2512)'                     | 'CHIP2512'     | ''          | ''            | '20141021'
 '0.005'      | '1%'      | '1W'     | '2512LF'  | 'EMPTY'  | 'CS+0058F127'(!)        = ''              | ''                 | 'CS+0058F127'           | 'R2512'             | '(SMR2512AW)'                  | '0.005'   | '1%'    | '1W'     | 'IO'       | 'RES CHIP 0.005 1W +-1%(2512)'                     | 'CHIP2512'     | ''          | ''            | '20141021'
 '36'         | '1%'      | '1/16W'  | '0402LF'  | 'CHIP'   | 'CS03602FB10'(!)        = 'End of Design' | 'Comp-Approve'     | 'CS03602FB10'           | 'R0402'             | '(R0402-0201)'                 | '36'      | '1%'    | '1/16W'  | 'DISCRETE' | 'RES CHIP 36 1/16W +-1%(0402)'                     | 'CHIP0402'     | ''          | ''            | '20141021'
 '36'         | '1%'      | '1/16W'  | '0402LF'  | 'EMPTY'  | 'CS03602FB10'(!)        = 'End of Design' | 'Comp-Approve'     | 'CS03602FB10'           | 'R0402'             | '(R0402-0201)'                 | '36'      | '1%'    | '1/16W'  | 'IO'       | 'RES CHIP 36 1/16W +-1%(0402)'                     | 'CHIP0402'     | ''          | ''            | '20141021'
 '100'        | '0.1%'    | '1/16W'  | '0402LF'  | 'CHIP'   | 'CS11002BB00'(!)        = ''              | ''                 | 'CS11002BB00'           | 'R0402'             | '(R0402-0201)'                 | '100'     | '0.1%'  | '1/16W'  | 'DISCRETE' | 'RES CHIP 100 1/16W +-0.1%(0402)'                  | 'CHIP0402'     | ''          | ''            | '20141021'
 '100'        | '0.1%'    | '1/16W'  | '0402LF'  | 'EMPTY'  | 'CS11002BB00'(!)        = ''              | ''                 | 'CS11002BB00'           | 'R0402'             | '(R0402-0201)'                 | '100'     | '0.1%'  | '1/16W'  | 'IO'       | 'RES CHIP 100 1/16W +-0.1%(0402)'                  | 'CHIP0402'     | ''          | ''            | '20141021'
 '0'          | '5%'      | '1/4W'   | '1206LF'  | 'CHIP'   | 'CS00006J248'(!)        = ''              | ''                 | 'CS00006J248'           | 'R1206'             | '(SMR1206AW)'                  | '0'       | '5%'    | '1/4W'   | 'DISCRETE' | 'RES CHIP 0 1/4W +-5%(1206)'                       | 'CHIP1206'     | ''          | ''            | '20141023'
 '0'          | '5%'      | '1/4W'   | '1206LF'  | 'EMPTY'  | 'CS00006J248'(!)        = ''              | ''                 | 'CS00006J248'           | 'R1206'             | '(SMR1206AW)'                  | '0'       | '5%'    | '1/4W'   | 'IO'       | 'RES CHIP 0 1/4W +-5%(1206)'                       | 'CHIP1206'     | ''          | ''            | '20141023'
 '7.5K'       | '0.1%'    | '1/16W'  | '0402LF'  | 'CHIP'   | 'CS27502BB00'(!)        = 'End of Design' | 'Comp-Approve'     | 'CS27502BB00'           | 'R0402'             | '(R0402-0201)'                 | '7.5K'    | '0.1%'  | '1/16W'  | 'DISCRETE' | 'RES CHIP 7.5K 1/16W +-0.1% (0402)'                | 'CHIP0402'     | ''          | ''            | '20141023'
 '7.5K'       | '0.1%'    | '1/16W'  | '0402LF'  | 'EMPTY'  | 'CS27502BB00'(!)        = 'End of Design' | 'Comp-Approve'     | 'CS27502BB00'           | 'R0402'             | '(R0402-0201)'                 | '7.5K'    | '0.1%'  | '1/16W'  | 'IO'       | 'RES CHIP 7.5K 1/16W +-0.1% (0402)'                | 'CHIP0402'     | ''          | ''            | '20141023'
 '3'          | '5%'      | '1W'     | '2512LF'  | 'CHIP'   | 'CS-3008JR00'(!)        = 'End of Design' | 'Comp-Release Qty' | 'CS-3008JR00'           | 'R2512'             | '(SMR2512)'                    | '3'       | '5%'    | '1W'     | 'DISCRETE' | 'RESISTOR CHIP 3 1W +-5%(2512)'                    | 'CHIP2512'     | ''          | ''            | '20141028'
 '3'          | '5%'      | '1W'     | '2512LF'  | 'EMPTY'  | 'CS-3008JR00'(!)        = 'End of Design' | 'Comp-Release Qty' | 'CS-3008JR00'           | 'R2512'             | '(SMR2512)'                    | '3'       | '5%'    | '1W'     | 'IO'       | 'RESISTOR CHIP 3 1W +-5%(2512)'                    | 'CHIP2512'     | ''          | ''            | '20141028'
 '8.25K'      | '0.1%'    | '1/16W'  | '0402LF'  | 'CHIP'   | 'CS28252BB00'(!)        = ''              | ''                 | 'CS28252BB00'           | 'R0402'             | '(R0402-0201)'                 | '8.25K'   | '0.1%'  | '1/16W'  | 'DISCRETE' | 'RES CHIP 8.25K 1/16W +-0.1%(0402)'                | 'CHIP0402'     | ''          | ''            | '20141029'
 '8.25K'      | '0.1%'    | '1/16W'  | '0402LF'  | 'EMPTY'  | 'CS28252BB00'(!)        = ''              | ''                 | 'CS28252BB00'           | 'R0402'             | '(R0402-0201)'                 | '8.25K'   | '0.1%'  | '1/16W'  | 'IO'       | 'RES CHIP 8.25K 1/16W +-0.1%(0402)'                | 'CHIP0402'     | ''          | ''            | '20141029'
 '28K'        | '0.1%'    | '1/16W'  | '0402LF'  | 'CHIP'   | 'CS32802BB00'(!)        = ''              | ''                 | 'CS32802BB00'           | 'R0402'             | '(R0402-0201)'                 | '28K'     | '0.1%'  | '1/16W'  | 'DISCRETE' | 'RES CHIP 28K 1/16W +-0.1%(0402)'                  | 'CHIP0402'     | ''          | ''            | '20141029'
 '28K'        | '0.1%'    | '1/16W'  | '0402LF'  | 'EMPTY'  | 'CS32802BB00'(!)        = ''              | ''                 | 'CS32802BB00'           | 'R0402'             | '(R0402-0201)'                 | '28K'     | '0.1%'  | '1/16W'  | 'IO'       | 'RES CHIP 28K 1/16W +-0.1%(0402)'                  | 'CHIP0402'     | ''          | ''            | '20141029'
 '22.9K'      | '0.1%'    | '1/16W'  | '0402LF'  | 'CHIP'   | 'CS32292BB00'(!)        = ''              | ''                 | 'CS32292BB00'           | 'R0402'             | '(R0402-0201)'                 | '22.9K'   | '0.1%'  | '1/16W'  | 'DISCRETE' | 'RES CHIP 22.9K 1/16W +-0.1%(0402)'                | 'CHIP0402'     | ''          | ''            | '20141029'
 '22.9K'      | '0.1%'    | '1/16W'  | '0402LF'  | 'EMPTY'  | 'CS32292BB00'(!)        = ''              | ''                 | 'CS32292BB00'           | 'R0402'             | '(R0402-0201)'                 | '22.9K'   | '0.1%'  | '1/16W'  | 'IO'       | 'RES CHIP 22.9K 1/16W +-0.1%(0402)'                | 'CHIP0402'     | ''          | ''            | '20141029'
 '22.1K'      | '0.1%'    | '1/16W'  | '0402LF'  | 'CHIP'   | 'CS32212BB00'(!)        = ''              | ''                 | 'CS32212BB00'           | 'R0402'             | '(R0402-0201)'                 | '22.1K'   | '0.1%'  | '1/16W'  | 'DISCRETE' | 'RES CHIP 22.1K 1/16W +-0.1%(0402)'                | 'CHIP0402'     | ''          | ''            | '20141029'
 '22.1K'      | '0.1%'    | '1/16W'  | '0402LF'  | 'EMPTY'  | 'CS32212BB00'(!)        = ''              | ''                 | 'CS32212BB00'           | 'R0402'             | '(R0402-0201)'                 | '22.1K'   | '0.1%'  | '1/16W'  | 'IO'       | 'RES CHIP 22.1K 1/16W +-0.1%(0402)'                | 'CHIP0402'     | ''          | ''            | '20141029'
 '12K'        | '0.1%'    | '1/16W'  | '0402LF'  | 'CHIP'   | 'CS31202BB00'(!)        = ''              | ''                 | 'CS31202BB00'           | 'R0402'             | '(R0402-0201)'                 | '12K'     | '0.1%'  | '1/16W'  | 'DISCRETE' | 'RES CHIP 12K 1/16W +-0.1%(0402)'                  | 'CHIP0402'     | ''          | ''            | '20141029'
 '12K'        | '0.1%'    | '1/16W'  | '0402LF'  | 'EMPTY'  | 'CS31202BB00'(!)        = ''              | ''                 | 'CS31202BB00'           | 'R0402'             | '(R0402-0201)'                 | '12K'     | '0.1%'  | '1/16W'  | 'IO'       | 'RES CHIP 12K 1/16W +-0.1%(0402)'                  | 'CHIP0402'     | ''          | ''            | '20141029'
 '1.87K'      | '0.1%'    | '1/16W'  | '0402LF'  | 'CHIP'   | 'CS21872B100'(!)        = ''              | ''                 | 'CS21872B100'           | 'R0402'             | '(R0402-0201)'                 | '1.87K'   | '0.1%'  | '1/16W'  | 'DISCRETE' | 'RES CHIP 1.87K(1/16W,+-0.1%,0402)'                | 'CHIP0402'     | ''          | ''            | '20141111'
 '1.87K'      | '0.1%'    | '1/16W'  | '0402LF'  | 'EMPTY'  | 'CS21872B100'(!)        = ''              | ''                 | 'CS21872B100'           | 'R0402'             | '(R0402-0201)'                 | '1.87K'   | '0.1%'  | '1/16W'  | 'IO'       | 'RES CHIP 1.87K(1/16W,+-0.1%,0402)'                | 'CHIP0402'     | ''          | ''            | '20141111'
 '10.4K'      | '0.1%'    | '1/16W'  | '0402LF'  | 'CHIP'   | 'CS31042B100'(!)        = ''              | ''                 | 'CS31042B100'           | 'R0402'             | '(R0402-0201)'                 | '10.4K'   | '0.1%'  | '1/16W'  | 'DISCRETE' | 'RES CHIP 10.4K(1/16W,+-0.1%,0402)'                | 'CHIP0402'     | ''          | ''            | '20141111'
 '10.4K'      | '0.1%'    | '1/16W'  | '0402LF'  | 'EMPTY'  | 'CS31042B100'(!)        = ''              | ''                 | 'CS31042B100'           | 'R0402'             | '(R0402-0201)'                 | '10.4K'   | '0.1%'  | '1/16W'  | 'IO'       | 'RES CHIP 10.4K(1/16W,+-0.1%,0402)'                | 'CHIP0402'     | ''          | ''            | '20141111'
 '12.7K'      | '0.1%'    | '1/16W'  | '0402LF'  | 'CHIP'   | 'CS31272B100'(!)        = ''              | ''                 | 'CS31272B100'           | 'R0402'             | '(R0402-0201)'                 | '12.7K'   | '0.1%'  | '1/16W'  | 'DISCRETE' | 'RES CHIP 12.7K(1/16W,+-0.1%,0402)'                | 'CHIP0402'     | ''          | ''            | '20141111'
 '12.7K'      | '0.1%'    | '1/16W'  | '0402LF'  | 'EMPTY'  | 'CS31272B100'(!)        = ''              | ''                 | 'CS31272B100'           | 'R0402'             | '(R0402-0201)'                 | '12.7K'   | '0.1%'  | '1/16W'  | 'IO'       | 'RES CHIP 12.7K(1/16W,+-0.1%,0402)'                | 'CHIP0402'     | ''          | ''            | '20141111'
 '47K'        | '0.1%'    | '1/16W'  | '0402LF'  | 'CHIP'   | 'CS34702B100'(!)        = ''              | ''                 | 'CS34702B100'           | 'R0402'             | '(R0402-0201)'                 | '47K'     | '0.1%'  | '1/16W'  | 'DISCRETE' | 'RES CHIP 47K(1/16W,+-0.1%,0402)'                  | 'CHIP0402'     | ''          | ''            | '20141111'
 '47K'        | '0.1%'    | '1/16W'  | '0402LF'  | 'EMPTY'  | 'CS34702B100'(!)        = ''              | ''                 | 'CS34702B100'           | 'R0402'             | '(R0402-0201)'                 | '47K'     | '0.1%'  | '1/16W'  | 'IO'       | 'RES CHIP 47K(1/16W,+-0.1%,0402)'                  | 'CHIP0402'     | ''          | ''            | '20141111'
 '115K'       | '0.1%'    | '1/16W'  | '0402LF'  | 'CHIP'   | 'CS41152B100'(!)        = ''              | ''                 | 'CS41152B100'           | 'R0402'             | '(R0402-0201)'                 | '115K'    | '0.1%'  | '1/16W'  | 'DISCRETE' | 'RES CHIP 115K(1/16W,+-0.1%,0402)'                 | 'CHIP0402'     | ''          | ''            | '20141111'
 '115K'       | '0.1%'    | '1/16W'  | '0402LF'  | 'EMPTY'  | 'CS41152B100'(!)        = ''              | ''                 | 'CS41152B100'           | 'R0402'             | '(R0402-0201)'                 | '115K'    | '0.1%'  | '1/16W'  | 'IO'       | 'RES CHIP 115K(1/16W,+-0.1%,0402)'                 | 'CHIP0402'     | ''          | ''            | '20141111'
 '1.3K'       | '1%'      | '1/8W'   | '0805LF'  | 'CHIP'   | 'CS21304FA00'(!)        = ''              | ''                 | 'CS21304FA00'           | 'R0805'             | '(SMR0805AW)'                  | '1.3K'    | '1%'    | '1/8W'   | 'DISCRETE' | 'RES CHIP 1.3K 1/8W +-1%(0805)'                    | 'CHIP0805'     | ''          | ''            | '20141128'
 '1.3K'       | '1%'      | '1/8W'   | '0805LF'  | 'EMPTY'  | 'CS21304FA00'(!)        = ''              | ''                 | 'CS21304FA00'           | 'R0805'             | '(SMR0805AW)'                  | '1.3K'    | '1%'    | '1/8W'   | 'IO'       | 'RES CHIP 1.3K 1/8W +-1%(0805)'                    | 'CHIP0805'     | ''          | ''            | '20141128'
 '249'        | '0.1%'    | '1/16W'  | '0402LF'  | 'CHIP'   | 'CS12492BB00'(!)        = ''              | ''                 | 'CS12492BB00'           | 'R0402'             | '(R0402-0201)'                 | '249'     | '0.1%'  | '1/16W'  | 'DISCRETE' | 'RES CHIP 249 1/16W +-0.1%(0402)'                  | 'CHIP0402'     | ''          | ''            | '20150106'
 '249'        | '0.1%'    | '1/16W'  | '0402LF'  | 'EMPTY'  | 'CS12492BB00'(!)        = ''              | ''                 | 'CS12492BB00'           | 'R0402'             | '(R0402-0201)'                 | '249'     | '0.1%'  | '1/16W'  | 'IO'       | 'RES CHIP 249 1/16W +-0.1%(0402)'                  | 'CHIP0402'     | ''          | ''            | '20150106'
 '0.001'      | '1%'      | '3W'     | '2512LF'  | 'CHIP'   | 'CS0000DFR01'(!)        = 'Potential'     | 'End of Life'      | 'CS0000DFR01'           | 'R2512XG_EOL'       | '(SMR2512AW)'                  | '0.001'   | '1%'    | '3W'     | 'DISCRETE' | 'RES CHIP 0.001 3W(+-1%,2512)'                     | 'CHIP2512'     | ''          | ''            | '20150107'
 '0.001'      | '1%'      | '3W'     | '2512LF'  | 'EMPTY'  | 'CS0000DFR01'(!)        = 'Potential'     | 'End of Life'      | 'CS0000DFR01'           | 'R2512XG_EOL'       | '(SMR2512AW)'                  | '0.001'   | '1%'    | '3W'     | 'IO'       | 'RES CHIP 0.001 3W(+-1%,2512)'                     | 'CHIP2512'     | ''          | ''            | '20150107'
 '45.3'       | '1%'      | '1/16W'  | '0402LF'  | 'CHIP'   | 'CS04532FB12'(!)        = 'End of Design' | 'Comp-Approve'     | 'CS04532FB12'           | 'R0402'             | '(R0402-0201)'                 | '45.3'    | '1%'    | '1/16W'  | 'DISCRETE' | 'RES CHIP 45.3 1/16W +-1%( 0402)'                  | 'CHIP0402'     | ''          | ''            | '20150114'
 '45.3'       | '1%'      | '1/16W'  | '0402LF'  | 'EMPTY'  | 'CS04532FB12'(!)        = 'End of Design' | 'Comp-Approve'     | 'CS04532FB12'           | 'R0402'             | '(R0402-0201)'                 | '45.3'    | '1%'    | '1/16W'  | 'IO'       | 'RES CHIP 45.3 1/16W +-1%( 0402)'                  | 'CHIP0402'     | ''          | ''            | '20150114'
 '270K'       | '1%'      | '1/16W'  | '0402LF'  | 'CHIP'   | 'CS42702FB00'(!)        = ''              | ''                 | 'CS42702FB00'           | 'R0402'             | '(R0402-0201)'                 | '270K'    | '1%'    | '1/16W'  | 'DISCRETE' | 'RES CHIP 270K 1/16W +-1%(0402)'                   | 'CHIP0402'     | ''          | ''            | '20150127'
 '270K'       | '1%'      | '1/16W'  | '0402LF'  | 'EMPTY'  | 'CS42702FB00'(!)        = ''              | ''                 | 'CS42702FB00'           | 'R0402'             | '(R0402-0201)'                 | '270K'    | '1%'    | '1/16W'  | 'IO'       | 'RES CHIP 270K 1/16W +-1%(0402)'                   | 'CHIP0402'     | ''          | ''            | '20150127'
 '36'         | '5%'      | '1/16W'  | '0402LF'  | 'CHIP'   | 'CS03602JB00'(!)        = 'End of Design' | 'Comp-Approve'     | 'CS03602JB00'           | 'R0402'             | '(R0402-0201)'                 | '36'      | '5%'    | '1/16W'  | 'DISCRETE' | 'RES CHIP 36 1/16W +-5%(0402)'                     | 'CHIP0402'     | ''          | ''            | '20150130'
 '36'         | '5%'      | '1/16W'  | '0402LF'  | 'EMPTY'  | 'CS03602JB00'(!)        = 'End of Design' | 'Comp-Approve'     | 'CS03602JB00'           | 'R0402'             | '(R0402-0201)'                 | '36'      | '5%'    | '1/16W'  | 'IO'       | 'RES CHIP 36 1/16W +-5%(0402)'                     | 'CHIP0402'     | ''          | ''            | '20150130'
 '0.62'       | '5%'      | '15W'    | 'THLF'    | 'CHIP'   | 'CL+620AJ000'(!)        = ''              | ''                 | 'CL+620AJ000'           | 'R18949D'           | '(R18949D)'                    | '0.62'    | '5%'    | '15W'    | 'DISCRETE' | 'RESISTOR CEMENT 0.62 15W +-5%(SQP)'               | 'R18949D'      | ''          | ''            | '20150130'
 '0.62'       | '5%'      | '15W'    | 'THLF'    | 'EMPTY'  | 'CL+620AJ000'(!)        = ''              | ''                 | 'CL+620AJ000'           | 'R18949D'           | '(R18949D)'                    | '0.62'    | '5%'    | '15W'    | 'IO'       | 'RESISTOR CEMENT 0.62 15W +-5%(SQP)'               | 'R18949D'      | ''          | ''            | '20150130'
 '0.39'       | '5%'      | '15W'    | 'THLF'    | 'CHIP'   | 'CL+390AJ000'(!)        = ''              | ''                 | 'CL+390AJ000'           | 'R18949D'           | '(R18949D)'                    | '0.39'    | '5%'    | '15W'    | 'DISCRETE' | 'RESISTOR CEMENT 0.39 15W +-5%(SQP)'               | 'R18949D'      | ''          | ''            | '20150130'
 '0.39'       | '5%'      | '15W'    | 'THLF'    | 'EMPTY'  | 'CL+390AJ000'(!)        = ''              | ''                 | 'CL+390AJ000'           | 'R18949D'           | '(R18949D)'                    | '0.39'    | '5%'    | '15W'    | 'IO'       | 'RESISTOR CEMENT 0.39 15W +-5%(SQP)'               | 'R18949D'      | ''          | ''            | '20150130'
 '3.16K'      | '1%'      | '1/10W'  | '0603LF'  | 'CHIP'   | 'CS23163F901'(!)        = ''              | ''                 | 'CS23163F901'           | 'R0603'             | '(SMR0603AW)'                  | '3.16K'   | '1%'    | '1/10W'  | 'DISCRETE' | 'RES CHIP 3.16K 1/10W +-1%(0603)'                  | 'CHIP0603'     | ''          | ''            | '20150203'
 '3.16K'      | '1%'      | '1/10W'  | '0603LF'  | 'EMPTY'  | 'CS23163F901'(!)        = ''              | ''                 | 'CS23163F901'           | 'R0603'             | '(SMR0603AW)'                  | '3.16K'   | '1%'    | '1/10W'  | 'IO'       | 'RES CHIP 3.16K 1/10W +-1%(0603)'                  | 'CHIP0603'     | ''          | ''            | '20150203'
 '866'        | '1%'      | '1/16W'  | '0402LF'  | 'CHIP'   | 'CS18662FB00'(!)        = 'End of Design' | 'Comp-Approve'     | 'CS18662FB00'           | 'R0402'             | '(R0402-0201)'                 | '866'     | '1%'    | '1/16W'  | 'DISCRETE' | 'RES CHIP 866 1/16W +-1%(0402)'                    | 'CHIP0402'     | ''          | ''            | '20150203'
 '866'        | '1%'      | '1/16W'  | '0402LF'  | 'EMPTY'  | 'CS18662FB00'(!)        = 'End of Design' | 'Comp-Approve'     | 'CS18662FB00'           | 'R0402'             | '(R0402-0201)'                 | '866'     | '1%'    | '1/16W'  | 'IO'       | 'RES CHIP 866 1/16W +-1%(0402)'                    | 'CHIP0402'     | ''          | ''            | '20150203'
 '45.3K'      | '1%'      | '1/8W'   | '0805LF'  | 'CHIP'   | 'CS34534FA00'(!)        = ''              | ''                 | 'CS34534FA00'           | 'R0805'             | '(SMR0805AW)'                  | '45.3K'   | '1%'    | '1/8W'   | 'DISCRETE' | 'RES CHIP 45.3K 1/8W +-1%(0805)'                   | 'CHIP0805'     | ''          | ''            | '20150210'
 '45.3K'      | '1%'      | '1/8W'   | '0805LF'  | 'EMPTY'  | 'CS34534FA00'(!)        = ''              | ''                 | 'CS34534FA00'           | 'R0805'             | '(SMR0805AW)'                  | '45.3K'   | '1%'    | '1/8W'   | 'IO'       | 'RES CHIP 45.3K 1/8W +-1%(0805)'                   | 'CHIP0805'     | ''          | ''            | '20150210'
 '220K'       | '1%'      | '1/16W'  | '0402LF'  | 'CHIP'   | 'CS42202FB10'(!)        = 'End of Design' | 'Comp-Approve'     | 'CS42202FB10'           | 'R0402'             | '(R0402-0201)'                 | '220K'    | '1%'    | '1/16W'  | 'DISCRETE' | 'RES CHIP 220K 1/16W +-1%(0402)'                   | 'CHIP0402'     | ''          | ''            | '20150302'
 '220K'       | '1%'      | '1/16W'  | '0402LF'  | 'EMPTY'  | 'CS42202FB10'(!)        = 'End of Design' | 'Comp-Approve'     | 'CS42202FB10'           | 'R0402'             | '(R0402-0201)'                 | '220K'    | '1%'    | '1/16W'  | 'IO'       | 'RES CHIP 220K 1/16W +-1%(0402)'                   | 'CHIP0402'     | ''          | ''            | '20150302'
 '3.16K'      | '1%'      | '1/10W'  | '0603LF'  | 'CHIP'   | 'CS23163F919'(!)        = ''              | ''                 | 'CS23163F919'           | 'R0603'             | '(SMR0603AW)'                  | '3.16K'   | '1%'    | '1/10W'  | 'DISCRETE' | 'RESISTER CHIP 3.16K 1/10W +-1%(0603)EP'           | 'CHIP0603'     | ''          | ''            | '20150302'
 '3.16K'      | '1%'      | '1/10W'  | '0603LF'  | 'EMPTY'  | 'CS23163F919'(!)        = ''              | ''                 | 'CS23163F919'           | 'R0603'             | '(SMR0603AW)'                  | '3.16K'   | '1%'    | '1/10W'  | 'IO'       | 'RESISTER CHIP 3.16K 1/10W +-1%(0603)EP'           | 'CHIP0603'     | ''          | ''            | '20150302'
 '3.9K'       | '5%'      | '1/16W'  | '0402LF'  | 'CHIP'   | 'CS23902JB00'(!)        = 'End of Design' | 'Comp-Approve'     | 'CS23902JB00'           | 'R0402'             | '(R0402-0201)'                 | '3.9K'    | '5%'    | '1/16W'  | 'DISCRETE' | 'RES CHIP 3.9K 1/16W +-5%(0402)'                   | 'CHIP0402'     | ''          | ''            | '20150303'
 '3.9K'       | '5%'      | '1/16W'  | '0402LF'  | 'EMPTY'  | 'CS23902JB00'(!)        = 'End of Design' | 'Comp-Approve'     | 'CS23902JB00'           | 'R0402'             | '(R0402-0201)'                 | '3.9K'    | '5%'    | '1/16W'  | 'IO'       | 'RES CHIP 3.9K 1/16W +-5%(0402)'                   | 'CHIP0402'     | ''          | ''            | '20150303'
 '68K'        | '1%'      | '1/16W'  | '0402LF'  | 'CHIP'   | 'CS36802FB00'(!)        = 'End of Design' | 'Comp-Approve'     | 'CS36802FB00'           | 'R0402'             | '(R0402-0201)'                 | '68K'     | '1%'    | '1/16W'  | 'DISCRETE' | 'RES CHIP 68K 1/16W +-1%(0402)'                    | 'CHIP0402'     | ''          | ''            | '20150303'
 '68K'        | '1%'      | '1/16W'  | '0402LF'  | 'EMPTY'  | 'CS36802FB00'(!)        = 'End of Design' | 'Comp-Approve'     | 'CS36802FB00'           | 'R0402'             | '(R0402-0201)'                 | '68K'     | '1%'    | '1/16W'  | 'IO'       | 'RES CHIP 68K 1/16W +-1%(0402)'                    | 'CHIP0402'     | ''          | ''            | '20150303'
 '787'        | '1%'      | '1/16W'  | '0402LF'  | 'CHIP'   | 'CS17872FB00'(!)        = 'End of Design' | 'Comp-Approve'     | 'CS17872FB00'           | 'R0402'             | '(R0402-0201)'                 | '787'     | '1%'    | '1/16W'  | 'DISCRETE' | 'RES CHIP 787 1/16W +-1%(0402)'                    | 'CHIP0402 '    | ''          | ''            | '20150310'
 '787'        | '1%'      | '1/16W'  | '0402LF'  | 'EMPTY'  | 'CS17872FB00'(!)        = 'End of Design' | 'Comp-Approve'     | 'CS17872FB00'           | 'R0402'             | '(R0402-0201)'                 | '787'     | '1%'    | '1/16W'  | 'IO'       | 'RES CHIP 787 1/16W +-1%(0402)'                    | 'CHIP0402 '    | ''          | ''            | '20150310'
 '787'        | '1%'      | '1/10W'  | '0603LF'  | 'CHIP'   | 'CS17873F901'(!)        = ''              | ''                 | 'CS17873F901'           | 'R0603'             | '(SMR0603AW)'                  | '787'     | '1%'    | '1/10W'  | 'DISCRETE' | 'RES CHIP 787 1/10W +-1%(0603)'                    | 'CHIP0603'     | ''          | ''            | '20150312'
 '787'        | '1%'      | '1/10W'  | '0603LF'  | 'EMPTY'  | 'CS17873F901'(!)        = ''              | ''                 | 'CS17873F901'           | 'R0603'             | '(SMR0603AW)'                  | '787'     | '1%'    | '1/10W'  | 'IO'       | 'RES CHIP 787 1/10W +-1%(0603)'                    | 'CHIP0603'     | ''          | ''            | '20150312'
 '866K'       | '1%'      | '1/16W'  | '0402LF'  | 'CHIP'   | 'CS48662FB00'(!)        = 'End of Design' | 'Comp-Approve'     | 'CS48662FB00'           | 'R0402'             | '(R0402-0201)'                 | '866K'    | '1%'    | '1/16W'  | 'DISCRETE' | 'RES CHIP 866K 1/16W +-1%(0402)'                   | 'CHIP0402'     | ''          | ''            | '20150316'
 '866K'       | '1%'      | '1/16W'  | '0402LF'  | 'EMPTY'  | 'CS48662FB00'(!)        = 'End of Design' | 'Comp-Approve'     | 'CS48662FB00'           | 'R0402'             | '(R0402-0201)'                 | '866K'    | '1%'    | '1/16W'  | 'IO'       | 'RES CHIP 866K 1/16W +-1%(0402)'                   | 'CHIP0402'     | ''          | ''            | '20150316'
 '2.94K'      | '0.1%'    | '1/16W'  | '0402LF'  | 'CHIP'   | 'CS22942BB00'(!)        = ''              | ''                 | 'CS22942BB00'           | 'R0402'             | '(R0402-0201)'                 | '2.94K'   | '0.1%'  | '1/16W'  | 'DISCRETE' | 'RES CHIP 2.94K 1/16W +-0.1%(0402)'                | 'CHIP0402 '    | ''          | ''            | '20150324'
 '2.94K'      | '0.1%'    | '1/16W'  | '0402LF'  | 'EMPTY'  | 'CS22942BB00'(!)        = ''              | ''                 | 'CS22942BB00'           | 'R0402'             | '(R0402-0201)'                 | '2.94K'   | '0.1%'  | '1/16W'  | 'IO'       | 'RES CHIP 2.94K 1/16W +-0.1%(0402)'                | 'CHIP0402 '    | ''          | ''            | '20150324'
 '1.24K'      | '0.1%'    | '1/10W'  | '0603LF'  | 'CHIP'   | 'CS21243B900'(!)        = ''              | ''                 | 'CS21243B900'           | 'R0603'             | '(SMR0603AW)'                  | '1.24K'   | '0.1%'  | '1/10W'  | 'DISCRETE' | 'RES CHIP 1.24K 1/10W +-0.1%(0603)'                | 'CHIP0603'     | ''          | ''            | '20150324'
 '1.24K'      | '0.1%'    | '1/10W'  | '0603LF'  | 'EMPTY'  | 'CS21243B900'(!)        = ''              | ''                 | 'CS21243B900'           | 'R0603'             | '(SMR0603AW)'                  | '1.24K'   | '0.1%'  | '1/10W'  | 'IO'       | 'RES CHIP 1.24K 1/10W +-0.1%(0603)'                | 'CHIP0603'     | ''          | ''            | '20150324'
 '3.32K'      | '0.1%'    | '1/10W'  | '0603LF'  | 'CHIP'   | 'CS23323B900'(!)        = ''              | ''                 | 'CS23323B900'           | 'R0603'             | '(SMR0603AW)'                  | '3.32K'   | '0.1%'  | '1/10W'  | 'DISCRETE' | 'RES CHIP 3.32K 1/10W +-0.1%(0603)'                | 'CHIP0603'     | ''          | ''            | '20150324'
 '3.32K'      | '0.1%'    | '1/10W'  | '0603LF'  | 'EMPTY'  | 'CS23323B900'(!)        = ''              | ''                 | 'CS23323B900'           | 'R0603'             | '(SMR0603AW)'                  | '3.32K'   | '0.1%'  | '1/10W'  | 'IO'       | 'RES CHIP 3.32K 1/10W +-0.1%(0603)'                | 'CHIP0603'     | ''          | ''            | '20150324'
 '0.51'       | '1%'      | '1/4W'   | '0805LF'  | 'CHIP'   | 'CS+5106FA00'(!)        = ''              | ''                 | 'CS+5106FA00'           | 'R0805'             | '(SMR0805AW)'                  | '0.51'    | '1%'    | '1/4W'   | 'DISCRETE' | 'RES CHIP 0.51 1/4W.+-1%(0805)'                    | 'CHIP0805'     | ''          | ''            | '20150327'
 '0.51'       | '1%'      | '1/4W'   | '0805LF'  | 'EMPTY'  | 'CS+5106FA00'(!)        = ''              | ''                 | 'CS+5106FA00'           | 'R0805'             | '(SMR0805AW)'                  | '0.51'    | '1%'    | '1/4W'   | 'IO'       | 'RES CHIP 0.51 1/4W.+-1%(0805)'                    | 'CHIP0805'     | ''          | ''            | '20150327'
 '4.53K'      | '1%'      | '1/10W'  | '0603LF'  | 'CHIP'   | 'CS24533F921'(!)        = ''              | ''                 | 'CS24533F921'           | 'R0603'             | '(SMR0603AW)'                  | '4.53K'   | '1%'    | '1/10W'  | 'DISCRETE' | 'RESISTOR CHIP 4.53K 1/10W +-1%(0603)'             | 'CHIP0603'     | ''          | ''            | '20150410'
 '4.53K'      | '1%'      | '1/10W'  | '0603LF'  | 'EMPTY'  | 'CS24533F921'(!)        = ''              | ''                 | 'CS24533F921'           | 'R0603'             | '(SMR0603AW)'                  | '4.53K'   | '1%'    | '1/10W'  | 'IO'       | 'RESISTOR CHIP 4.53K 1/10W +-1%(0603)'             | 'CHIP0603'     | ''          | ''            | '20150410'
 '549'        | '1%'      | '1/16W'  | '0402LF'  | 'CHIP'   | 'CS15492FB29'(!)        = 'End of Design' | 'Comp-Release Qty' | 'CS15492FB29'           | 'R0402'             | '(R0402-0201)'                 | '549'     | '1%'    | '1/16W'  | 'DISCRETE' | 'RES CHIP 549 1/16W +-1%(0402)'                    | 'CHIP0402 '    | ''          | ''            | '20150328'
 '549'        | '1%'      | '1/16W'  | '0402LF'  | 'EMPTY'  | 'CS15492FB29'(!)        = 'End of Design' | 'Comp-Release Qty' | 'CS15492FB29'           | 'R0402'             | '(R0402-0201)'                 | '549'     | '1%'    | '1/16W'  | 'IO'       | 'RES CHIP 549 1/16W +-1%(0402)'                    | 'CHIP0402 '    | ''          | ''            | '20150328'
 '100'        | '1%'      | '2W'     | '2512LF'  | 'CHIP'   | 'CS1100AFR00'(!)        = ''              | ''                 | 'CS1100AFR00'           | 'R2512'             | '(SMR2512AW)'                  | '100'     | '1%'    | '2W'     | 'DISCRETE' | 'RES CHIP 100 2W +-1%(2512)'                       | 'CHIP2512 '    | ''          | ''            | '20150511'
 '100'        | '1%'      | '2W'     | '2512LF'  | 'EMPTY'  | 'CS1100AFR00'(!)        = ''              | ''                 | 'CS1100AFR00'           | 'R2512'             | '(SMR2512AW)'                  | '100'     | '1%'    | '2W'     | 'IO'       | 'RES CHIP 100 2W +-1%(2512)'                       | 'CHIP2512 '    | ''          | ''            | '20150511'
 '10K'        | '1%'      | '1/20W'  | '0201LF'  | 'CHIP'   | 'CS31001FE14'(!)        = ''              | ''                 | 'CS31001FE14'           | 'R0201'             | '(SMR0201AW)'                  | '10K'     | '1%'    | '1/20W'  | 'DISCRETE' | 'RES CHIP 10K(1/20W,+-1%,0201)'                    | 'CHIP0201'     | ''          | ''            | '20150511'
 '10K'        | '1%'      | '1/20W'  | '0201LF'  | 'EMPTY'  | 'CS31001FE14'(!)        = ''              | ''                 | 'CS31001FE14'           | 'R0201'             | '(SMR0201AW)'                  | '10K'     | '1%'    | '1/20W'  | 'IO'       | 'RES CHIP 10K(1/20W,+-1%,0201)'                    | 'CHIP0201'     | ''          | ''            | '20150511'
 '0.005'      | '1%'      | '1/4W'   | '0603LF'  | 'CHIP'   | 'CS+0056F900'(!)        = 'End of Design' | 'Comp-Approve'     | 'CS+0056F900'           | 'R0603_H38'         | '(SMR0603AW)'                  | '0.005'   | '1%'    | '1/4W'   | 'DISCRETE' | 'RES CHIP 0.005 1/4W +-1%(0603)'                   | 'CHIP0603'     | ''          | ''            | '20150518'
 '0.005'      | '1%'      | '1/4W'   | '0603LF'  | 'EMPTY'  | 'CS+0056F900'(!)        = 'End of Design' | 'Comp-Approve'     | 'CS+0056F900'           | 'R0603_H38'         | '(SMR0603AW)'                  | '0.005'   | '1%'    | '1/4W'   | 'IO'       | 'RES CHIP 0.005 1/4W +-1%(0603)'                   | 'CHIP0603'     | ''          | ''            | '20150518'
 '69.8'       | '1%'      | '1/16W'  | '0402LF'  | 'CHIP'   | 'CS06982FB00'(!)        = 'End of Design' | 'Comp-Approve'     | 'CS06982FB00'           | 'R0402'             | '(R0402-0201)'                 | '69.8'    | '1%'    | '1/16W'  | 'DISCRETE' | 'RES CHIP 69.8 1/16W +-1% (0402)'                  | 'CHIP0402 '    | ''          | ''            | '20150522'
 '69.8'       | '1%'      | '1/16W'  | '0402LF'  | 'EMPTY'  | 'CS06982FB00'(!)        = 'End of Design' | 'Comp-Approve'     | 'CS06982FB00'           | 'R0402'             | '(R0402-0201)'                 | '69.8'    | '1%'    | '1/16W'  | 'IO'       | 'RES CHIP 69.8 1/16W +-1% (0402)'                  | 'CHIP0402 '    | ''          | ''            | '20150522'
 '5.6'        | '1%'      | '1/10W'  | '0603LF'  | 'CHIP'   | 'CS-5603F914'(!)        = 'End of Design' | 'Comp-Approve'     | 'CS-5603F914'           | 'R0603'             | '(SMR0603AW)'                  | '5.6'     | '1%'    | '1/10W'  | 'DISCRETE' | 'RES CHIP 5.6 1/10W +-1%(0603)'                    | 'CHIP0603'     | ''          | ''            | '20150610'
 '5.6'        | '1%'      | '1/10W'  | '0603LF'  | 'EMPTY'  | 'CS-5603F914'(!)        = 'End of Design' | 'Comp-Approve'     | 'CS-5603F914'           | 'R0603'             | '(SMR0603AW)'                  | '5.6'     | '1%'    | '1/10W'  | 'IO'       | 'RES CHIP 5.6 1/10W +-1%(0603)'                    | 'CHIP0603'     | ''          | ''            | '20150610'
 '49.9'       | '0.1%'    | '1/16W'  | '0402LF'  | 'CHIP'   | 'CS04992BB01'(!)        = ''              | ''                 | 'CS04992BB01'           | 'R0402'             | '(R0402-0201)'                 | '49.9'    | '0.1%'  | '1/16W'  | 'DISCRETE' | 'RES CHIP 49.9 1/16W +-0.1%(0402)'                 | 'CHIP0402'     | ''          | ''            | '20150611'
 '49.9'       | '0.1%'    | '1/16W'  | '0402LF'  | 'EMPTY'  | 'CS04992BB01'(!)        = ''              | ''                 | 'CS04992BB01'           | 'R0402'             | '(R0402-0201)'                 | '49.9'    | '0.1%'  | '1/16W'  | 'IO'       | 'RES CHIP 49.9 1/16W +-0.1%(0402)'                 | 'CHIP0402'     | ''          | ''            | '20150611'
 '59'         | '1%'      | '1/16W'  | '0402LF'  | 'CHIP'   | 'CS05902FB00'(!)        = 'End of Design' | 'Comp-Approve'     | 'CS05902FB00'           | 'R0402'             | '(R0402-0201)'                 | '59'      | '1%'    | '1/16W'  | 'DISCRETE' | 'RES CHIP 59 1/16W +-1%(0402)'                     | 'CHIP0402'     | ''          | ''            | '20150611'
 '59'         | '1%'      | '1/16W'  | '0402LF'  | 'EMPTY'  | 'CS05902FB00'(!)        = 'End of Design' | 'Comp-Approve'     | 'CS05902FB00'           | 'R0402'             | '(R0402-0201)'                 | '59'      | '1%'    | '1/16W'  | 'IO'       | 'RES CHIP 59 1/16W +-1%(0402)'                     | 'CHIP0402'     | ''          | ''            | '20150611'
 '475K'       | '1%'      | '1/16W'  | '0402LF'  | 'CHIP'   | 'CS44755FB04'(!)        = ''              | ''                 | 'CS44755FB04'           | 'R0402'             | '(R0402-0201)'                 | '475K'    | '1%'    | '1/16W'  | 'DISCRETE' | 'RES CHIP 475K 1/16W +-1%(0402)'                   | 'CHIP0402'     | ''          | ''            | '20150612'
 '475K'       | '1%'      | '1/16W'  | '0402LF'  | 'EMPTY'  | 'CS44755FB04'(!)        = ''              | ''                 | 'CS44755FB04'           | 'R0402'             | '(R0402-0201)'                 | '475K'    | '1%'    | '1/16W'  | 'IO'       | 'RES CHIP 475K 1/16W +-1%(0402)'                   | 'CHIP0402'     | ''          | ''            | '20150612'
 '127K'       | '1%'      | '1/16W'  | '0402LF'  | 'CHIP'   | 'CS41272FB19'(!)        = 'End of Design' | 'Comp-Approve'     | 'CS41272FB19'           | 'R0402'             | '(R0402-0201)'                 | '127K'    | '1%'    | '1/16W'  | 'DISCRETE' | 'RES CHIP 127K 1/16W +-1%(0402)'                   | 'CHIP0402'     | ''          | ''            | '20150615'
 '127K'       | '1%'      | '1/16W'  | '0402LF'  | 'EMPTY'  | 'CS41272FB19'(!)        = 'End of Design' | 'Comp-Approve'     | 'CS41272FB19'           | 'R0402'             | '(R0402-0201)'                 | '127K'    | '1%'    | '1/16W'  | 'IO'       | 'RES CHIP 127K 1/16W +-1%(0402)'                   | 'CHIP0402'     | ''          | ''            | '20150615'
 '15.8K'      | '1%'      | '1/16W'  | '0402LF'  | 'CHIP'   | 'CS31582FB12'(!)        = 'End of Design' | 'Comp-Approve'     | 'CS31582FB12'           | 'R0402'             | '(R0402-0201)'                 | '15.8K'   | '1%'    | '1/16W'  | 'DISCRETE' | 'RES CHIP 15.8K 1/16W +-1% (0402)'                 | 'CHIP0402'     | ''          | ''            | '20150615'
 '15.8K'      | '1%'      | '1/16W'  | '0402LF'  | 'EMPTY'  | 'CS31582FB12'(!)        = 'End of Design' | 'Comp-Approve'     | 'CS31582FB12'           | 'R0402'             | '(R0402-0201)'                 | '15.8K'   | '1%'    | '1/16W'  | 'IO'       | 'RES CHIP 15.8K 1/16W +-1% (0402)'                 | 'CHIP0402'     | ''          | ''            | '20150615'
 '100K'       | '0.1%'    | '1/16W'  | '0402LF'  | 'CHIP'   | 'CS41002BB06'(!)        = ''              | ''                 | 'CS41002BB06'           | 'R0402'             | '(R0402-0201)'                 | '100K'    | '0.1%'  | '1/16W'  | 'DISCRETE' | 'RES CHIP 100K 1/16W +-0.1%(0402)'                 | 'CHIP0402'     | ''          | ''            | '20150623'
 '100K'       | '0.1%'    | '1/16W'  | '0402LF'  | 'EMPTY'  | 'CS41002BB06'(!)        = ''              | ''                 | 'CS41002BB06'           | 'R0402'             | '(R0402-0201)'                 | '100K'    | '0.1%'  | '1/16W'  | 'IO'       | 'RES CHIP 100K 1/16W +-0.1%(0402)'                 | 'CHIP0402'     | ''          | ''            | '20150623'
 '133K'       | '0.1%'    | '1/16W'  | '0402LF'  | 'CHIP'   | 'CS41332BB00'(!)        = ''              | ''                 | 'CS41332BB00'           | 'R0402'             | '(R0402-0201)'                 | '133K'    | '0.1%'  | '1/16W'  | 'DISCRETE' | 'RES CHIP 133K 1/16W +-0.1%(0402)'                 | 'CHIP0402'     | ''          | ''            | '20150623'
 '133K'       | '0.1%'    | '1/16W'  | '0402LF'  | 'EMPTY'  | 'CS41332BB00'(!)        = ''              | ''                 | 'CS41332BB00'           | 'R0402'             | '(R0402-0201)'                 | '133K'    | '0.1%'  | '1/16W'  | 'IO'       | 'RES CHIP 133K 1/16W +-0.1%(0402)'                 | 'CHIP0402'     | ''          | ''            | '20150623'
 '5.9K'       | '0.1%'    | '1/16W'  | '0402LF'  | 'CHIP'   | 'CS25902BB00'(!)        = ''              | ''                 | 'CS25902BB00'           | 'R0402'             | '(R0402-0201)'                 | '5.9K'    | '0.1%'  | '1/16W'  | 'DISCRETE' | 'RES CHIP 5.9K 1/16W +-0.1% (0402)'                | 'CHIP0402'     | ''          | ''            | '20150624'
 '5.9K'       | '0.1%'    | '1/16W'  | '0402LF'  | 'EMPTY'  | 'CS25902BB00'(!)        = ''              | ''                 | 'CS25902BB00'           | 'R0402'             | '(R0402-0201)'                 | '5.9K'    | '0.1%'  | '1/16W'  | 'IO'       | 'RES CHIP 5.9K 1/16W +-0.1% (0402)'                | 'CHIP0402'     | ''          | ''            | '20150624'
 '118K'       | '0.1%'    | '1/16W'  | '0402LF'  | 'CHIP'   | 'CS41182BB00'(!)        = ''              | ''                 | 'CS41182BB00'           | 'R0402'             | '(R0402-0201)'                 | '118K'    | '0.1%'  | '1/16W'  | 'DISCRETE' | 'RES CHIP 118K 1/16W +-0.1% (0402)'                | 'CHIP0402'     | ''          | ''            | '20150624'
 '118K'       | '0.1%'    | '1/16W'  | '0402LF'  | 'EMPTY'  | 'CS41182BB00'(!)        = ''              | ''                 | 'CS41182BB00'           | 'R0402'             | '(R0402-0201)'                 | '118K'    | '0.1%'  | '1/16W'  | 'IO'       | 'RES CHIP 118K 1/16W +-0.1% (0402)'                | 'CHIP0402'     | ''          | ''            | '20150624'
 '16.9K'      | '0.1%'    | '1/16W'  | '0402LF'  | 'CHIP'   | 'CS31692BB00'(!)        = ''              | ''                 | 'CS31692BB00'           | 'R0402'             | '(R0402-0201)'                 | '16.9K'   | '0.1%'  | '1/16W'  | 'DISCRETE' | 'RES CHIP 16.9K 1/16W +-0.1%(0402)'                | 'CHIP0402'     | ''          | ''            | '20150702'
 '16.9K'      | '0.1%'    | '1/16W'  | '0402LF'  | 'EMPTY'  | 'CS31692BB00'(!)        = ''              | ''                 | 'CS31692BB00'           | 'R0402'             | '(R0402-0201)'                 | '16.9K'   | '0.1%'  | '1/16W'  | 'IO'       | 'RES CHIP 16.9K 1/16W +-0.1%(0402)'                | 'CHIP0402'     | ''          | ''            | '20150702'
 '7.87K'      | '1%'      | '1/16W'  | '0402LF'  | 'CHIP'   | 'CS27872FB13'(!)        = 'End of Design' | 'Comp-Approve'     | 'CS27872FB13'           | 'R0402'             | '(R0402-0201)'                 | '7.87K'   | '1%'    | '1/16W'  | 'DISCRETE' | 'RES CHIP 7.87K 1/16W +-1%(0402)'                  | 'CHIP0402'     | ''          | ''            | '20150720'
 '7.87K'      | '1%'      | '1/16W'  | '0402LF'  | 'EMPTY'  | 'CS27872FB13'(!)        = 'End of Design' | 'Comp-Approve'     | 'CS27872FB13'           | 'R0402'             | '(R0402-0201)'                 | '7.87K'   | '1%'    | '1/16W'  | 'IO'       | 'RES CHIP 7.87K 1/16W +-1%(0402)'                  | 'CHIP0402'     | ''          | ''            | '20150720'
 '158K'       | '1%'      | '1/16W'  | '0402LF'  | 'CHIP'   | 'CS41582FB14'(!)        = 'End of Design' | 'Comp-Approve'     | 'CS41582FB14'           | 'R0402'             | '(R0402-0201)'                 | '158K'    | '1%'    | '1/16W'  | 'DISCRETE' | 'RES CHIP 158K 1/16W +-1% (0402)'                  | 'CHIP0402'     | ''          | ''            | '20150728'
 '158K'       | '1%'      | '1/16W'  | '0402LF'  | 'EMPTY'  | 'CS41582FB14'(!)        = 'End of Design' | 'Comp-Approve'     | 'CS41582FB14'           | 'R0402'             | '(R0402-0201)'                 | '158K'    | '1%'    | '1/16W'  | 'IO'       | 'RES CHIP 158K 1/16W +-1% (0402)'                  | 'CHIP0402'     | ''          | ''            | '20150728'
 '15K'        | '1%'      | '1/10W'  | '0603LF'  | 'CHIP'   | 'CS31503F939'(!)        = ''              | ''                 | 'CS31503F939'           | 'R0603'             | '(SMR0603AW)'                  | '15K'     | '1%'    | '1/10W'  | 'DISCRETE' | 'RESISTOR CHIP 15K 1/10W+-1%(0603)'                | 'CHIP0603'     | ''          | ''            | '20150728'
 '15K'        | '1%'      | '1/10W'  | '0603LF'  | 'EMPTY'  | 'CS31503F939'(!)        = ''              | ''                 | 'CS31503F939'           | 'R0603'             | '(SMR0603AW)'                  | '15K'     | '1%'    | '1/10W'  | 'IO'       | 'RESISTOR CHIP 15K 1/10W+-1%(0603)'                | 'CHIP0603'     | ''          | ''            | '20150728'
 '2.26M'      | '1%'      | '1/8W'   | '0805LF'  | 'CHIP'   | 'CS52264FA00'(!)        = ''              | ''                 | 'CS52264FA00'           | 'R0805'             | '(SMR0805AW)'                  | '2.26M'   | '1%'    | '1/8W'   | 'DISCRETE' | 'RES CHIP 2.26M 1/8W +-1% (0805)'                  | 'CHIP0805'     | ''          | ''            | '20150803'
 '2.26M'      | '1%'      | '1/8W'   | '0805LF'  | 'EMPTY'  | 'CS52264FA00'(!)        = ''              | ''                 | 'CS52264FA00'           | 'R0805'             | '(SMR0805AW)'                  | '2.26M'   | '1%'    | '1/8W'   | 'IO'       | 'RES CHIP 2.26M 1/8W +-1% (0805)'                  | 'CHIP0805'     | ''          | ''            | '20150803'
 '20K'        | '1%'      | '1/8W'   | '0805LF'  | 'CHIP'   | 'CS32004FA00'(!)        = ''              | ''                 | 'CS32004FA00'           | 'R0805'             | '(SMR0805AW)'                  | '20K'     | '1%'    | '1/8W'   | 'DISCRETE' | 'RES CHIP 20K 1/8W +-1%(0805)'                     | 'CHIP0805'     | ''          | ''            | '20150803'
 '20K'        | '1%'      | '1/8W'   | '0805LF'  | 'EMPTY'  | 'CS32004FA00'(!)        = ''              | ''                 | 'CS32004FA00'           | 'R0805'             | '(SMR0805AW)'                  | '20K'     | '1%'    | '1/8W'   | 'IO'       | 'RES CHIP 20K 1/8W +-1%(0805)'                     | 'CHIP0805'     | ''          | ''            | '20150803'
 '4.99K'      | '0.1%'    | '1/16W'  | '0402LF'  | 'CHIP'   | 'CS24992BB00'(!)        = ''              | ''                 | 'CS24992BB00'           | 'R0402'             | '(R0402-0201)'                 | '4.99K'   | '0.1%'  | '1/16W'  | 'DISCRETE' | 'RES CHIP 4.99K 1/16W +-0.1%(0402)'                | 'CHIP0402'     | ''          | ''            | '20150805'
 '4.99K'      | '0.1%'    | '1/16W'  | '0402LF'  | 'EMPTY'  | 'CS24992BB00'(!)        = ''              | ''                 | 'CS24992BB00'           | 'R0402'             | '(R0402-0201)'                 | '4.99K'   | '0.1%'  | '1/16W'  | 'IO'       | 'RES CHIP 4.99K 1/16W +-0.1%(0402)'                | 'CHIP0402'     | ''          | ''            | '20150805'
 '30K'        | '0.1%'    | '1/16W'  | '0402LF'  | 'CHIP'   | 'CS33002BB00'(!)        = ''              | ''                 | 'CS33002BB00'           | 'R0402'             | '(R0402-0201)'                 | '30K'     | '0.1%'  | '1/16W'  | 'DISCRETE' | 'RES CHIP 30K 1/16W +-0.1%(0402)HF'                | 'CHIP0402'     | ''          | ''            | '20150805'
 '30K'        | '0.1%'    | '1/16W'  | '0402LF'  | 'EMPTY'  | 'CS33002BB00'(!)        = ''              | ''                 | 'CS33002BB00'           | 'R0402'             | '(R0402-0201)'                 | '30K'     | '0.1%'  | '1/16W'  | 'IO'       | 'RES CHIP 30K 1/16W +-0.1%(0402)HF'                | 'CHIP0402'     | ''          | ''            | '20150805'
 '24K'        | '0.1%'    | '1/16W'  | '0402LF'  | 'CHIP'   | 'CS32402BB00'(!)        = ''              | ''                 | 'CS32402BB00'           | 'R0402'             | '(R0402-0201)'                 | '24K'     | '0.1%'  | '1/16W'  | 'DISCRETE' | 'RES CHIP 24K 1/16W +-0.1% (0402)'                 | 'CHIP0402'     | ''          | ''            | '20150805'
 '24K'        | '0.1%'    | '1/16W'  | '0402LF'  | 'EMPTY'  | 'CS32402BB00'(!)        = ''              | ''                 | 'CS32402BB00'           | 'R0402'             | '(R0402-0201)'                 | '24K'     | '0.1%'  | '1/16W'  | 'IO'       | 'RES CHIP 24K 1/16W +-0.1% (0402)'                 | 'CHIP0402'     | ''          | ''            | '20150805'
 '29.4K'      | '0.1%'    | '1/16W'  | '0402LF'  | 'CHIP'   | 'CS32942BB00'(!)        = ''              | ''                 | 'CS32942BB00'           | 'R0402'             | '(R0402-0201)'                 | '29.4K'   | '0.1%'  | '1/16W'  | 'DISCRETE' | 'RES CHIP 29.4K 1/16W +-0.1%(0402)'                | 'CHIP0402'     | ''          | ''            | '20150807'
 '29.4K'      | '0.1%'    | '1/16W'  | '0402LF'  | 'EMPTY'  | 'CS32942BB00'(!)        = ''              | ''                 | 'CS32942BB00'           | 'R0402'             | '(R0402-0201)'                 | '29.4K'   | '0.1%'  | '1/16W'  | 'IO'       | 'RES CHIP 29.4K 1/16W +-0.1%(0402)'                | 'CHIP0402'     | ''          | ''            | '20150807'
 '60.4K'      | '0.1%'    | '1/16W'  | '0402LF'  | 'CHIP'   | 'CS36042BB00'(!)        = ''              | ''                 | 'CS36042BB00'           | 'R0402'             | '(R0402-0201)'                 | '60.4K'   | '0.1%'  | '1/16W'  | 'DISCRETE' | 'RES CHIP 60.4K 1/16W +-0.1%(0402)'                | 'CHIP0402'     | ''          | ''            | '20150807'
 '60.4K'      | '0.1%'    | '1/16W'  | '0402LF'  | 'EMPTY'  | 'CS36042BB00'(!)        = ''              | ''                 | 'CS36042BB00'           | 'R0402'             | '(R0402-0201)'                 | '60.4K'   | '0.1%'  | '1/16W'  | 'IO'       | 'RES CHIP 60.4K 1/16W +-0.1%(0402)'                | 'CHIP0402'     | ''          | ''            | '20150807'
 '51.1K'      | '1%'      | '1/16W'  | '0402LF'  | 'CHIP'   | 'CS35112FB17'(!)        = 'End of Design' | 'Comp-Approve'     | 'CS35112FB17'           | 'R0402'             | '(R0402-0201)'                 | '51.1K'   | '1%'    | '1/16W'  | 'DISCRETE' | 'RES CHIP 51.1K 1/16W +-1%(0402) L-F'              | 'CHIP0402'     | ''          | ''            | '20150810'
 '51.1K'      | '1%'      | '1/16W'  | '0402LF'  | 'EMPTY'  | 'CS35112FB17'(!)        = 'End of Design' | 'Comp-Approve'     | 'CS35112FB17'           | 'R0402'             | '(R0402-0201)'                 | '51.1K'   | '1%'    | '1/16W'  | 'IO'       | 'RES CHIP 51.1K 1/16W +-1%(0402) L-F'              | 'CHIP0402'     | ''          | ''            | '20150810'
 '475K'       | '1%'      | '1/16W'  | '0402LF'  | 'CHIP'   | 'CS44752FB08'(!)        = 'End of Design' | 'Comp-Approve'     | 'CS44752FB08'           | 'R0402'             | '(R0402-0201)'                 | '475K'    | '1%'    | '1/16W'  | 'DISCRETE' | 'RES CHIP 475K 1/16W +-1%(0402)'                   | 'CHIP0402'     | ''          | ''            | '20150819'
 '475K'       | '1%'      | '1/16W'  | '0402LF'  | 'EMPTY'  | 'CS44752FB08'(!)        = 'End of Design' | 'Comp-Approve'     | 'CS44752FB08'           | 'R0402'             | '(R0402-0201)'                 | '475K'    | '1%'    | '1/16W'  | 'IO'       | 'RES CHIP 475K 1/16W +-1%(0402)'                   | 'CHIP0402'     | ''          | ''            | '20150819'
 '6.49K'      | '0.1%'    | '1/16W'  | '0402LF'  | 'CHIP'   | 'CS26492BB00'(!)        = ''              | ''                 | 'CS26492BB00'           | 'R0402'             | '(R0402-0201)'                 | '6.49K'   | '0.1%'  | '1/16W'  | 'DISCRETE' | 'RES CHIP 6.49K 1/16W +-0.1%(0402)'                | 'CHIP0402'     | ''          | ''            | '20150828'
 '6.49K'      | '0.1%'    | '1/16W'  | '0402LF'  | 'EMPTY'  | 'CS26492BB00'(!)        = ''              | ''                 | 'CS26492BB00'           | 'R0402'             | '(R0402-0201)'                 | '6.49K'   | '0.1%'  | '1/16W'  | 'IO'       | 'RES CHIP 6.49K 1/16W +-0.1%(0402)'                | 'CHIP0402'     | ''          | ''            | '20150828'
 '6.2K'       | '5%'      | '1/16W'  | '0402LF'  | 'CHIP'   | 'CS26202JB19'(!)        = 'End of Design' | 'Comp-Approve'     | 'CS26202JB19'           | 'R0402'             | '(R0402-0201)'                 | '6.2K'    | '5%'    | '1/16W'  | 'DISCRETE' | 'RES CHIP 6.2K 1/16W+-5%(0402)'                    | 'CHIP0402'     | ''          | ''            | '20150910'
 '6.2K'       | '5%'      | '1/16W'  | '0402LF'  | 'EMPTY'  | 'CS26202JB19'(!)        = 'End of Design' | 'Comp-Approve'     | 'CS26202JB19'           | 'R0402'             | '(R0402-0201)'                 | '6.2K'    | '5%'    | '1/16W'  | 'IO'       | 'RES CHIP 6.2K 1/16W+-5%(0402)'                    | 'CHIP0402'     | ''          | ''            | '20150910'
 '85.5K'      | '1%'      | '1/16W'  | '0402LF'  | 'CHIP'   | 'CS38552FB00'(!)        = ''              | ''                 | 'CS38552FB00'           | 'R0402'             | '(R0402-0201)'                 | '85.5K'   | '1%'    | '1/16W'  | 'DISCRETE' | 'RES CHIP 85.5K 1/16W +-1%(0402)'                  | 'CHIP0402'     | ''          | ''            | '20150915'
 '85.5K'      | '1%'      | '1/16W'  | '0402LF'  | 'EMPTY'  | 'CS38552FB00'(!)        = ''              | ''                 | 'CS38552FB00'           | 'R0402'             | '(R0402-0201)'                 | '85.5K'   | '1%'    | '1/16W'  | 'IO'       | 'RES CHIP 85.5K 1/16W +-1%(0402)'                  | 'CHIP0402'     | ''          | ''            | '20150915'
 '1.96K'      | '1%'      | '1/16W'  | '0402LF'  | 'CHIP'   | 'CS21962FB08'(!)        = 'End of Design' | 'Comp-Approve'     | 'CS21962FB08'           | 'R0402'             | '(R0402-0201)'                 | '1.96K'   | '1%'    | '1/16W'  | 'DISCRETE' | 'RES CHIP 1.96K 1/16W +-1%(0402)'                  | 'CHIP0402'     | ''          | ''            | '20151014'
 '1.96K'      | '1%'      | '1/16W'  | '0402LF'  | 'EMPTY'  | 'CS21962FB08'(!)        = 'End of Design' | 'Comp-Approve'     | 'CS21962FB08'           | 'R0402'             | '(R0402-0201)'                 | '1.96K'   | '1%'    | '1/16W'  | 'IO'       | 'RES CHIP 1.96K 1/16W +-1%(0402)'                  | 'CHIP0402'     | ''          | ''            | '20151014'
 '39'         | '1%'      | '1/16W'  | '0402LF'  | 'CHIP'   | 'CS03902FB11'(!)        = 'End of Design' | 'Comp-Approve'     | 'CS03902FB11'           | 'R0402'             | '(R0402-0201)'                 | '39'      | '1%'    | '1/16W'  | 'DISCRETE' | 'RES CHIP 39 1/16W +-1%(0402)'                     | 'CHIP0402'     | ''          | ''            | '20151020'
 '39'         | '1%'      | '1/16W'  | '0402LF'  | 'EMPTY'  | 'CS03902FB11'(!)        = 'End of Design' | 'Comp-Approve'     | 'CS03902FB11'           | 'R0402'             | '(R0402-0201)'                 | '39'      | '1%'    | '1/16W'  | 'IO'       | 'RES CHIP 39 1/16W +-1%(0402)'                     | 'CHIP0402'     | ''          | ''            | '20151020'
 '4.3K'       | '1%'      | '1/16W'  | '0402LF'  | 'CHIP'   | 'CS24302FB07'(!)        = 'End of Design' | 'Comp-Approve'     | 'CS24302FB07'           | 'R0402'             | '(R0402-0201)'                 | '4.3K'    | '1%'    | '1/16W'  | 'DISCRETE' | 'RES CHIP 4.3K 1/16W +-1%(0402)'                   | 'CHIP0402'     | ''          | ''            | '20151120'
 '4.3K'       | '1%'      | '1/16W'  | '0402LF'  | 'EMPTY'  | 'CS24302FB07'(!)        = 'End of Design' | 'Comp-Approve'     | 'CS24302FB07'           | 'R0402'             | '(R0402-0201)'                 | '4.3K'    | '1%'    | '1/16W'  | 'IO'       | 'RES CHIP 4.3K 1/16W +-1%(0402)'                   | 'CHIP0402'     | ''          | ''            | '20151120'
 '20K'        | '0.1%'    | '1/16W'  | '0402LF'  | 'CHIP'   | 'CS32002BB00'(!)        = ''              | ''                 | 'CS32002BB00'           | 'R0402'             | '(R0402-0201)'                 | '20K'     | '0.1%'  | '1/16W'  | 'DISCRETE' | 'RES CHIP 20K 1/16W +-0.1%(0402)'                  | 'CHIP0402'     | ''          | ''            | '20151203'
 '20K'        | '0.1%'    | '1/16W'  | '0402LF'  | 'EMPTY'  | 'CS32002BB00'(!)        = ''              | ''                 | 'CS32002BB00'           | 'R0402'             | '(R0402-0201)'                 | '20K'     | '0.1%'  | '1/16W'  | 'IO'       | 'RES CHIP 20K 1/16W +-0.1%(0402)'                  | 'CHIP0402'     | ''          | ''            | '20151203'
 '1.69M'      | '1%'      | '1/16W'  | '0402LF'  | 'CHIP'   | 'CS51692FB06'(!)        = ''              | ''                 | 'CS51692FB06'           | 'R0402'             | '(R0402-0201)'                 | '1.69M'   | '1%'    | '1/16W'  | 'DISCRETE' | 'RES CHIP 1.69M.1/16W +-1%(0402)EP'                | 'CHIP0402'     | ''          | ''            | '20151207'
 '1.69M'      | '1%'      | '1/16W'  | '0402LF'  | 'EMPTY'  | 'CS51692FB06'(!)        = ''              | ''                 | 'CS51692FB06'           | 'R0402'             | '(R0402-0201)'                 | '1.69M'   | '1%'    | '1/16W'  | 'IO'       | 'RES CHIP 1.69M.1/16W +-1%(0402)EP'                | 'CHIP0402'     | ''          | ''            | '20151207'
 '681K'       | '1%'      | '1/16W'  | '0402LF'  | 'CHIP'   | 'CS46812FB00'(!)        = 'End of Design' | 'Comp-Approve'     | 'CS46812FB00'           | 'R0402'             | '(R0402-0201)'                 | '681K'    | '1%'    | '1/16W'  | 'DISCRETE' | 'RES CHIP 681K 1/16W +-1%(0402)'                   | 'CHIP0402'     | ''          | ''            | '20151208'
 '681K'       | '1%'      | '1/16W'  | '0402LF'  | 'EMPTY'  | 'CS46812FB00'(!)        = 'End of Design' | 'Comp-Approve'     | 'CS46812FB00'           | 'R0402'             | '(R0402-0201)'                 | '681K'    | '1%'    | '1/16W'  | 'IO'       | 'RES CHIP 681K 1/16W +-1%(0402)'                   | 'CHIP0402'     | ''          | ''            | '20151208'
 '1.07K'      | '0.1%'    | '1/16W'  | '0402LF'  | 'CHIP'   | 'CS21072BB00'(!)        = ''              | ''                 | 'CS21072BB00'           | 'R0402'             | '(R0402-0201)'                 | '1.07K'   | '0.1%'  | '1/16W'  | 'DISCRETE' | 'RES CHIP 1.07K 1/16W +-0.1% (0402)'               | 'CHIP0402'     | ''          | ''            | '20151208'
 '1.07K'      | '0.1%'    | '1/16W'  | '0402LF'  | 'EMPTY'  | 'CS21072BB00'(!)        = ''              | ''                 | 'CS21072BB00'           | 'R0402'             | '(R0402-0201)'                 | '1.07K'   | '0.1%'  | '1/16W'  | 'IO'       | 'RES CHIP 1.07K 1/16W +-0.1% (0402)'               | 'CHIP0402'     | ''          | ''            | '20151208'
 '150'        | '5%'      | '1/16W'  | '0402LF'  | 'CHIP'   | 'TMP_QCS11502JB22'(!)   = 'End of Design' | 'Comp-Approve'     | 'CS11502JB22'           | 'R0402'             | '(R0402-0201)'                 | '150'     | '5%'    | '1/16W'  | 'DISCRETE' | 'RES CHIP 150 1/16W +-5%(0402)'                    | 'CHIP0402'     | ''          | ''            | '20151222'
 '150'        | '5%'      | '1/16W'  | '0402LF'  | 'EMPTY'  | 'TMP_QCS11502JB22'(!)   = 'End of Design' | 'Comp-Approve'     | 'CS11502JB22'           | 'R0402'             | '(R0402-0201)'                 | '150'     | '5%'    | '1/16W'  | 'IO'       | 'RES CHIP 150 1/16W +-5%(0402)'                    | 'CHIP0402'     | ''          | ''            | '20151222'
 '0'          | '5%'      | '1/20W'  | '0201LF'  | 'CHIP'   | 'CS00001JE18'(!)        = ''              | ''                 | 'CS00001JE18'           | 'R0201'             | '(SMR0201AW)'                  | '0'       | '5%'    | '1/20W'  | 'DISCRETE' | 'RES CHIP 0(1/20W,+-5%,0201)'                      | 'CHIP0201'     | ''          | ''            | '20151228'
 '0'          | '5%'      | '1/20W'  | '0201LF'  | 'EMPTY'  | 'CS00001JE18'(!)        = ''              | ''                 | 'CS00001JE18'           | 'R0201'             | '(SMR0201AW)'                  | '0'       | '5%'    | '1/20W'  | 'IO'       | 'RES CHIP 0(1/20W,+-5%,0201)'                      | 'CHIP0201'     | ''          | ''            | '20151228'
 '249K'       | '1%'      | '1/16W'  | '0402LF'  | 'CHIP'   | 'CS42492FB18'(!)        = 'End of Design' | 'Comp-Approve'     | 'CS42492FB18'           | 'R0402'             | '(R0402-0201)'                 | '249K'    | '1%'    | '1/16W'  | 'DISCRETE' | 'RES CHIP 249K 1/16W +-1%(0402)EP'                 | 'CHIP0402'     | ''          | ''            | '20151228'
 '249K'       | '1%'      | '1/16W'  | '0402LF'  | 'EMPTY'  | 'CS42492FB18'(!)        = 'End of Design' | 'Comp-Approve'     | 'CS42492FB18'           | 'R0402'             | '(R0402-0201)'                 | '249K'    | '1%'    | '1/16W'  | 'IO'       | 'RES CHIP 249K 1/16W +-1%(0402)EP'                 | 'CHIP0402'     | ''          | ''            | '20151228'
 '0.001'      | '1%'      | '1W'     | '2512LF'  | 'CHIP'   | 'CS+0018FR03'(!)        = ''              | ''                 | 'CS+0018FR03'           | 'R2512A'            | '(SMR2512AW)'                  | '0.001'   | '1%'    | '1W'     | 'DISCRETE' | 'RES CHIP 0.001 1W +-1%(2512)AEC'                  | 'CHIP2512'     | ''          | ''            | '20151229'
 '0.001'      | '1%'      | '1W'     | '2512LF'  | 'EMPTY'  | 'CS+0018FR03'(!)        = ''              | ''                 | 'CS+0018FR03'           | 'R2512A'            | '(SMR2512AW)'                  | '0.001'   | '1%'    | '1W'     | 'IO'       | 'RES CHIP 0.001 1W +-1%(2512)AEC'                  | 'CHIP2512'     | ''          | ''            | '20151229'
 '0.0005'     | '1%'      | '1W'     | '2512LF'  | 'CHIP'   | 'CS00008FR03'(!)        = ''              | ''                 | 'CS00008FR03'           | 'R2512A'            | '(SMR2512AW)'                  | '0.0005'  | '1%'    | '1W'     | 'DISCRETE' | 'RES CHIP 0.0005 1W +-1%(2512)AEC'                 | 'CHIP2512'     | ''          | ''            | '20160105'
 '0.0005'     | '1%'      | '1W'     | '2512LF'  | 'EMPTY'  | 'CS00008FR03'(!)        = ''              | ''                 | 'CS00008FR03'           | 'R2512A'            | '(SMR2512AW)'                  | '0.0005'  | '1%'    | '1W'     | 'IO'       | 'RES CHIP 0.0005 1W +-1%(2512)AEC'                 | 'CHIP2512'     | ''          | ''            | '20160105'
 '41.2K'      | '1%'      | '1/16W'  | '0402LF'  | 'CHIP'   | 'CS34122FB19'(!)        = ''              | ''                 | 'CS34122FB19'           | 'R0402'             | '(R0402-0201)'                 | '41.2K'   | '1%'    | '1/16W'  | 'DISCRETE' | 'RES CHIP 41.2K 1/16W +-1%(0402)'                  | 'CHIP0402'     | ''          | ''            | '20160112'
 '41.2K'      | '1%'      | '1/16W'  | '0402LF'  | 'EMPTY'  | 'CS34122FB19'(!)        = ''              | ''                 | 'CS34122FB19'           | 'R0402'             | '(R0402-0201)'                 | '41.2K'   | '1%'    | '1/16W'  | 'IO'       | 'RES CHIP 41.2K 1/16W +-1%(0402)'                  | 'CHIP0402'     | ''          | ''            | '20160112'
 '15'         | '1%'      | '1/20W'  | '0201LF'  | 'CHIP'   | 'CS01501FE01'(!)        = ''              | 'End of Life'      | 'CS01501FE01'           | 'R0201_EOL'         | '(SMR0201AW)'                  | '15'      | '1%'    | '1/20W'  | 'DISCRETE' | 'RES CHIP 15 1/20W +-1%(0201)'                     | 'CHIP0201'     | ''          | ''            | '20160112'
 '15'         | '1%'      | '1/20W'  | '0201LF'  | 'EMPTY'  | 'CS01501FE01'(!)        = ''              | 'End of Life'      | 'CS01501FE01'           | 'R0201_EOL'         | '(SMR0201AW)'                  | '15'      | '1%'    | '1/20W'  | 'IO'       | 'RES CHIP 15 1/20W +-1%(0201)'                     | 'CHIP0201'     | ''          | ''            | '20160112'
 '1.54M'      | '1%'      | '1/8W'   | '0805LF'  | 'CHIP'   | 'CS51544FA00'(!)        = ''              | ''                 | 'CS51544FA00'           | 'R0805'             | '(SMR0805AW)'                  | '1.54M'   | '1%'    | '1/8W'   | 'DISCRETE' | 'RES CHIP 1.54M 1/8W +-1% (0805)'                  | 'CHIP0805'     | ''          | ''            | '20160112'
 '1.54M'      | '1%'      | '1/8W'   | '0805LF'  | 'EMPTY'  | 'CS51544FA00'(!)        = ''              | ''                 | 'CS51544FA00'           | 'R0805'             | '(SMR0805AW)'                  | '1.54M'   | '1%'    | '1/8W'   | 'IO'       | 'RES CHIP 1.54M 1/8W +-1% (0805)'                  | 'CHIP0805'     | ''          | ''            | '20160112'
 '147K'       | '1%'      | '1/16W'  | '0402LF'  | 'CHIP'   | 'CS41472FB04'(!)        = ''              | ''                 | 'CS41472FB04'           | 'R0402'             | '(R0402-0201)'                 | '147K'    | '1%'    | '1/16W'  | 'DISCRETE' | 'RES CHIP 147K 1/16W +-1%(0402)AEC'                | 'CHIP0402'     | ''          | ''            | '20160111'
 '147K'       | '1%'      | '1/16W'  | '0402LF'  | 'EMPTY'  | 'CS41472FB04'(!)        = ''              | ''                 | 'CS41472FB04'           | 'R0402'             | '(R0402-0201)'                 | '147K'    | '1%'    | '1/16W'  | 'IO'       | 'RES CHIP 147K 1/16W +-1%(0402)AEC'                | 'CHIP0402'     | ''          | ''            | '20160111'
 '0'          | '1%'      | '1/16W'  | '0402LF'  | 'CHIP'   | 'CS00002FB03'(!)        = ''              | ''                 | 'CS00002FB03'           | 'R0402'             | '(R0402_OCTAGONXA,R0402-0201)' | '0'       | '1%'    | '1/16W'  | 'DISCRETE' | 'RES CHIP 0 1/16W +-1%(0402)AEC'                   | 'CHIP0402'     | ''          | ''            | '20160111'
 '0'          | '1%'      | '1/16W'  | '0402LF'  | 'EMPTY'  | 'CS00002FB03'(!)        = ''              | ''                 | 'CS00002FB03'           | 'R0402'             | '(R0402_OCTAGONXA,R0402-0201)' | '0'       | '1%'    | '1/16W'  | 'IO'       | 'RES CHIP 0 1/16W +-1%(0402)AEC'                   | 'CHIP0402'     | ''          | ''            | '20160111'
 '0'          | '5%'      | '1/16W'  | '0402LF'  | 'CHIP'   | 'CS00002JB17'(!)        = ''              | ''                 | 'CS00002JB17'           | 'R0402'             | '(R0402-0201)'                 | '0'       | '5%'    | '1/16W'  | 'DISCRETE' | 'RES CHIP 0 1/16W +-5%(0402)AEC'                   | 'CHIP0402'     | ''          | ''            | '20160111'
 '0'          | '5%'      | '1/16W'  | '0402LF'  | 'EMPTY'  | 'CS00002JB17'(!)        = ''              | ''                 | 'CS00002JB17'           | 'R0402'             | '(R0402-0201)'                 | '0'       | '5%'    | '1/16W'  | 'IO'       | 'RES CHIP 0 1/16W +-5%(0402)AEC'                   | 'CHIP0402'     | ''          | ''            | '20160111'
 '1'          | '1%'      | '1/16W'  | '0402LF'  | 'CHIP'   | 'CS-1002FB09'(!)        = ''              | ''                 | 'CS-1002FB09'           | 'R0402'             | '(R0402-0201)'                 | '1'       | '1%'    | '1/16W'  | 'DISCRETE' | 'RES CHIP 1 1/16W +-1%(0402)AEC'                   | 'CHIP0402'     | ''          | ''            | '20160111'
 '1'          | '1%'      | '1/16W'  | '0402LF'  | 'EMPTY'  | 'CS-1002FB09'(!)        = ''              | ''                 | 'CS-1002FB09'           | 'R0402'             | '(R0402-0201)'                 | '1'       | '1%'    | '1/16W'  | 'IO'       | 'RES CHIP 1 1/16W +-1%(0402)AEC'                   | 'CHIP0402'     | ''          | ''            | '20160111'
 '1'          | '5%'      | '1/16W'  | '0402LF'  | 'CHIP'   | 'CS-1002JB06'(!)        = ''              | ''                 | 'CS-1002JB06'           | 'R0402'             | '(R0402-0201)'                 | '1'       | '5%'    | '1/16W'  | 'DISCRETE' | 'RES CHIP 1 1/16W +-5%(0402)AEC'                   | 'CHIP0402'     | ''          | ''            | '20160111'
 '1'          | '5%'      | '1/16W'  | '0402LF'  | 'EMPTY'  | 'CS-1002JB06'(!)        = ''              | ''                 | 'CS-1002JB06'           | 'R0402'             | '(R0402-0201)'                 | '1'       | '5%'    | '1/16W'  | 'IO'       | 'RES CHIP 1 1/16W +-5%(0402)AEC'                   | 'CHIP0402'     | ''          | ''            | '20160111'
 '1.8K'       | '1%'      | '1/16W'  | '0402LF'  | 'CHIP'   | 'CS21802FB03'(!)        = ''              | ''                 | 'CS21802FB03'           | 'R0402'             | '(R0402-0201)'                 | '1.8K'    | '1%'    | '1/16W'  | 'DISCRETE' | 'RES CHIP 1.8K 1/16W +-1%(0402)AEC'                | 'CHIP0402'     | ''          | ''            | '20160111'
 '1.8K'       | '1%'      | '1/16W'  | '0402LF'  | 'EMPTY'  | 'CS21802FB03'(!)        = ''              | ''                 | 'CS21802FB03'           | 'R0402'             | '(R0402-0201)'                 | '1.8K'    | '1%'    | '1/16W'  | 'IO'       | 'RES CHIP 1.8K 1/16W +-1%(0402)AEC'                | 'CHIP0402'     | ''          | ''            | '20160111'
 '10'         | '1%'      | '1/16W'  | '0402LF'  | 'CHIP'   | 'CS01002FB11'(!)        = ''              | ''                 | 'CS01002FB11'           | 'R0402'             | '(R0402-0201)'                 | '10'      | '1%'    | '1/16W'  | 'DISCRETE' | 'RES CHIP 10 1/16W +-1%(0402)AEC'                  | 'CHIP0402'     | ''          | ''            | '20160111'
 '10'         | '1%'      | '1/16W'  | '0402LF'  | 'EMPTY'  | 'CS01002FB11'(!)        = ''              | ''                 | 'CS01002FB11'           | 'R0402'             | '(R0402-0201)'                 | '10'      | '1%'    | '1/16W'  | 'IO'       | 'RES CHIP 10 1/16W +-1%(0402)AEC'                  | 'CHIP0402'     | ''          | ''            | '20160111'
 '100'        | '0.1%'    | '1/16W'  | '0402LF'  | 'CHIP'   | 'CS11002BB01'(!)        = ''              | ''                 | 'CS11002BB01'           | 'R0402'             | '(R0402-0201)'                 | '100'     | '0.1%'  | '1/16W'  | 'DISCRETE' | 'RES CHIP 100 1/16W +-0.1%(0402)AEC'               | 'CHIP0402'     | ''          | ''            | '20160111'
 '100'        | '0.1%'    | '1/16W'  | '0402LF'  | 'EMPTY'  | 'CS11002BB01'(!)        = ''              | ''                 | 'CS11002BB01'           | 'R0402'             | '(R0402-0201)'                 | '100'     | '0.1%'  | '1/16W'  | 'IO'       | 'RES CHIP 100 1/16W +-0.1%(0402)AEC'               | 'CHIP0402'     | ''          | ''            | '20160111'
 '100'        | '1%'      | '1/16W'  | '0402LF'  | 'CHIP'   | 'CS11002FB11'(!)        = ''              | ''                 | 'CS11002FB11'           | 'R0402'             | '(R0402-0201)'                 | '100'     | '1%'    | '1/16W'  | 'DISCRETE' | 'RES CHIP 100 1/16W +-1%(0402)AEC'                 | 'CHIP0402'     | ''          | ''            | '20160111'
 '100'        | '1%'      | '1/16W'  | '0402LF'  | 'EMPTY'  | 'CS11002FB11'(!)        = ''              | ''                 | 'CS11002FB11'           | 'R0402'             | '(R0402-0201)'                 | '100'     | '1%'    | '1/16W'  | 'IO'       | 'RES CHIP 100 1/16W +-1%(0402)AEC'                 | 'CHIP0402'     | ''          | ''            | '20160111'
 '100K'       | '0.1%'    | '1/16W'  | '0402LF'  | 'CHIP'   | 'CS41002BB02'(!)        = ''              | ''                 | 'CS41002BB02'           | 'R0402'             | '(R0402-0201)'                 | '100K'    | '0.1%'  | '1/16W'  | 'DISCRETE' | 'RES CHIP 100K 1/16W +-0.1%(0402)AEC'              | 'CHIP0402'     | ''          | ''            | '20160111'
 '100K'       | '0.1%'    | '1/16W'  | '0402LF'  | 'EMPTY'  | 'CS41002BB02'(!)        = ''              | ''                 | 'CS41002BB02'           | 'R0402'             | '(R0402-0201)'                 | '100K'    | '0.1%'  | '1/16W'  | 'IO'       | 'RES CHIP 100K 1/16W +-0.1%(0402)AEC'              | 'CHIP0402'     | ''          | ''            | '20160111'
 '100K'       | '1%'      | '1/16W'  | '0402LF'  | 'CHIP'   | 'CS41002FB16'(!)        = ''              | ''                 | 'CS41002FB16'           | 'R0402'             | '(R0402-0201)'                 | '100K'    | '1%'    | '1/16W'  | 'DISCRETE' | 'RES CHIP 100K 1/16W +-1%(0402)AEC'                | 'CHIP0402'     | ''          | ''            | '20160113'
 '100K'       | '1%'      | '1/16W'  | '0402LF'  | 'EMPTY'  | 'CS41002FB16'(!)        = ''              | ''                 | 'CS41002FB16'           | 'R0402'             | '(R0402-0201)'                 | '100K'    | '1%'    | '1/16W'  | 'IO'       | 'RES CHIP 100K 1/16W +-1%(0402)AEC'                | 'CHIP0402'     | ''          | ''            | '20160113'
 '10K'        | '0.1%'    | '1/16W'  | '0402LF'  | 'CHIP'   | 'CS31002BB05'(!)        = ''              | ''                 | 'CS31002BB05'           | 'R0402'             | '(R0402-0201)'                 | '10K'     | '0.1%'  | '1/16W'  | 'DISCRETE' | 'RES CHIP 10K 1/16W +-0.1%(0402)AEC'               | 'CHIP0402'     | ''          | ''            | '20160113'
 '10K'        | '0.1%'    | '1/16W'  | '0402LF'  | 'EMPTY'  | 'CS31002BB05'(!)        = ''              | ''                 | 'CS31002BB05'           | 'R0402'             | '(R0402-0201)'                 | '10K'     | '0.1%'  | '1/16W'  | 'IO'       | 'RES CHIP 10K 1/16W +-0.1%(0402)AEC'               | 'CHIP0402'     | ''          | ''            | '20160113'
 '10K'        | '1%'      | '1/16W'  | '0402LF'  | 'CHIP'   | 'CS31002FB13'(!)        = ''              | ''                 | 'CS31002FB13'           | 'R0402'             | '(R0402-0201)'                 | '10K'     | '1%'    | '1/16W'  | 'DISCRETE' | 'RES CHIP 10K 1/16W +-1%(0402)AEC'                 | 'CHIP0402'     | ''          | ''            | '20160113'
 '10K'        | '1%'      | '1/16W'  | '0402LF'  | 'EMPTY'  | 'CS31002FB13'(!)        = ''              | ''                 | 'CS31002FB13'           | 'R0402'             | '(R0402-0201)'                 | '10K'     | '1%'    | '1/16W'  | 'IO'       | 'RES CHIP 10K 1/16W +-1%(0402)AEC'                 | 'CHIP0402'     | ''          | ''            | '20160113'
 '10K'        | '5%'      | '1/16W'  | '0402LF'  | 'CHIP'   | 'CS31002JB09'(!)        = ''              | ''                 | 'CS31002JB09'           | 'R0402'             | '(R0402-0201)'                 | '10K'     | '5%'    | '1/16W'  | 'DISCRETE' | 'RES CHIP 10K 1/16W +-5%(0402)AEC'                 | 'CHIP0402'     | ''          | ''            | '20160113'
 '10K'        | '5%'      | '1/16W'  | '0402LF'  | 'EMPTY'  | 'CS31002JB09'(!)        = ''              | ''                 | 'CS31002JB09'           | 'R0402'             | '(R0402-0201)'                 | '10K'     | '5%'    | '1/16W'  | 'IO'       | 'RES CHIP 10K 1/16W +-5%(0402)AEC'                 | 'CHIP0402'     | ''          | ''            | '20160113'
 '11.8K'      | '1%'      | '1/16W'  | '0402LF'  | 'CHIP'   | 'CS31182FB04'(!)        = ''              | ''                 | 'CS31182FB04'           | 'R0402'             | '(R0402-0201)'                 | '11.8K'   | '1%'    | '1/16W'  | 'DISCRETE' | 'RES CHIP 11.8K 1/16W +-1%(0402)AEC'               | 'CHIP0402'     | ''          | ''            | '20160113'
 '11.8K'      | '1%'      | '1/16W'  | '0402LF'  | 'EMPTY'  | 'CS31182FB04'(!)        = ''              | ''                 | 'CS31182FB04'           | 'R0402'             | '(R0402-0201)'                 | '11.8K'   | '1%'    | '1/16W'  | 'IO'       | 'RES CHIP 11.8K 1/16W +-1%(0402)AEC'               | 'CHIP0402'     | ''          | ''            | '20160113'
 '43K'        | '1%'      | '1/10W'  | '0603LF'  | 'CHIP'   | 'CS34303F901'(!)        = 'End of Design' | 'Comp-Approve'     | 'CS34303F901'           | 'R0603'             | '(SMR0603AW)'                  | '43K'     | '1%'    | '1/10W'  | 'DISCRETE' | 'RES CHIP 43K 1/10W +-1%(0603)'                    | 'CHIPR0603'    | ''          | ''            | '20160115'
 '43K'        | '1%'      | '1/10W'  | '0603LF'  | 'EMPTY'  | 'CS34303F901'(!)        = 'End of Design' | 'Comp-Approve'     | 'CS34303F901'           | 'R0603'             | '(SMR0603AW)'                  | '43K'     | '1%'    | '1/10W'  | 'IO'       | 'RES CHIP 43K 1/10W +-1%(0603)'                    | 'CHIPR0603'    | ''          | ''            | '20160115'
 '1K'         | '1%'      | '1/16W'  | '0402LF'  | 'CHIP'   | 'CS21002BB01'(!)        = ''              | 'End of Life'      | 'CS21002BB01'           | 'R0402_EOL'         | '(R0402-0201)'                 | '1K'      | '1%'    | '1/16W'  | 'DISCRETE' | 'RES CHIP 1K 1/16W +-0.1%(0402)AEC'                | 'CHIPR0402'    | ''          | ''            | '20160115'
 '1K'         | '1%'      | '1/16W'  | '0402LF'  | 'EMPTY'  | 'CS21002BB01'(!)        = ''              | 'End of Life'      | 'CS21002BB01'           | 'R0402_EOL'         | '(R0402-0201)'                 | '1K'      | '1%'    | '1/16W'  | 'IO'       | 'RES CHIP 1K 1/16W +-0.1%(0402)AEC'                | 'CHIPR0402'    | ''          | ''            | '20160115'
 '0.005'      | '1%'      | '1W'     | '2512LF'  | 'CHIP'   | 'CS+0058FR02'(!)        = 'Non-Preferred' | 'End of Life'      | 'CS+0058FR02'           | 'R2512A_EOL'        | '(SMR2512AW)'                  | '0.005'   | '1%'    | '1W'     | 'DISCRETE' | 'RES CHIP 0.005 1W +-1%(2512)AEC'                  | 'CHIP2512'     | ''          | ''            | '20160115'
 '0.005'      | '1%'      | '1W'     | '2512LF'  | 'EMPTY'  | 'CS+0058FR02'(!)        = 'Non-Preferred' | 'End of Life'      | 'CS+0058FR02'           | 'R2512A_EOL'        | '(SMR2512AW)'                  | '0.005'   | '1%'    | '1W'     | 'IO'       | 'RES CHIP 0.005 1W +-1%(2512)AEC'                  | 'CHIP2512'     | ''          | ''            | '20160115'
 '113'        | '1%'      | '1/16W'  | '0402LF'  | 'CHIP'   | 'CS11132FB04'(!)        = ''              | ''                 | 'CS11132FB04'           | 'R0402'             | '(R0402-0201)'                 | '113'     | '1%'    | '1/16W'  | 'DISCRETE' | 'RES CHIP 113 1/16W +-1%(0402)AEC'                 | 'CHIP0402'     | ''          | ''            | '20160116'
 '113'        | '1%'      | '1/16W'  | '0402LF'  | 'EMPTY'  | 'CS11132FB04'(!)        = ''              | ''                 | 'CS11132FB04'           | 'R0402'             | '(R0402-0201)'                 | '113'     | '1%'    | '1/16W'  | 'IO'       | 'RES CHIP 113 1/16W +-1%(0402)AEC'                 | 'CHIP0402'     | ''          | ''            | '20160116'
 '115K'       | '1%'      | '1/16W'  | '0402LF'  | 'CHIP'   | 'CS41152FB01'(!)        = ''              | ''                 | 'CS41152FB01'           | 'R0402'             | '(R0402-0201)'                 | '115K'    | '1%'    | '1/16W'  | 'DISCRETE' | 'RES CHIP 115K 1/16W +-1%(0402)AEC'                | 'CHIP0402'     | ''          | ''            | '20160116'
 '115K'       | '1%'      | '1/16W'  | '0402LF'  | 'EMPTY'  | 'CS41152FB01'(!)        = ''              | ''                 | 'CS41152FB01'           | 'R0402'             | '(R0402-0201)'                 | '115K'    | '1%'    | '1/16W'  | 'IO'       | 'RES CHIP 115K 1/16W +-1%(0402)AEC'                | 'CHIP0402'     | ''          | ''            | '20160116'
 '12.1K'      | '1%'      | '1/16W'  | '0402LF'  | 'CHIP'   | 'CS31212FB06'(!)        = ''              | ''                 | 'CS31212FB06'           | 'R0402'             | '(R0402-0201)'                 | '12.1K'   | '1%'    | '1/16W'  | 'DISCRETE' | 'RES CHIP 12.1K 1/16W +-1%(0402)AEC'               | 'CHIP0402'     | ''          | ''            | '20160116'
 '12.1K'      | '1%'      | '1/16W'  | '0402LF'  | 'EMPTY'  | 'CS31212FB06'(!)        = ''              | ''                 | 'CS31212FB06'           | 'R0402'             | '(R0402-0201)'                 | '12.1K'   | '1%'    | '1/16W'  | 'IO'       | 'RES CHIP 12.1K 1/16W +-1%(0402)AEC'               | 'CHIP0402'     | ''          | ''            | '20160116'
 '120'        | '1%'      | '1/16W'  | '0402LF'  | 'CHIP'   | 'CS11202FB04'(!)        = ''              | ''                 | 'CS11202FB04'           | 'R0402'             | '(R0402-0201)'                 | '120'     | '1%'    | '1/16W'  | 'DISCRETE' | 'RES CHIP 120 1/16W +-1%(0402)AEC'                 | 'CHIP0402'     | ''          | ''            | '20160116'
 '120'        | '1%'      | '1/16W'  | '0402LF'  | 'EMPTY'  | 'CS11202FB04'(!)        = ''              | ''                 | 'CS11202FB04'           | 'R0402'             | '(R0402-0201)'                 | '120'     | '1%'    | '1/16W'  | 'IO'       | 'RES CHIP 120 1/16W +-1%(0402)AEC'                 | 'CHIP0402'     | ''          | ''            | '20160116'
 '12K'        | '1%'      | '1/16W'  | '0402LF'  | 'CHIP'   | 'CS31202FB05'(!)        = ''              | ''                 | 'CS31202FB05'           | 'R0402'             | '(R0402-0201)'                 | '12K'     | '1%'    | '1/16W'  | 'DISCRETE' | 'RES CHIP 12K 1/16W +-1%(0402)AEC'                 | 'CHIP0402'     | ''          | ''            | '20160116'
 '12K'        | '1%'      | '1/16W'  | '0402LF'  | 'EMPTY'  | 'CS31202FB05'(!)        = ''              | ''                 | 'CS31202FB05'           | 'R0402'             | '(R0402-0201)'                 | '12K'     | '1%'    | '1/16W'  | 'IO'       | 'RES CHIP 12K 1/16W +-1%(0402)AEC'                 | 'CHIP0402'     | ''          | ''            | '20160116'
 '15'         | '1%'      | '1/16W'  | '0402LF'  | 'CHIP'   | 'CS01502FB04'(!)        = ''              | ''                 | 'CS01502FB04'           | 'R0402'             | '(R0402-0201)'                 | '15'      | '1%'    | '1/16W'  | 'DISCRETE' | 'RES CHIP 15 1/16W +-1%(0402)AEC'                  | 'CHIP0402'     | ''          | ''            | '20160116'
 '15'         | '1%'      | '1/16W'  | '0402LF'  | 'EMPTY'  | 'CS01502FB04'(!)        = ''              | ''                 | 'CS01502FB04'           | 'R0402'             | '(R0402-0201)'                 | '15'      | '1%'    | '1/16W'  | 'IO'       | 'RES CHIP 15 1/16W +-1%(0402)AEC'                  | 'CHIP0402'     | ''          | ''            | '20160116'
 '15.8K'      | '1%'      | '1/16W'  | '0402LF'  | 'CHIP'   | 'CS31582FB03'(!)        = ''              | ''                 | 'CS31582FB03'           | 'R0402'             | '(R0402-0201)'                 | '15.8K'   | '1%'    | '1/16W'  | 'DISCRETE' | 'RES CHIP 15.8K 1/16W +-1%(0402)AEC'               | 'CHIP0402'     | ''          | ''            | '20160116'
 '15.8K'      | '1%'      | '1/16W'  | '0402LF'  | 'EMPTY'  | 'CS31582FB03'(!)        = ''              | ''                 | 'CS31582FB03'           | 'R0402'             | '(R0402-0201)'                 | '15.8K'   | '1%'    | '1/16W'  | 'IO'       | 'RES CHIP 15.8K 1/16W +-1%(0402)AEC'               | 'CHIP0402'     | ''          | ''            | '20160116'
 '150'        | '1%'      | '1/16W'  | '0402LF'  | 'CHIP'   | 'CS11502FB08'(!)        = ''              | ''                 | 'CS11502FB08'           | 'R0402'             | '(R0402-0201)'                 | '150'     | '1%'    | '1/16W'  | 'DISCRETE' | 'RES CHIP 150 1/16W +-1%(0402)AEC'                 | 'CHIP0402'     | ''          | ''            | '20160116'
 '150'        | '1%'      | '1/16W'  | '0402LF'  | 'EMPTY'  | 'CS11502FB08'(!)        = ''              | ''                 | 'CS11502FB08'           | 'R0402'             | '(R0402-0201)'                 | '150'     | '1%'    | '1/16W'  | 'IO'       | 'RES CHIP 150 1/16W +-1%(0402)AEC'                 | 'CHIP0402'     | ''          | ''            | '20160116'
 '150'        | '5%'      | '1/16W'  | '0402LF'  | 'CHIP'   | 'CS11502JB03'(!)        = ''              | ''                 | 'CS11502JB03'           | 'R0402'             | '(R0402-0201)'                 | '150'     | '5%'    | '1/16W'  | 'DISCRETE' | 'RES CHIP 150 1/16W +-5%(0402)AEC'                 | 'CHIP0402'     | ''          | ''            | '20160116'
 '150'        | '5%'      | '1/16W'  | '0402LF'  | 'EMPTY'  | 'CS11502JB03'(!)        = ''              | ''                 | 'CS11502JB03'           | 'R0402'             | '(R0402-0201)'                 | '150'     | '5%'    | '1/16W'  | 'IO'       | 'RES CHIP 150 1/16W +-5%(0402)AEC'                 | 'CHIP0402'     | ''          | ''            | '20160116'
 '150K'       | '1%'      | '1/16W'  | '0402LF'  | 'CHIP'   | 'CS41502FB05'(!)        = ''              | ''                 | 'CS41502FB05'           | 'R0402'             | '(R0402-0201)'                 | '150K'    | '1%'    | '1/16W'  | 'DISCRETE' | 'RES CHIP 150K 1/16W +-1%(0402)AEC'                | 'CHIP0402'     | ''          | ''            | '20160116'
 '150K'       | '1%'      | '1/16W'  | '0402LF'  | 'EMPTY'  | 'CS41502FB05'(!)        = ''              | ''                 | 'CS41502FB05'           | 'R0402'             | '(R0402-0201)'                 | '150K'    | '1%'    | '1/16W'  | 'IO'       | 'RES CHIP 150K 1/16W +-1%(0402)AEC'                | 'CHIP0402'     | ''          | ''            | '20160116'
 '154K'       | '1%'      | '1/16W'  | '0402LF'  | 'CHIP'   | 'CS41542FB06'(!)        = ''              | ''                 | 'CS41542FB06'           | 'R0402'             | '(R0402-0201)'                 | '154K'    | '1%'    | '1/16W'  | 'DISCRETE' | 'RES CHIP 154K 1/16W +-1%(0402)AEC'                | 'CHIP0402'     | ''          | ''            | '20160116'
 '154K'       | '1%'      | '1/16W'  | '0402LF'  | 'EMPTY'  | 'CS41542FB06'(!)        = ''              | ''                 | 'CS41542FB06'           | 'R0402'             | '(R0402-0201)'                 | '154K'    | '1%'    | '1/16W'  | 'IO'       | 'RES CHIP 154K 1/16W +-1%(0402)AEC'                | 'CHIP0402'     | ''          | ''            | '20160116'
 '15K'        | '1%'      | '1/16W'  | '0402LF'  | 'CHIP'   | 'CS31502FB06'(!)        = ''              | ''                 | 'CS31502FB06'           | 'R0402'             | '(R0402-0201)'                 | '15K'     | '1%'    | '1/16W'  | 'DISCRETE' | 'RES CHIP 15K 1/16W +-1%(0402)AEC'                 | 'CHIP0402'     | ''          | ''            | '20160116'
 '15K'        | '1%'      | '1/16W'  | '0402LF'  | 'EMPTY'  | 'CS31502FB06'(!)        = ''              | ''                 | 'CS31502FB06'           | 'R0402'             | '(R0402-0201)'                 | '15K'     | '1%'    | '1/16W'  | 'IO'       | 'RES CHIP 15K 1/16W +-1%(0402)AEC'                 | 'CHIP0402'     | ''          | ''            | '20160116'
 '169'        | '1%'      | '1/16W'  | '0402LF'  | 'CHIP'   | 'CS11692FB02'(!)        = ''              | ''                 | 'CS11692FB02'           | 'R0402'             | '(R0402-0201)'                 | '169'     | '1%'    | '1/16W'  | 'DISCRETE' | 'RES CHIP 169 1/16W +-1%(0402)AEC'                 | 'CHIP0402'     | ''          | ''            | '20160116'
 '169'        | '1%'      | '1/16W'  | '0402LF'  | 'EMPTY'  | 'CS11692FB02'(!)        = ''              | ''                 | 'CS11692FB02'           | 'R0402'             | '(R0402-0201)'                 | '169'     | '1%'    | '1/16W'  | 'IO'       | 'RES CHIP 169 1/16W +-1%(0402)AEC'                 | 'CHIP0402'     | ''          | ''            | '20160116'
 '16K'        | '1%'      | '1/16W'  | '0402LF'  | 'CHIP'   | 'CS31602FB02'(!)        = ''              | ''                 | 'CS31602FB02'           | 'R0402'             | '(R0402-0201)'                 | '16K'     | '1%'    | '1/16W'  | 'DISCRETE' | 'RES CHIP 16K 1/16W +-1%(0402)AEC'                 | 'CHIP0402'     | ''          | ''            | '20160116'
 '16K'        | '1%'      | '1/16W'  | '0402LF'  | 'EMPTY'  | 'CS31602FB02'(!)        = ''              | ''                 | 'CS31602FB02'           | 'R0402'             | '(R0402-0201)'                 | '16K'     | '1%'    | '1/16W'  | 'IO'       | 'RES CHIP 16K 1/16W +-1%(0402)AEC'                 | 'CHIP0402'     | ''          | ''            | '20160116'
 '1K'         | '5%'      | '1/16W'  | '0402LF'  | 'CHIP'   | 'CS21002JB08'(!)        = ''              | ''                 | 'CS21002JB08'           | 'R0402'             | '(R0402-0201)'                 | '1K'      | '5%'    | '1/16W'  | 'DISCRETE' | 'RES CHIP 1K 1/16W +-5%(0402)AEC'                  | 'CHIP0402'     | ''          | ''            | '20160116'
 '1K'         | '5%'      | '1/16W'  | '0402LF'  | 'EMPTY'  | 'CS21002JB08'(!)        = ''              | ''                 | 'CS21002JB08'           | 'R0402'             | '(R0402-0201)'                 | '1K'      | '5%'    | '1/16W'  | 'IO'       | 'RES CHIP 1K 1/16W +-5%(0402)AEC'                  | 'CHIP0402'     | ''          | ''            | '20160116'
 '1M'         | '1%'      | '1/16W'  | '0402LF'  | 'CHIP'   | 'CS51002FB06'(!)        = ''              | ''                 | 'CS51002FB06'           | 'R0402'             | '(R0402-0201)'                 | '1M'      | '1%'    | '1/16W'  | 'DISCRETE' | 'RES CHIP 1M 1/16W +-1%(0402)AEC'                  | 'CHIP0402'     | ''          | ''            | '20160116'
 '1M'         | '1%'      | '1/16W'  | '0402LF'  | 'EMPTY'  | 'CS51002FB06'(!)        = ''              | ''                 | 'CS51002FB06'           | 'R0402'             | '(R0402-0201)'                 | '1M'      | '1%'    | '1/16W'  | 'IO'       | 'RES CHIP 1M 1/16W +-1%(0402)AEC'                  | 'CHIP0402'     | ''          | ''            | '20160116'
 '2'          | '1%'      | '1/16W'  | '0402LF'  | 'CHIP'   | 'CS-2002FB03'(!)        = ''              | ''                 | 'CS-2002FB03'           | 'R0402'             | '(R0402-0201)'                 | '2'       | '1%'    | '1/16W'  | 'DISCRETE' | 'RES CHIP 2 1/16W +-1%(0402)AEC'                   | 'CHIP0402'     | ''          | ''            | '20160116'
 '2'          | '1%'      | '1/16W'  | '0402LF'  | 'EMPTY'  | 'CS-2002FB03'(!)        = ''              | ''                 | 'CS-2002FB03'           | 'R0402'             | '(R0402-0201)'                 | '2'       | '1%'    | '1/16W'  | 'IO'       | 'RES CHIP 2 1/16W +-1%(0402)AEC'                   | 'CHIP0402'     | ''          | ''            | '20160116'
 '2.2K'       | '1%'      | '1/16W'  | '0402LF'  | 'CHIP'   | 'CS22202FB02'(!)        = ''              | ''                 | 'CS22202FB02'           | 'R0402'             | '(R0402-0201)'                 | '2.2K'    | '1%'    | '1/16W'  | 'DISCRETE' | 'RES CHIP 2.2K 1/16W +-1%(0402)AEC'                | 'CHIP0402'     | ''          | ''            | '20160116'
 '2.2K'       | '1%'      | '1/16W'  | '0402LF'  | 'EMPTY'  | 'CS22202FB02'(!)        = ''              | ''                 | 'CS22202FB02'           | 'R0402'             | '(R0402-0201)'                 | '2.2K'    | '1%'    | '1/16W'  | 'IO'       | 'RES CHIP 2.2K 1/16W +-1%(0402)AEC'                | 'CHIP0402'     | ''          | ''            | '20160116'
 '20'         | '1%'      | '1/16W'  | '0402LF'  | 'CHIP'   | 'CS02002FB04'(!)        = ''              | ''                 | 'CS02002FB04'           | 'R0402'             | '(R0402-0201)'                 | '20'      | '1%'    | '1/16W'  | 'DISCRETE' | 'RES CHIP 20 1/16W +-1%(0402)AEC'                  | 'CHIP0402'     | ''          | ''            | '20160116'
 '20'         | '1%'      | '1/16W'  | '0402LF'  | 'EMPTY'  | 'CS02002FB04'(!)        = ''              | ''                 | 'CS02002FB04'           | 'R0402'             | '(R0402-0201)'                 | '20'      | '1%'    | '1/16W'  | 'IO'       | 'RES CHIP 20 1/16W +-1%(0402)AEC'                  | 'CHIP0402'     | ''          | ''            | '20160116'
 '200'        | '1%'      | '1/16W'  | '0402LF'  | 'CHIP'   | 'CS12002FB12'(!)        = ''              | ''                 | 'CS12002FB12'           | 'R0402'             | '(R0402-0201)'                 | '200'     | '1%'    | '1/16W'  | 'DISCRETE' | 'RES CHIP 200 1/16W +-1%(0402)AEC'                 | 'CHIP0402'     | ''          | ''            | '20160116'
 '200'        | '1%'      | '1/16W'  | '0402LF'  | 'EMPTY'  | 'CS12002FB12'(!)        = ''              | ''                 | 'CS12002FB12'           | 'R0402'             | '(R0402-0201)'                 | '200'     | '1%'    | '1/16W'  | 'IO'       | 'RES CHIP 200 1/16W +-1%(0402)AEC'                 | 'CHIP0402'     | ''          | ''            | '20160116'
 '200K'       | '1%'      | '1/16W'  | '0402LF'  | 'CHIP'   | 'CS42002FB10'(!)        = ''              | ''                 | 'CS42002FB10'           | 'R0402'             | '(R0402-0201)'                 | '200K'    | '1%'    | '1/16W'  | 'DISCRETE' | 'RES CHIP 200K 1/16W +-1%(0402)AEC'                | 'CHIP0402'     | ''          | ''            | '20160116'
 '200K'       | '1%'      | '1/16W'  | '0402LF'  | 'EMPTY'  | 'CS42002FB10'(!)        = ''              | ''                 | 'CS42002FB10'           | 'R0402'             | '(R0402-0201)'                 | '200K'    | '1%'    | '1/16W'  | 'IO'       | 'RES CHIP 200K 1/16W +-1%(0402)AEC'                | 'CHIP0402'     | ''          | ''            | '20160116'
 '200'        | '0.1%'    | '1/16W'  | '0402LF'  | 'CHIP'   | 'CS12002BB01'(!)        = ''              | ''                 | 'CS12002BB01'           | 'R0402'             | '(R0402-0201)'                 | '200'     | '0.1%'  | '1/16W'  | 'DISCRETE' | 'RES CHIP 200 1/16W +-0.1%(0402)AEC'               | 'CHIP0402'     | ''          | ''            | '20160120'
 '200'        | '0.1%'    | '1/16W'  | '0402LF'  | 'EMPTY'  | 'CS12002BB01'(!)        = ''              | ''                 | 'CS12002BB01'           | 'R0402'             | '(R0402-0201)'                 | '200'     | '0.1%'  | '1/16W'  | 'IO'       | 'RES CHIP 200 1/16W +-0.1%(0402)AEC'               | 'CHIP0402'     | ''          | ''            | '20160120'
 '200'        | '0.1%'    | '1/16W'  | '0402LF'  | 'CHIP'   | 'CS12002BB00'(!)        = ''              | ''                 | 'CS12002BB00'           | 'R0402'             | '(R0402-0201)'                 | '200'     | '0.1%'  | '1/16W'  | 'DISCRETE' | 'RES CHIP 200 1/16W +-0.1% (0402)'                 | 'CHIP0402'     | ''          | ''            | '20160120'
 '200'        | '0.1%'    | '1/16W'  | '0402LF'  | 'EMPTY'  | 'CS12002BB00'(!)        = ''              | ''                 | 'CS12002BB00'           | 'R0402'             | '(R0402-0201)'                 | '200'     | '0.1%'  | '1/16W'  | 'IO'       | 'RES CHIP 200 1/16W +-0.1% (0402)'                 | 'CHIP0402'     | ''          | ''            | '20160120'
 '20K'        | '1%'      | '1/16W'  | '0402LF'  | 'CHIP'   | 'CS32002FB12'(!)        = ''              | ''                 | 'CS32002FB12'           | 'R0402'             | '(R0402-0201)'                 | '20K'     | '1%'    | '1/16W'  | 'DISCRETE' | 'RES CHIP 20K 1/16W +-1%(0402)AEC'                 | 'CHIP0402'     | ''          | ''            | '20160120'
 '20K'        | '1%'      | '1/16W'  | '0402LF'  | 'EMPTY'  | 'CS32002FB12'(!)        = ''              | ''                 | 'CS32002FB12'           | 'R0402'             | '(R0402-0201)'                 | '20K'     | '1%'    | '1/16W'  | 'IO'       | 'RES CHIP 20K 1/16W +-1%(0402)AEC'                 | 'CHIP0402'     | ''          | ''            | '20160120'
 '22'         | '1%'      | '1/16W'  | '0402LF'  | 'CHIP'   | 'CS02202FB03'(!)        = ''              | ''                 | 'CS02202FB03'           | 'R0402'             | '(R0402-0201)'                 | '22'      | '1%'    | '1/16W'  | 'DISCRETE' | 'RES CHIP 22 1/16W +-1%(0402)AEC'                  | 'CHIP0402'     | ''          | ''            | '20160120'
 '22'         | '1%'      | '1/16W'  | '0402LF'  | 'EMPTY'  | 'CS02202FB03'(!)        = ''              | ''                 | 'CS02202FB03'           | 'R0402'             | '(R0402-0201)'                 | '22'      | '1%'    | '1/16W'  | 'IO'       | 'RES CHIP 22 1/16W +-1%(0402)AEC'                  | 'CHIP0402'     | ''          | ''            | '20160120'
 '220'        | '5%'      | '1/16W'  | '0402LF'  | 'CHIP'   | 'CS12202JB04'(!)        = ''              | ''                 | 'CS12202JB04'           | 'R0402'             | '(R0402-0201)'                 | '220'     | '5%'    | '1/16W'  | 'DISCRETE' | 'RES CHIP 220 1/16W +-5%(0402)AEC'                 | 'CHIP0402'     | ''          | ''            | '20160120'
 '220'        | '5%'      | '1/16W'  | '0402LF'  | 'EMPTY'  | 'CS12202JB04'(!)        = ''              | ''                 | 'CS12202JB04'           | 'R0402'             | '(R0402-0201)'                 | '220'     | '5%'    | '1/16W'  | 'IO'       | 'RES CHIP 220 1/16W +-5%(0402)AEC'                 | 'CHIP0402'     | ''          | ''            | '20160120'
 '221'        | '1%'      | '1/16W'  | '0402LF'  | 'CHIP'   | 'CS12212FB04'(!)        = ''              | ''                 | 'CS12212FB04'           | 'R0402'             | '(R0402-0201)'                 | '221'     | '1%'    | '1/16W'  | 'DISCRETE' | 'RES CHIP 221 1/16W +-1%(0402)AEC'                 | 'CHIP0402'     | ''          | ''            | '20160120'
 '221'        | '1%'      | '1/16W'  | '0402LF'  | 'EMPTY'  | 'CS12212FB04'(!)        = ''              | ''                 | 'CS12212FB04'           | 'R0402'             | '(R0402-0201)'                 | '221'     | '1%'    | '1/16W'  | 'IO'       | 'RES CHIP 221 1/16W +-1%(0402)AEC'                 | 'CHIP0402'     | ''          | ''            | '20160120'
 '240'        | '1%'      | '1/16W'  | '0402LF'  | 'CHIP'   | 'CS12402FB02'(!)        = ''              | ''                 | 'CS12402FB02'           | 'R0402'             | '(R0402-0201)'                 | '240'     | '1%'    | '1/16W'  | 'DISCRETE' | 'RES CHIP 240 1/16W +-1%(0402)AEC'                 | 'CHIP0402'     | ''          | ''            | '20160120'
 '240'        | '1%'      | '1/16W'  | '0402LF'  | 'EMPTY'  | 'CS12402FB02'(!)        = ''              | ''                 | 'CS12402FB02'           | 'R0402'             | '(R0402-0201)'                 | '240'     | '1%'    | '1/16W'  | 'IO'       | 'RES CHIP 240 1/16W +-1%(0402)AEC'                 | 'CHIP0402'     | ''          | ''            | '20160120'
 '249'        | '0.1%'    | '1/16W'  | '0402LF'  | 'CHIP'   | 'CS12492BB03'(!)        = ''              | ''                 | 'CS12492BB03'           | 'R0402'             | '(R0402-0201)'                 | '249'     | '0.1%'  | '1/16W'  | 'DISCRETE' | 'RES CHIP 249 1/16W +-0.1%(0402)AEC'               | 'CHIP0402'     | ''          | ''            | '20160120'
 '249'        | '0.1%'    | '1/16W'  | '0402LF'  | 'EMPTY'  | 'CS12492BB03'(!)        = ''              | ''                 | 'CS12492BB03'           | 'R0402'             | '(R0402-0201)'                 | '249'     | '0.1%'  | '1/16W'  | 'IO'       | 'RES CHIP 249 1/16W +-0.1%(0402)AEC'               | 'CHIP0402'     | ''          | ''            | '20160120'
 '25.5K'      | '1%'      | '1/16W'  | '0402LF'  | 'CHIP'   | 'CS32552FB04'(!)        = ''              | ''                 | 'CS32552FB04'           | 'R0402'             | '(R0402-0201)'                 | '25.5K'   | '1%'    | '1/16W'  | 'DISCRETE' | 'RES CHIP 25.5K 1/16W +-1%(0402)AEC'               | 'CHIP0402'     | ''          | ''            | '20160120'
 '25.5K'      | '1%'      | '1/16W'  | '0402LF'  | 'EMPTY'  | 'CS32552FB04'(!)        = ''              | ''                 | 'CS32552FB04'           | 'R0402'             | '(R0402-0201)'                 | '25.5K'   | '1%'    | '1/16W'  | 'IO'       | 'RES CHIP 25.5K 1/16W +-1%(0402)AEC'               | 'CHIP0402'     | ''          | ''            | '20160120'
 '255K'       | '1%'      | '1/16W'  | '0402LF'  | 'CHIP'   | 'CS42552FB03'(!)        = ''              | ''                 | 'CS42552FB03'           | 'R0402'             | '(R0402-0201)'                 | '255K'    | '1%'    | '1/16W'  | 'DISCRETE' | 'RES CHIP 255K 1/16W +-1%(0402)AEC'                | 'CHIP0402'     | ''          | ''            | '20160121'
 '255K'       | '1%'      | '1/16W'  | '0402LF'  | 'EMPTY'  | 'CS42552FB03'(!)        = ''              | ''                 | 'CS42552FB03'           | 'R0402'             | '(R0402-0201)'                 | '255K'    | '1%'    | '1/16W'  | 'IO'       | 'RES CHIP 255K 1/16W +-1%(0402)AEC'                | 'CHIP0402'     | ''          | ''            | '20160121'
 '27.4'       | '1%'      | '1/16W'  | '0402LF'  | 'CHIP'   | 'CS02742FB04'(!)        = ''              | ''                 | 'CS02742FB04'           | 'R0402'             | '(R0402-0201)'                 | '27.4'    | '1%'    | '1/16W'  | 'DISCRETE' | 'RES CHIP 27.4 1/16W +-1%(0402)AEC'                | 'CHIP0402'     | ''          | ''            | '20160121'
 '27.4'       | '1%'      | '1/16W'  | '0402LF'  | 'EMPTY'  | 'CS02742FB04'(!)        = ''              | ''                 | 'CS02742FB04'           | 'R0402'             | '(R0402-0201)'                 | '27.4'    | '1%'    | '1/16W'  | 'IO'       | 'RES CHIP 27.4 1/16W +-1%(0402)AEC'                | 'CHIP0402'     | ''          | ''            | '20160121'
 '2K'         | '1%'      | '1/16W'  | '0402LF'  | 'CHIP'   | 'CS22002FB11'(!)        = ''              | ''                 | 'CS22002FB11'           | 'R0402'             | '(R0402-0201)'                 | '2K'      | '1%'    | '1/16W'  | 'DISCRETE' | 'RES CHIP 2K 1/16W +-1%(0402)AEC'                  | 'CHIP0402'     | ''          | ''            | '20160121'
 '2K'         | '1%'      | '1/16W'  | '0402LF'  | 'EMPTY'  | 'CS22002FB11'(!)        = ''              | ''                 | 'CS22002FB11'           | 'R0402'             | '(R0402-0201)'                 | '2K'      | '1%'    | '1/16W'  | 'IO'       | 'RES CHIP 2K 1/16W +-1%(0402)AEC'                  | 'CHIP0402'     | ''          | ''            | '20160121'
 '3.01K'      | '1%'      | '1/16W'  | '0402LF'  | 'CHIP'   | 'CS23012FB09'(!)        = ''              | ''                 | 'CS23012FB09'           | 'R0402'             | '(R0402-0201)'                 | '3.01K'   | '1%'    | '1/16W'  | 'DISCRETE' | 'RES CHIP 3.01K 1/16W +-1%(0402)AEC'               | 'CHIP0402'     | ''          | ''            | '20160121'
 '3.01K'      | '1%'      | '1/16W'  | '0402LF'  | 'EMPTY'  | 'CS23012FB09'(!)        = ''              | ''                 | 'CS23012FB09'           | 'R0402'             | '(R0402-0201)'                 | '3.01K'   | '1%'    | '1/16W'  | 'IO'       | 'RES CHIP 3.01K 1/16W +-1%(0402)AEC'               | 'CHIP0402'     | ''          | ''            | '20160121'
 '33'         | '1%'      | '1/16W'  | '0402LF'  | 'CHIP'   | 'CS03302FB04'(!)        = ''              | ''                 | 'CS03302FB04'           | 'R0402'             | '(R0402-0201)'                 | '33'      | '1%'    | '1/16W'  | 'DISCRETE' | 'RES CHIP 33 1/16W +-1%(0402)AEC'                  | 'CHIP0402'     | ''          | ''            | '20160121'
 '33'         | '1%'      | '1/16W'  | '0402LF'  | 'EMPTY'  | 'CS03302FB04'(!)        = ''              | ''                 | 'CS03302FB04'           | 'R0402'             | '(R0402-0201)'                 | '33'      | '1%'    | '1/16W'  | 'IO'       | 'RES CHIP 33 1/16W +-1%(0402)AEC'                  | 'CHIP0402'     | ''          | ''            | '20160121'
 '33'         | '5%'      | '1/16W'  | '0402LF'  | 'CHIP'   | 'CS03302JB09'(!)        = ''              | ''                 | 'CS03302JB09'           | 'R0402'             | '(R0402-0201)'                 | '33'      | '5%'    | '1/16W'  | 'DISCRETE' | 'RES CHIP 33 1/16W +-5% (0402)AEC'                 | 'CHIP0402'     | ''          | ''            | '20160121'
 '33'         | '5%'      | '1/16W'  | '0402LF'  | 'EMPTY'  | 'CS03302JB09'(!)        = ''              | ''                 | 'CS03302JB09'           | 'R0402'             | '(R0402-0201)'                 | '33'      | '5%'    | '1/16W'  | 'IO'       | 'RES CHIP 33 1/16W +-5% (0402)AEC'                 | 'CHIP0402'     | ''          | ''            | '20160121'
 '332'        | '1%'      | '1/16W'  | '0402LF'  | 'CHIP'   | 'CS13322FB06'(!)        = ''              | ''                 | 'CS13322FB06'           | 'R0402'             | '(R0402-0201)'                 | '332'     | '1%'    | '1/16W'  | 'DISCRETE' | 'RES CHIP 332 1/16W +-1%(0402)AEC'                 | 'CHIP0402'     | ''          | ''            | '20160121'
 '332'        | '1%'      | '1/16W'  | '0402LF'  | 'EMPTY'  | 'CS13322FB06'(!)        = ''              | ''                 | 'CS13322FB06'           | 'R0402'             | '(R0402-0201)'                 | '332'     | '1%'    | '1/16W'  | 'IO'       | 'RES CHIP 332 1/16W +-1%(0402)AEC'                 | 'CHIP0402'     | ''          | ''            | '20160121'
 '348'        | '1%'      | '1/16W'  | '0402LF'  | 'CHIP'   | 'CS13482FB03'(!)        = ''              | ''                 | 'CS13482FB03'           | 'R0402'             | '(R0402-0201)'                 | '348'     | '1%'    | '1/16W'  | 'DISCRETE' | 'RES CHIP 348 1/16W +-1%(0402)AEC'                 | 'CHIP0402'     | ''          | ''            | '20160121'
 '348'        | '1%'      | '1/16W'  | '0402LF'  | 'EMPTY'  | 'CS13482FB03'(!)        = ''              | ''                 | 'CS13482FB03'           | 'R0402'             | '(R0402-0201)'                 | '348'     | '1%'    | '1/16W'  | 'IO'       | 'RES CHIP 348 1/16W +-1%(0402)AEC'                 | 'CHIP0402'     | ''          | ''            | '20160121'
 '348K'       | '1%'      | '1/16W'  | '0402LF'  | 'CHIP'   | 'CS43482FB02'(!)        = ''              | ''                 | 'CS43482FB02'           | 'R0402'             | '(R0402-0201)'                 | '348K'    | '1%'    | '1/16W'  | 'DISCRETE' | 'RES CHIP 348K 1/16W +-1%(0402)AEC'                | 'CHIP0402'     | ''          | ''            | '20160121'
 '348K'       | '1%'      | '1/16W'  | '0402LF'  | 'EMPTY'  | 'CS43482FB02'(!)        = ''              | ''                 | 'CS43482FB02'           | 'R0402'             | '(R0402-0201)'                 | '348K'    | '1%'    | '1/16W'  | 'IO'       | 'RES CHIP 348K 1/16W +-1%(0402)AEC'                | 'CHIP0402'     | ''          | ''            | '20160121'
 '34K'        | '1%'      | '1/16W'  | '0402LF'  | 'CHIP'   | 'CS33402FB03'(!)        = ''              | ''                 | 'CS33402FB03'           | 'R0402'             | '(R0402-0201)'                 | '34K'     | '1%'    | '1/16W'  | 'DISCRETE' | 'RES CHIP 34K 1/16W +-1%(0402)AEC'                 | 'CHIP0402'     | ''          | ''            | '20160121'
 '34K'        | '1%'      | '1/16W'  | '0402LF'  | 'EMPTY'  | 'CS33402FB03'(!)        = ''              | ''                 | 'CS33402FB03'           | 'R0402'             | '(R0402-0201)'                 | '34K'     | '1%'    | '1/16W'  | 'IO'       | 'RES CHIP 34K 1/16W +-1%(0402)AEC'                 | 'CHIP0402'     | ''          | ''            | '20160121'
 '36'         | '5%'      | '1/16W'  | '0402LF'  | 'CHIP'   | 'CS03602JB02'(!)        = ''              | ''                 | 'CS03602JB02'           | 'R0402'             | '(R0402-0201)'                 | '36'      | '5%'    | '1/16W'  | 'DISCRETE' | 'RES CHIP 36 1/16W +-5%(0402)AEC'                  | 'CHIP0402'     | ''          | ''            | '20160201'
 '36'         | '5%'      | '1/16W'  | '0402LF'  | 'EMPTY'  | 'CS03602JB02'(!)        = ''              | ''                 | 'CS03602JB02'           | 'R0402'             | '(R0402-0201)'                 | '36'      | '5%'    | '1/16W'  | 'IO'       | 'RES CHIP 36 1/16W +-5%(0402)AEC'                  | 'CHIP0402'     | ''          | ''            | '20160201'
 '37.4K'      | '1%'      | '1/16W'  | '0402LF'  | 'CHIP'   | 'CS33742FB06'(!)        = ''              | ''                 | 'CS33742FB06'           | 'R0402'             | '(R0402-0201)'                 | '37.4K'   | '1%'    | '1/16W'  | 'DISCRETE' | 'RES CHIP 37.4K 1/16W +-1%(0402)AEC'               | 'CHIP0402'     | ''          | ''            | '20160201'
 '37.4K'      | '1%'      | '1/16W'  | '0402LF'  | 'EMPTY'  | 'CS33742FB06'(!)        = ''              | ''                 | 'CS33742FB06'           | 'R0402'             | '(R0402-0201)'                 | '37.4K'   | '1%'    | '1/16W'  | 'IO'       | 'RES CHIP 37.4K 1/16W +-1%(0402)AEC'               | 'CHIP0402'     | ''          | ''            | '20160201'
 '0.0003'     | '1%'      | '4W'     | '2725LF'  | 'CHIP'   | 'CS0000FFT04'(!)        = 'End of Design' | 'Comp-Approve'     | 'CS0000FFT04'           | 'R2725'             | '(SMR2725AW)'                  | '0.0003'  | '1%'    | '4W'     | 'DISCRETE' | 'RES CHIP 0.0003 4W +-1%(2725)'                    | 'CHIP2725'     | ''          | ''            | '20160201'
 '0.0003'     | '1%'      | '4W'     | '2725LF'  | 'EMPTY'  | 'CS0000FFT04'(!)        = 'End of Design' | 'Comp-Approve'     | 'CS0000FFT04'           | 'R2725'             | '(SMR2725AW)'                  | '0.0003'  | '1%'    | '4W'     | 'IO'       | 'RES CHIP 0.0003 4W +-1%(2725)'                    | 'CHIP2725'     | ''          | ''            | '20160201'
 '82K'        | '1%'      | '1/8W'   | '0805LF'  | 'CHIP'   | 'CS38204FA00'(!)        = ''              | ''                 | 'CS38204FA00'           | 'R0805'             | '(SMR0805AW)'                  | '82K'     | '1%'    | '1/8W'   | 'DISCRETE' | 'RES CHIP 82K 1/8W +-1%(0805)'                     | 'CHIP0805'     | ''          | ''            | '20160205'
 '82K'        | '1%'      | '1/8W'   | '0805LF'  | 'EMPTY'  | 'CS38204FA00'(!)        = ''              | ''                 | 'CS38204FA00'           | 'R0805'             | '(SMR0805AW)'                  | '82K'     | '1%'    | '1/8W'   | 'IO'       | 'RES CHIP 82K 1/8W +-1%(0805)'                     | 'CHIP0805'     | ''          | ''            | '20160205'
 '665K'       | '0.1%'    | '1/16W'  | '0402LF'  | 'CHIP'   | 'CS46652BB00'(!)        = ''              | ''                 | 'CS46652BB00'           | 'R0402'             | '(R0402-0201)'                 | '665K'    | '0.1%'  | '1/16W'  | 'DISCRETE' | 'RES CHIP 665K 1/16W +-0.1%(0402)'                 | 'CHIP0402'     | ''          | ''            | '20160205'
 '665K'       | '0.1%'    | '1/16W'  | '0402LF'  | 'EMPTY'  | 'CS46652BB00'(!)        = ''              | ''                 | 'CS46652BB00'           | 'R0402'             | '(R0402-0201)'                 | '665K'    | '0.1%'  | '1/16W'  | 'IO'       | 'RES CHIP 665K 1/16W +-0.1%(0402)'                 | 'CHIP0402'     | ''          | ''            | '20160205'
 '4.02'       | '1%'      | '1/16W'  | '0402LF'  | 'CHIP'   | 'CS-4022FB00'(!)        = ''              | ''                 | 'CS-4022FB00'           | 'R0402'             | '(R0402-0201)'                 | '4.02'    | '1%'    | '1/16W'  | 'DISCRETE' | 'RES CHIP 4.02 1/16W +-1%(0402)'                   | 'CHIP0402'     | ''          | ''            | '20160205'
 '4.02'       | '1%'      | '1/16W'  | '0402LF'  | 'EMPTY'  | 'CS-4022FB00'(!)        = ''              | ''                 | 'CS-4022FB00'           | 'R0402'             | '(R0402-0201)'                 | '4.02'    | '1%'    | '1/16W'  | 'IO'       | 'RES CHIP 4.02 1/16W +-1%(0402)'                   | 'CHIP0402'     | ''          | ''            | '20160205'
 '665K'       | '0.1%'    | '1/8W'   | '0805LF'  | 'CHIP'   | 'CS46654BA00'(!)        = ''              | ''                 | 'CS46654BA00'           | 'R0805'             | '(SMR0805AW)'                  | '665K'    | '0.1%'  | '1/8W'   | 'DISCRETE' | 'RES CHIP 665K 1/8W +-0.1%(0805)AEC'               | 'CHIP0805'     | ''          | ''            | '20160303'
 '665K'       | '0.1%'    | '1/8W'   | '0805LF'  | 'EMPTY'  | 'CS46654BA00'(!)        = ''              | ''                 | 'CS46654BA00'           | 'R0805'             | '(SMR0805AW)'                  | '665K'    | '0.1%'  | '1/8W'   | 'IO'       | 'RES CHIP 665K 1/8W +-0.1%(0805)AEC'               | 'CHIP0805'     | ''          | ''            | '20160303'
 '0.001'      | '1%'      | '3W'     | '2512LF'  | 'CHIP'   | 'CS+001DFR00'(!)        = ''              | ''                 | 'CS+001DFR00'           | 'R2512XJ'           | '(SMR2512AW)'                  | '0.001'   | '1%'    | '3W'     | 'DISCRETE' | 'RES CHIP 0.001 3W(+-1%,2512)'                     | 'CHIP2512'     | ''          | ''            | '20160303'
 '0.001'      | '1%'      | '3W'     | '2512LF'  | 'EMPTY'  | 'CS+001DFR00'(!)        = ''              | ''                 | 'CS+001DFR00'           | 'R2512XJ'           | '(SMR2512AW)'                  | '0.001'   | '1%'    | '3W'     | 'IO'       | 'RES CHIP 0.001 3W(+-1%,2512)'                     | 'CHIP2512'     | ''          | ''            | '20160303'
 '0.002'      | '1%'      | '1W'     | '1206LF'  | 'CHIP'   | 'CS+0028F201'(!)        = ''              | ''                 | 'CS+0028F201'           | 'R1206XA'           | '(SMR1206AW)'                  | '0.002'   | '1%'    | '1W'     | 'DISCRETE' | 'RES CHIP 0.002 1W +-1%(1206)'                     | 'CHIP1206'     | ''          | ''            | '20160307'
 '0.002'      | '1%'      | '1W'     | '1206LF'  | 'EMPTY'  | 'CS+0028F201'(!)        = ''              | ''                 | 'CS+0028F201'           | 'R1206XA'           | '(SMR1206AW)'                  | '0.002'   | '1%'    | '1W'     | 'IO'       | 'RES CHIP 0.002 1W +-1%(1206)'                     | 'CHIP1206'     | ''          | ''            | '20160307'
 '820'        | '1%'      | '1/4W'   | '0805LF'  | 'CHIP'   | 'CS18206FA00'(!)        = ''              | ''                 | 'CS18206FA00'           | 'R0805'             | '(SMR0805AW)'                  | '820'     | '1%'    | '1/4W'   | 'DISCRETE' | 'RES CHIP 820 1/4W +-1%(0805)'                     | 'CHIP0805'     | ''          | ''            | '20160310'
 '820'        | '1%'      | '1/4W'   | '0805LF'  | 'EMPTY'  | 'CS18206FA00'(!)        = ''              | ''                 | 'CS18206FA00'           | 'R0805'             | '(SMR0805AW)'                  | '820'     | '1%'    | '1/4W'   | 'IO'       | 'RES CHIP 820 1/4W +-1%(0805)'                     | 'CHIP0805'     | ''          | ''            | '20160310'
 '887'        | '1%'      | '1/16W'  | 'R0402LF' | 'CHIP'   | 'CS18872FB01'(!)        = 'End of Design' | 'Comp-Approve'     | 'CS18872FB01'           | 'R0402'             | '(R0402-0201)'                 | '887'     | '1%'    | '1/16W'  | 'DISCRETE' | 'RES CHIP 887 1/16W +-1%(0402)'                    | 'CHIP0402'     | ''          | ''            | '20160314'
 '887'        | '1%'      | '1/16W'  | 'R0402LF' | 'EMPTY'  | 'CS18872FB01'(!)        = 'End of Design' | 'Comp-Approve'     | 'CS18872FB01'           | 'R0402'             | '(R0402-0201)'                 | '887'     | '1%'    | '1/16W'  | 'IO'       | 'RES CHIP 887 1/16W +-1%(0402)'                    | 'CHIP0402'     | ''          | ''            | '20160314'
 '2.2'        | '1%'      | '1/10W'  | '0603LF'  | 'CHIP'   | 'CS-2203F901'(!)        = ''              | ''                 | 'CS-2203F901'           | 'R0603'             | '(SMR0603AW)'                  | '2.2'     | '1%'    | '1/10W'  | 'DISCRETE' | 'RES CHIP 2.2 1/10W +-1%(0603)AEC'                 | 'CHIPR0603'    | ''          | ''            | '20160315'
 '2.2'        | '1%'      | '1/10W'  | '0603LF'  | 'EMPTY'  | 'CS-2203F901'(!)        = ''              | ''                 | 'CS-2203F901'           | 'R0603'             | '(SMR0603AW)'                  | '2.2'     | '1%'    | '1/10W'  | 'IO'       | 'RES CHIP 2.2 1/10W +-1%(0603)AEC'                 | 'CHIPR0603'    | ''          | ''            | '20160315'
 '27'         | '1%'      | '1/16W'  | '0402LF'  | 'CHIP'   | 'CS02702FB11'(!)        = 'End of Design' | 'Comp-Approve'     | 'CS02702FB11'           | 'R0402'             | '(R0402-0201)'                 | '27'      | '1%'    | '1/16W'  | 'DISCRETE' | 'RES CHIP 27 1/16W +-1%(0402)'                     | 'CHIPR0402'    | ''          | ''            | '20160317'
 '27'         | '1%'      | '1/16W'  | '0402LF'  | 'EMPTY'  | 'CS02702FB11'(!)        = 'End of Design' | 'Comp-Approve'     | 'CS02702FB11'           | 'R0402'             | '(R0402-0201)'                 | '27'      | '1%'    | '1/16W'  | 'IO'       | 'RES CHIP 27 1/16W +-1%(0402)'                     | 'CHIPR0402'    | ''          | ''            | '20160317'
 '43K'        | '1%'      | '1/8W'   | '0805LF'  | 'CHIP'   | 'CS34304FA00'(!)        = ''              | ''                 | 'CS34304FA00'           | 'R0805'             | '(SMR0805AW)'                  | '43K'     | '1%'    | '1/8W'   | 'DISCRETE' | 'RES CHIP 43K 1/8W +-1% (0805)'                    | 'CHIPR0805'    | ''          | ''            | '20160321'
 '43K'        | '1%'      | '1/8W'   | '0805LF'  | 'EMPTY'  | 'CS34304FA00'(!)        = ''              | ''                 | 'CS34304FA00'           | 'R0805'             | '(SMR0805AW)'                  | '43K'     | '1%'    | '1/8W'   | 'IO'       | 'RES CHIP 43K 1/8W +-1% (0805)'                    | 'CHIPR0805'    | ''          | ''            | '20160321'
 '8.2'        | '5%'      | '1W'     | '2512LF'  | 'CHIP'   | 'CS00828JR00'(!)        = ''              | ''                 | 'CS00828JR00'           | 'R2512XK'           | '(SMR2512AW)'                  | '8.2'     | '5%'    | '1W'     | 'DISCRETE' | 'RES CHIP 8.2 1W +-5%(2512)'                       | 'CHIPR2512'    | ''          | ''            | '20160323'
 '8.2'        | '5%'      | '1W'     | '2512LF'  | 'EMPTY'  | 'CS00828JR00'(!)        = ''              | ''                 | 'CS00828JR00'           | 'R2512XK'           | '(SMR2512AW)'                  | '8.2'     | '5%'    | '1W'     | 'IO'       | 'RES CHIP 8.2 1W +-5%(2512)'                       | 'CHIPR2512'    | ''          | ''            | '20160323'
 '2.7M'       | '1%'      | '1/8W'   | '0805LF'  | 'CHIP'   | 'CS52704FA00'(!)        = ''              | ''                 | 'CS52704FA00'           | 'R0805'             | '(SMR0805AW)'                  | '2.7M'    | '1%'    | '1/8W'   | 'DISCRETE' | 'RES CHIP 2.7M(+-1%,1/8W,0805)TAI'                 | 'CHIPR0805'    | ''          | ''            | '20160325'
 '2.7M'       | '1%'      | '1/8W'   | '0805LF'  | 'EMPTY'  | 'CS52704FA00'(!)        = ''              | ''                 | 'CS52704FA00'           | 'R0805'             | '(SMR0805AW)'                  | '2.7M'    | '1%'    | '1/8W'   | 'IO'       | 'RES CHIP 2.7M(+-1%,1/8W,0805)TAI'                 | 'CHIPR0805'    | ''          | ''            | '20160325'
 '9.31K'      | '0.1%'    | '1/16W'  | '0402LF'  | 'CHIP'   | 'CS29312BB00'(!)        = 'End of Design' | 'Comp-Approve'     | 'CS29312BB00'           | 'R0402'             | '(R0402-0201)'                 | '9.31K'   | '0.1%'  | '1/16W'  | 'DISCRETE' | 'RES CHIP 9.31K 1/16W +-0.1%(0402)EF'              | 'CHIPR0402'    | ''          | ''            | '20160329'
 '9.31K'      | '0.1%'    | '1/16W'  | '0402LF'  | 'EMPTY'  | 'CS29312BB00'(!)        = 'End of Design' | 'Comp-Approve'     | 'CS29312BB00'           | 'R0402'             | '(R0402-0201)'                 | '9.31K'   | '0.1%'  | '1/16W'  | 'IO'       | 'RES CHIP 9.31K 1/16W +-0.1%(0402)EF'              | 'CHIPR0402'    | ''          | ''            | '20160329'
 '0.001'      | '1%'      | '1W'     | '2512LF'  | 'CHIP'   | 'CS+0018FR05'(!)        = ''              | ''                 | 'CS+0018FR05'           | 'R2512XF'           | '(SMR2512AW)'                  | '0.001'   | '1%'    | '1W'     | 'DISCRETE' | 'RES CHIP 0.001(+-1%,1W, 2512)TAI'                 | 'CHIPR2512'    | ''          | ''            | '20160411'
 '0.001'      | '1%'      | '1W'     | '2512LF'  | 'EMPTY'  | 'CS+0018FR05'(!)        = ''              | ''                 | 'CS+0018FR05'           | 'R2512XF'           | '(SMR2512AW)'                  | '0.001'   | '1%'    | '1W'     | 'IO'       | 'RES CHIP 0.001(+-1%,1W, 2512)TAI'                 | 'CHIPR2512'    | ''          | ''            | '20160411'
 '0.002'      | '1%'      | '1W'     | '2512LF'  | 'CHIP'   | 'CS+0028FR02'(!)        = ''              | ''                 | 'CS+0028FR02'           | 'R2512XF'           | '(SMR2512AW)'                  | '0.002'   | '1%'    | '1W'     | 'DISCRETE' | 'RES CHIP 0.002( +-1%,1W,2512)TAI'                 | 'CHIPR2512'    | ''          | ''            | '20160411'
 '0.002'      | '1%'      | '1W'     | '2512LF'  | 'EMPTY'  | 'CS+0028FR02'(!)        = ''              | ''                 | 'CS+0028FR02'           | 'R2512XF'           | '(SMR2512AW)'                  | '0.002'   | '1%'    | '1W'     | 'IO'       | 'RES CHIP 0.002( +-1%,1W,2512)TAI'                 | 'CHIPR2512'    | ''          | ''            | '20160411'
 '0.0005'     | '1%'      | '3W'     | '2512LF'  | 'CHIP'   | 'CS0000DFR04'(!)        = ''              | ''                 | 'CS0000DFR04'           | 'R2512XF'           | '(SMR2512AW)'                  | '0.0005'  | '1%'    | '3W'     | 'DISCRETE' | 'RES CHIP 0.0005(+-1%,3W,2512)TAI'                 | 'CHIPR2512'    | ''          | ''            | '20160411'
 '0.0005'     | '1%'      | '3W'     | '2512LF'  | 'EMPTY'  | 'CS0000DFR04'(!)        = ''              | ''                 | 'CS0000DFR04'           | 'R2512XF'           | '(SMR2512AW)'                  | '0.0005'  | '1%'    | '3W'     | 'IO'       | 'RES CHIP 0.0005(+-1%,3W,2512)TAI'                 | 'CHIPR2512'    | ''          | ''            | '20160411'
 '2.26K'      | '0.1%'    | '1/16W'  | '0402LF'  | 'CHIP'   | 'CS22262BB00'(!)        = ''              | ''                 | 'CS22262BB00'           | 'R0402'             | '(R0402-0201)'                 | '2.26K'   | '0.1%'  | '1/16W'  | 'DISCRETE' | 'RES CHIP 2.26K 1/16W +-0.1%(0402)'                | 'CHIPR0402'    | ''          | ''            | '20160415'
 '2.26K'      | '0.1%'    | '1/16W'  | '0402LF'  | 'EMPTY'  | 'CS22262BB00'(!)        = ''              | ''                 | 'CS22262BB00'           | 'R0402'             | '(R0402-0201)'                 | '2.26K'   | '0.1%'  | '1/16W'  | 'IO'       | 'RES CHIP 2.26K 1/16W +-0.1%(0402)'                | 'CHIPR0402'    | ''          | ''            | '20160415'
 '0.008'      | '1%'      | '3W'     | '2512LF'  | 'CHIP'   | 'CS+008DFR02'(!)        = ''              | ''                 | 'CS+008DFR02'           | 'R2512XL'           | '(SMR2512AW)'                  | '0.008'   | '1%'    | '3W'     | 'DISCRETE' | 'RES CHIP 0.008(+-1%,3W,2512)TAI'                  | 'CHIPR2512'    | ''          | ''            | '20160419'
 '0.008'      | '1%'      | '3W'     | '2512LF'  | 'EMPTY'  | 'CS+008DFR02'(!)        = ''              | ''                 | 'CS+008DFR02'           | 'R2512XL'           | '(SMR2512AW)'                  | '0.008'   | '1%'    | '3W'     | 'IO'       | 'RES CHIP 0.008(+-1%,3W,2512)TAI'                  | 'CHIPR2512'    | ''          | ''            | '20160419'
 '0.02'       | '1%'      | '1/2W'   | '0805LF'  | 'CHIP'   | 'CS+0207FA00'(!)        = 'End of Design' | 'Comp-Approve'     | 'CS+0207FA00'           | 'R0805XA'           | '(SMR0805AW)'                  | '0.02'    | '1%'    | '1/2W'   | 'DISCRETE' | 'RES CHIP 0.02 1/2W +-1% (0805)'                   | 'CHIPR0805'    | ''          | ''            | '20160420'
 '0.02'       | '1%'      | '1/2W'   | '0805LF'  | 'EMPTY'  | 'CS+0207FA00'(!)        = 'End of Design' | 'Comp-Approve'     | 'CS+0207FA00'           | 'R0805XA'           | '(SMR0805AW)'                  | '0.02'    | '1%'    | '1/2W'   | 'IO'       | 'RES CHIP 0.02 1/2W +-1% (0805)'                   | 'CHIPR0805'    | ''          | ''            | '20160420'
 '787K'       | '1%'      | '1/16W'  | '0402LF'  | 'CHIP'   | 'CS47872FB00'(!)        = 'End of Design' | 'Comp-Approve'     | 'CS47872FB00'           | 'R0402'             | '(R0402-0201)'                 | '787K'    | '1%'    | '1/16W'  | 'DISCRETE' | 'RES CHIP 787K 1/16W +-1%(0402)'                   | 'CHIPR0402'    | ''          | ''            | '20160421'
 '787K'       | '1%'      | '1/16W'  | '0402LF'  | 'EMPTY'  | 'CS47872FB00'(!)        = 'End of Design' | 'Comp-Approve'     | 'CS47872FB00'           | 'R0402'             | '(R0402-0201)'                 | '787K'    | '1%'    | '1/16W'  | 'IO'       | 'RES CHIP 787K 1/16W +-1%(0402)'                   | 'CHIPR0402'    | ''          | ''            | '20160421'
 '7.5'        | '1%'      | '2W'     | '2512LF'  | 'CHIP'   | 'CS-750AFR01'(!)        = ''              | ''                 | 'CS-750AFR01'           | 'R2512XK'           | '(SMR2512AW)'                  | '7.5'     | '1%'    | '2W'     | 'DISCRETE' | 'RES CHIP 7.5 2W +-1%(2512)'                       | 'CHIPR2512'    | ''          | ''            | '20160426'
 '7.5'        | '1%'      | '2W'     | '2512LF'  | 'EMPTY'  | 'CS-750AFR01'(!)        = ''              | ''                 | 'CS-750AFR01'           | 'R2512XK'           | '(SMR2512AW)'                  | '7.5'     | '1%'    | '2W'     | 'IO'       | 'RES CHIP 7.5 2W +-1%(2512)'                       | 'CHIPR2512'    | ''          | ''            | '20160426'
 '0.003'      | '1%'      | '4W'     | '2725LF'  | 'CHIP'   | 'CS+003FFT00'(!)        = 'End of Design' | 'Comp-Approve'     | 'CS+003FFT00'           | 'R2725'             | '(SMR2725AW)'                  | '0.003'   | '1%'    | '4W'     | 'DISCRETE' | 'RES CHIP 0.003 4W +-1% (2725)EF'                  | 'CHIPR2725'    | ''          | ''            | '20160426'
 '0.003'      | '1%'      | '4W'     | '2725LF'  | 'EMPTY'  | 'CS+003FFT00'(!)        = 'End of Design' | 'Comp-Approve'     | 'CS+003FFT00'           | 'R2725'             | '(SMR2725AW)'                  | '0.003'   | '1%'    | '4W'     | 'IO'       | 'RES CHIP 0.003 4W +-1% (2725)EF'                  | 'CHIPR2725'    | ''          | ''            | '20160426'
 '3.3'        | '1%'      | '1/10W'  | '0603LF'  | 'CHIP'   | 'CS-3303F901'(!)        = ''              | ''                 | 'CS-3303F901'           | 'R0603'             | '(SMR0603AW)'                  | '3.3'     | '1%'    | '1/10W'  | 'DISCRETE' | 'RES CHIP 3.3 1/10W +-1%(0603)AEC'                 | 'CHIPR0603'    | ''          | ''            | '20160503'
 '3.3'        | '1%'      | '1/10W'  | '0603LF'  | 'EMPTY'  | 'CS-3303F901'(!)        = ''              | ''                 | 'CS-3303F901'           | 'R0603'             | '(SMR0603AW)'                  | '3.3'     | '1%'    | '1/10W'  | 'IO'       | 'RES CHIP 3.3 1/10W +-1%(0603)AEC'                 | 'CHIPR0603'    | ''          | ''            | '20160503'
 '3.3'        | '1%'      | '1/16W'  | '0402LF'  | 'CHIP'   | 'CS-3302FB02'(!)        = ''              | ''                 | 'CS-3302FB02'           | 'R0402'             | '(R0402-0201)'                 | '3.3'     | '1%'    | '1/16W'  | 'DISCRETE' | 'RES CHIP 3.3 1/16W +-1%(0402)AEC'                 | 'CHIPR0402'    | ''          | ''            | '20160503'
 '3.3'        | '1%'      | '1/16W'  | '0402LF'  | 'EMPTY'  | 'CS-3302FB02'(!)        = ''              | ''                 | 'CS-3302FB02'           | 'R0402'             | '(R0402-0201)'                 | '3.3'     | '1%'    | '1/16W'  | 'IO'       | 'RES CHIP 3.3 1/16W +-1%(0402)AEC'                 | 'CHIPR0402'    | ''          | ''            | '20160503'
 '2.2'        | '1%'      | '1/4W'   | '1206LF'  | 'CHIP'   | 'CS-2206F201'(!)        = ''              | ''                 | 'CS-2206F201'           | 'R1206'             | '(SMR1206AW)'                  | '2.2'     | '1%'    | '1/4W'   | 'DISCRETE' | 'RES CHIP 2.2 1/4W +-1%(1206)AEC'                  | 'CHIPR1206'    | ''          | ''            | '20160503'
 '2.2'        | '1%'      | '1/4W'   | '1206LF'  | 'EMPTY'  | 'CS-2206F201'(!)        = ''              | ''                 | 'CS-2206F201'           | 'R1206'             | '(SMR1206AW)'                  | '2.2'     | '1%'    | '1/4W'   | 'IO'       | 'RES CHIP 2.2 1/4W +-1%(1206)AEC'                  | 'CHIPR1206'    | ''          | ''            | '20160503'
 '0'          | ''        | '1/8W'   | '0805LF'  | 'CHIP'   | 'CS00004TA02'(!)        = 'End of Design' | 'Comp-Approve'     | 'CS00004TA02'           | 'R0805'             | '(SMR0805AW)'                  | '0'       | ''      | '1/8W'   | 'DISCRETE' | 'RESISTOR CHIP 0 1/8W(0805)'                       | 'CHIPR0805'    | ''          | ''            | '20160511'
 '0'          | ''        | '1/8W'   | '0805LF'  | 'EMPTY'  | 'CS00004TA02'(!)        = 'End of Design' | 'Comp-Approve'     | 'CS00004TA02'           | 'R0805'             | '(SMR0805AW)'                  | '0'       | ''      | '1/8W'   | 'IO'       | 'RESISTOR CHIP 0 1/8W(0805)'                       | 'CHIPR0805'    | ''          | ''            | '20160511'
 '825K'       | '1%'      | '1/20W'  | '0201LF'  | 'CHIP'   | 'CS48251FE00'(!)        = ''              | ''                 | 'CS48251FE00'           | 'R0201'             | '(SMR0201AW)'                  | '825K'    | '1%'    | '1/20W'  | 'DISCRETE' | 'RESISTOR CHIP 825K 1/20W+-1%(0201)'               | 'CHIPR0201'    | ''          | ''            | '20160512'
 '825K'       | '1%'      | '1/20W'  | '0201LF'  | 'EMPTY'  | 'CS48251FE00'(!)        = ''              | ''                 | 'CS48251FE00'           | 'R0201'             | '(SMR0201AW)'                  | '825K'    | '1%'    | '1/20W'  | 'IO'       | 'RESISTOR CHIP 825K 1/20W+-1%(0201)'               | 'CHIPR0201'    | ''          | ''            | '20160512'
 '220'        | '5%'      | '1/10W'  | '0603LF'  | 'CHIP'   | 'CS12203J947'(!)        = ''              | ''                 | 'CS12203J947'           | 'R0603'             | '(SMR0603AW)'                  | '220'     | '5%'    | '1/10W'  | 'DISCRETE' | 'RES CHIP 220 1/10W +-5%(0603) EP'                 | 'CHIPR0603'    | ''          | ''            | '20160616'
 '220'        | '5%'      | '1/10W'  | '0603LF'  | 'EMPTY'  | 'CS12203J947'(!)        = ''              | ''                 | 'CS12203J947'           | 'R0603'             | '(SMR0603AW)'                  | '220'     | '5%'    | '1/10W'  | 'IO'       | 'RES CHIP 220 1/10W +-5%(0603) EP'                 | 'CHIPR0603'    | ''          | ''            | '20160616'
 '267K'       | '1%'      | '1/16W'  | '0402LF'  | 'CHIP'   | 'CS42672FB16'(!)        = 'End of Design' | 'Comp-Approve'     | 'CS42672FB16'           | 'R0402'             | '(R0402-0201)'                 | '267K'    | '1%'    | '1/16W'  | 'DISCRETE' | 'RES CHIP 267K 1/16W +-1%(0402)'                   | 'CHIPR0402'    | ''          | ''            | '20160617'
 '267K'       | '1%'      | '1/16W'  | '0402LF'  | 'EMPTY'  | 'CS42672FB16'(!)        = 'End of Design' | 'Comp-Approve'     | 'CS42672FB16'           | 'R0402'             | '(R0402-0201)'                 | '267K'    | '1%'    | '1/16W'  | 'IO'       | 'RES CHIP 267K 1/16W +-1%(0402)'                   | 'CHIPR0402'    | ''          | ''            | '20160617'
 '5.9K'       | '0.1%'    | '1/16W'  | '0402LF'  | 'CHIP'   | 'CS25902BB02'(!)        = 'Non-Preferred' | 'End of Life'      | 'CS25902BB02'           | 'R0402_EOL'         | '(R0402-0201)'                 | '5.9K'    | '0.1%'  | '1/16W'  | 'DISCRETE' | 'RES CHIP 5.9K 1/16W +-0.1% (0402)DAL_AEC'         | 'CHIPR0402'    | ''          | ''            | '20160628'
 '5.9K'       | '0.1%'    | '1/16W'  | '0402LF'  | 'EMPTY'  | 'CS25902BB02'(!)        = 'Non-Preferred' | 'End of Life'      | 'CS25902BB02'           | 'R0402_EOL'         | '(R0402-0201)'                 | '5.9K'    | '0.1%'  | '1/16W'  | 'IO'       | 'RES CHIP 5.9K 1/16W +-0.1% (0402)DAL_AEC'         | 'CHIPR0402'    | ''          | ''            | '20160628'
 '10K'        | '0.1%'    | '1/16W'  | '0402LF'  | 'CHIP'   | 'CS31002BB07'(!)        = 'Non-Preferred' | 'End of Life'      | 'CS31002BB07'           | 'R0402_EOL'         | '(R0402-0201)'                 | '10K'     | '0.1%'  | '1/16W'  | 'DISCRETE' | 'RES CHIP 10K 1/16W +-0.1%(0402)DAL_AEC'           | 'CHIPR0402'    | ''          | ''            | '20160628'
 '10K'        | '0.1%'    | '1/16W'  | '0402LF'  | 'EMPTY'  | 'CS31002BB07'(!)        = 'Non-Preferred' | 'End of Life'      | 'CS31002BB07'           | 'R0402_EOL'         | '(R0402-0201)'                 | '10K'     | '0.1%'  | '1/16W'  | 'IO'       | 'RES CHIP 10K 1/16W +-0.1%(0402)DAL_AEC'           | 'CHIPR0402'    | ''          | ''            | '20160628'
 '100K'       | '0.1%'    | '1/16W'  | '0402LF'  | 'CHIP'   | 'CS41002BB03'(!)        = 'Non-Preferred' | 'End of Life'      | 'CS41002BB03'           | 'R0402_EOL'         | '(R0402-0201)'                 | '100K'    | '0.1%'  | '1/16W'  | 'DISCRETE' | 'RES CHIP 100K 1/16W +-0.1%(0402)DAL_AEC'          | 'CHIPR0402'    | ''          | ''            | '20160628'
 '100K'       | '0.1%'    | '1/16W'  | '0402LF'  | 'EMPTY'  | 'CS41002BB03'(!)        = 'Non-Preferred' | 'End of Life'      | 'CS41002BB03'           | 'R0402_EOL'         | '(R0402-0201)'                 | '100K'    | '0.1%'  | '1/16W'  | 'IO'       | 'RES CHIP 100K 1/16W +-0.1%(0402)DAL_AEC'          | 'CHIPR0402'    | ''          | ''            | '20160628'
 '249'        | '0.1%'    | '1/16W'  | '0402LF'  | 'CHIP'   | 'CS12492BB04'(!)        = 'Non-Preferred' | 'End of Life'      | 'CS12492BB04'           | 'R0402_EOL'         | '(R0402-0201)'                 | '249'     | '0.1%'  | '1/16W'  | 'DISCRETE' | 'RES CHIP 249 1/16W +-0.1%(0402)DAL_AEC'           | 'CHIPR0402'    | ''          | ''            | '20160628'
 '249'        | '0.1%'    | '1/16W'  | '0402LF'  | 'EMPTY'  | 'CS12492BB04'(!)        = 'Non-Preferred' | 'End of Life'      | 'CS12492BB04'           | 'R0402_EOL'         | '(R0402-0201)'                 | '249'     | '0.1%'  | '1/16W'  | 'IO'       | 'RES CHIP 249 1/16W +-0.1%(0402)DAL_AEC'           | 'CHIPR0402'    | ''          | ''            | '20160628'
 '15'         | '5%'      | '1/16W'  | '0402LF'  | 'CHIP'   | 'CS01502JB06'(!)        = ''              | ''                 | 'CS01502JB06'           | 'R0402'             | '(R0402-0201)'                 | '15'      | '5%'    | '1/16W'  | 'DISCRETE' | 'RES CHIP 15 1/16W +-5%(0402)DAL_AEC'              | 'CHIPR0402'    | ''          | ''            | '20160628'
 '15'         | '5%'      | '1/16W'  | '0402LF'  | 'EMPTY'  | 'CS01502JB06'(!)        = ''              | ''                 | 'CS01502JB06'           | 'R0402'             | '(R0402-0201)'                 | '15'      | '5%'    | '1/16W'  | 'IO'       | 'RES CHIP 15 1/16W +-5%(0402)DAL_AEC'              | 'CHIPR0402'    | ''          | ''            | '20160628'
 '10'         | '5%'      | '1/16W'  | '0402LF'  | 'CHIP'   | 'CS01002JB08'(!)        = ''              | ''                 | 'CS01002JB08'           | 'R0402'             | '(R0402-0201)'                 | '10'      | '5%'    | '1/16W'  | 'DISCRETE' | 'RES CHIP 10 1/16W +5%(0402)DAL_AEC'               | 'CHIPR0402'    | ''          | ''            | '20160628'
 '10'         | '5%'      | '1/16W'  | '0402LF'  | 'EMPTY'  | 'CS01002JB08'(!)        = ''              | ''                 | 'CS01002JB08'           | 'R0402'             | '(R0402-0201)'                 | '10'      | '5%'    | '1/16W'  | 'IO'       | 'RES CHIP 10 1/16W +5%(0402)DAL_AEC'               | 'CHIPR0402'    | ''          | ''            | '20160628'
 '200'        | '0.1%'    | '1/16W'  | '0402LF'  | 'CHIP'   | 'CS12002BB02'(!)        = 'Non-Preferred' | 'End of Life'      | 'CS12002BB02'           | 'R0402_EOL'         | '(R0402-0201)'                 | '200'     | '0.1%'  | '1/16W'  | 'DISCRETE' | 'RES CHIP 200 1/16W +0.1% (0402)DAL_AEC'           | 'CHIPR0402'    | ''          | ''            | '20160629'
 '200'        | '0.1%'    | '1/16W'  | '0402LF'  | 'EMPTY'  | 'CS12002BB02'(!)        = 'Non-Preferred' | 'End of Life'      | 'CS12002BB02'           | 'R0402_EOL'         | '(R0402-0201)'                 | '200'     | '0.1%'  | '1/16W'  | 'IO'       | 'RES CHIP 200 1/16W +0.1% (0402)DAL_AEC'           | 'CHIPR0402'    | ''          | ''            | '20160629'
 '1'          | '5%'      | '1/16W'  | '0402LF'  | 'CHIP'   | 'CS-1002JB07'(!)        = ''              | ''                 | 'CS-1002JB07'           | 'R0402'             | '(R0402-0201)'                 | '1'       | '5%'    | '1/16W'  | 'DISCRETE' | 'RES CHIP 1 1/16W +-5%(0402) DAL_AEC'              | 'CHIPR0402'    | ''          | ''            | '20160629'
 '1'          | '5%'      | '1/16W'  | '0402LF'  | 'EMPTY'  | 'CS-1002JB07'(!)        = ''              | ''                 | 'CS-1002JB07'           | 'R0402'             | '(R0402-0201)'                 | '1'       | '5%'    | '1/16W'  | 'IO'       | 'RES CHIP 1 1/16W +-5%(0402) DAL_AEC'              | 'CHIPR0402'    | ''          | ''            | '20160629'
 '100'        | '0.1%'    | '1/16W'  | '0402LF'  | 'CHIP'   | 'CS11002BB03'(!)        = 'Non-Preferred' | 'End of Life'      | 'CS11002BB03'           | 'R0402_EOL'         | '(R0402-0201)'                 | '100'     | '0.1%'  | '1/16W'  | 'DISCRETE' | 'RES CHIP 100 1/16W +-0.1%(0402) DAL_AEC'          | 'CHIPR0402'    | ''          | ''            | '20160629'
 '100'        | '0.1%'    | '1/16W'  | '0402LF'  | 'EMPTY'  | 'CS11002BB03'(!)        = 'Non-Preferred' | 'End of Life'      | 'CS11002BB03'           | 'R0402_EOL'         | '(R0402-0201)'                 | '100'     | '0.1%'  | '1/16W'  | 'IO'       | 'RES CHIP 100 1/16W +-0.1%(0402) DAL_AEC'          | 'CHIPR0402'    | ''          | ''            | '20160629'
 '220'        | '5%'      | '1/16W'  | '0402LF'  | 'CHIP'   | 'CS12202JB05'(!)        = ''              | ''                 | 'CS12202JB05'           | 'R0402'             | '(R0402-0201)'                 | '220'     | '5%'    | '1/16W'  | 'DISCRETE' | 'RES CHIP 220 1/16W +-5%(0402)DAL_AEC'             | 'CHIPR0402'    | ''          | ''            | '20160629'
 '220'        | '5%'      | '1/16W'  | '0402LF'  | 'EMPTY'  | 'CS12202JB05'(!)        = ''              | ''                 | 'CS12202JB05'           | 'R0402'             | '(R0402-0201)'                 | '220'     | '5%'    | '1/16W'  | 'IO'       | 'RES CHIP 220 1/16W +-5%(0402)DAL_AEC'             | 'CHIPR0402'    | ''          | ''            | '20160629'
 '0'          | ''        | '1/16W'  | '0402LF'  | 'CHIP'   | 'CS00002TB01'(!)        = ''              | ''                 | 'CS00002TB01'           | 'R0402'             | '(R0402-0201)'                 | '0'       | ''      | '1/16W'  | 'DISCRETE' | 'RES CHIP 0 1/16W (0402) DAL_AEC'                  | 'CHIPR0402'    | ''          | ''            | '20160630'
 '0'          | ''        | '1/16W'  | '0402LF'  | 'EMPTY'  | 'CS00002TB01'(!)        = ''              | ''                 | 'CS00002TB01'           | 'R0402'             | '(R0402-0201)'                 | '0'       | ''      | '1/16W'  | 'IO'       | 'RES CHIP 0 1/16W (0402) DAL_AEC'                  | 'CHIPR0402'    | ''          | ''            | '20160630'
 '10'         | '1%'      | '1/16W'  | '0402LF'  | 'CHIP'   | 'CS01002FB13'(!)        = ''              | ''                 | 'CS01002FB13'           | 'R0402'             | '(R0402-0201)'                 | '10'      | '1%'    | '1/16W'  | 'DISCRETE' | 'RES CHIP 10 1/16W +-1%(0402) DAL_AEC'             | 'CHIPR0402'    | ''          | ''            | '20160630'
 '10'         | '1%'      | '1/16W'  | '0402LF'  | 'EMPTY'  | 'CS01002FB13'(!)        = ''              | ''                 | 'CS01002FB13'           | 'R0402'             | '(R0402-0201)'                 | '10'      | '1%'    | '1/16W'  | 'IO'       | 'RES CHIP 10 1/16W +-1%(0402) DAL_AEC'             | 'CHIPR0402'    | ''          | ''            | '20160630'
 '15'         | '1%'      | '1/16W'  | '0402LF'  | 'CHIP'   | 'CS01502FB05'(!)        = ''              | ''                 | 'CS01502FB05'           | 'R0402'             | '(R0402-0201)'                 | '15'      | '1%'    | '1/16W'  | 'DISCRETE' | 'RES CHIP 15 1/16W +-1%(0402)DAL_AEC'              | 'CHIPR0402'    | ''          | ''            | '20160630'
 '15'         | '1%'      | '1/16W'  | '0402LF'  | 'EMPTY'  | 'CS01502FB05'(!)        = ''              | ''                 | 'CS01502FB05'           | 'R0402'             | '(R0402-0201)'                 | '15'      | '1%'    | '1/16W'  | 'IO'       | 'RES CHIP 15 1/16W +-1%(0402)DAL_AEC'              | 'CHIPR0402'    | ''          | ''            | '20160630'
 '21'         | '1%'      | '1/16W'  | '0402LF'  | 'CHIP'   | 'CS02102FB05'(!)        = ''              | ''                 | 'CS02102FB05'           | 'R0402'             | '(R0402-0201)'                 | '21'      | '1%'    | '1/16W'  | 'DISCRETE' | 'RES CHIP 21 1/16W +-1%(0402)DAL_AEC'              | 'CHIPR0402'    | ''          | ''            | '20160630'
 '21'         | '1%'      | '1/16W'  | '0402LF'  | 'EMPTY'  | 'CS02102FB05'(!)        = ''              | ''                 | 'CS02102FB05'           | 'R0402'             | '(R0402-0201)'                 | '21'      | '1%'    | '1/16W'  | 'IO'       | 'RES CHIP 21 1/16W +-1%(0402)DAL_AEC'              | 'CHIPR0402'    | ''          | ''            | '20160630'
 '22'         | '1%'      | '1/16W'  | '0402LF'  | 'CHIP'   | 'CS02202FB05'(!)        = ''              | ''                 | 'CS02202FB05'           | 'R0402'             | '(R0402-0201)'                 | '22'      | '1%'    | '1/16W'  | 'DISCRETE' | 'RES CHIP 22 1/16W +-1%(0402)DAL_AEC'              | 'CHIPR0402'    | ''          | ''            | '20160630'
 '22'         | '1%'      | '1/16W'  | '0402LF'  | 'EMPTY'  | 'CS02202FB05'(!)        = ''              | ''                 | 'CS02202FB05'           | 'R0402'             | '(R0402-0201)'                 | '22'      | '1%'    | '1/16W'  | 'IO'       | 'RES CHIP 22 1/16W +-1%(0402)DAL_AEC'              | 'CHIPR0402'    | ''          | ''            | '20160630'
 '27.4'       | '1%'      | '1/16W'  | '0402LF'  | 'CHIP'   | 'CS02742FB05'(!)        = ''              | ''                 | 'CS02742FB05'           | 'R0402'             | '(R0402-0201)'                 | '27.4'    | '1%'    | '1/16W'  | 'DISCRETE' | 'RES CHIP 27.4 1/16W +-1%(0402)DAL_AEC'            | 'CHIPR0402'    | ''          | ''            | '20160630'
 '27.4'       | '1%'      | '1/16W'  | '0402LF'  | 'EMPTY'  | 'CS02742FB05'(!)        = ''              | ''                 | 'CS02742FB05'           | 'R0402'             | '(R0402-0201)'                 | '27.4'    | '1%'    | '1/16W'  | 'IO'       | 'RES CHIP 27.4 1/16W +-1%(0402)DAL_AEC'            | 'CHIPR0402'    | ''          | ''            | '20160630'
 '0.001'      | '1%'      | '1W'     | '2512LF'  | 'CHIP'   | 'CS+0018FR04'(!)        = ''              | ''                 | 'CS+0018FR04'           | 'R2512A'            | '(SMR2512AW)'                  | '0.001'   | '1%'    | '1W'     | 'DISCRETE' | 'RES CHIP 0.001 1W +-1% (2512)'                    | 'CHIPR2512'    | ''          | ''            | '20160705'
 '0.001'      | '1%'      | '1W'     | '2512LF'  | 'EMPTY'  | 'CS+0018FR04'(!)        = ''              | ''                 | 'CS+0018FR04'           | 'R2512A'            | '(SMR2512AW)'                  | '0.001'   | '1%'    | '1W'     | 'IO'       | 'RES CHIP 0.001 1W +-1% (2512)'                    | 'CHIPR2512'    | ''          | ''            | '20160705'
 '20'         | '1%'      | '1/16W'  | '0402LF'  | 'CHIP'   | 'CS02002FB05'(!)        = ''              | ''                 | 'CS02002FB05'           | 'R0402'             | '(R0402-0201)'                 | '20'      | '1%'    | '1/16W'  | 'DISCRETE' | 'RES CHIP 20 1/16W +-1%(0402)DAL_AEC'              | 'CHIPR0402'    | ''          | ''            | '20160706'
 '20'         | '1%'      | '1/16W'  | '0402LF'  | 'EMPTY'  | 'CS02002FB05'(!)        = ''              | ''                 | 'CS02002FB05'           | 'R0402'             | '(R0402-0201)'                 | '20'      | '1%'    | '1/16W'  | 'IO'       | 'RES CHIP 20 1/16W +-1%(0402)DAL_AEC'              | 'CHIPR0402'    | ''          | ''            | '20160706'
 '33'         | '1%'      | '1/16W'  | '0402LF'  | 'CHIP'   | 'CS03302FB05'(!)        = ''              | ''                 | 'CS03302FB05'           | 'R0402'             | '(R0402-0201)'                 | '33'      | '1%'    | '1/16W'  | 'DISCRETE' | 'RES CHIP 33 1/16W +-1%(0402)DAL_AEC'              | 'CHIPR0402'    | ''          | ''            | '20160706'
 '33'         | '1%'      | '1/16W'  | '0402LF'  | 'EMPTY'  | 'CS03302FB05'(!)        = ''              | ''                 | 'CS03302FB05'           | 'R0402'             | '(R0402-0201)'                 | '33'      | '1%'    | '1/16W'  | 'IO'       | 'RES CHIP 33 1/16W +-1%(0402)DAL_AEC'              | 'CHIPR0402'    | ''          | ''            | '20160706'
 '33.2'       | '1%'      | '1/16W'  | '0402LF'  | 'CHIP'   | 'CS03322FB09'(!)        = ''              | ''                 | 'CS03322FB09'           | 'R0402'             | '(R0402-0201)'                 | '33.2'    | '1%'    | '1/16W'  | 'DISCRETE' | 'RES CHIP 33.2 1/16W +-1%(0402)DAL_AEC'            | 'CHIPR0402'    | ''          | ''            | '20160706'
 '33.2'       | '1%'      | '1/16W'  | '0402LF'  | 'EMPTY'  | 'CS03322FB09'(!)        = ''              | ''                 | 'CS03322FB09'           | 'R0402'             | '(R0402-0201)'                 | '33.2'    | '1%'    | '1/16W'  | 'IO'       | 'RES CHIP 33.2 1/16W +-1%(0402)DAL_AEC'            | 'CHIPR0402'    | ''          | ''            | '20160706'
 '36'         | '1%'      | '1/16W'  | '0402LF'  | 'CHIP'   | 'CS03602FB03'(!)        = ''              | ''                 | 'CS03602FB03'           | 'R0402'             | '(R0402-0201)'                 | '36'      | '1%'    | '1/16W'  | 'DISCRETE' | 'RES CHIP 36 1/16W +-1%(0402)DAL_AEC'              | 'CHIPR0402'    | ''          | ''            | '20160706'
 '36'         | '1%'      | '1/16W'  | '0402LF'  | 'EMPTY'  | 'CS03602FB03'(!)        = ''              | ''                 | 'CS03602FB03'           | 'R0402'             | '(R0402-0201)'                 | '36'      | '1%'    | '1/16W'  | 'IO'       | 'RES CHIP 36 1/16W +-1%(0402)DAL_AEC'              | 'CHIPR0402'    | ''          | ''            | '20160706'
 '39'         | '1%'      | '1/16W'  | '0402LF'  | 'CHIP'   | 'CS03902FB03'(!)        = ''              | ''                 | 'CS03902FB03'           | 'R0402'             | '(R0402-0201)'                 | '39'      | '1%'    | '1/16W'  | 'DISCRETE' | 'RES CHIP 39 1/16W +-1%(0402)DAL_AEC'              | 'CHIPR0402'    | ''          | ''            | '20160706'
 '39'         | '1%'      | '1/16W'  | '0402LF'  | 'EMPTY'  | 'CS03902FB03'(!)        = ''              | ''                 | 'CS03902FB03'           | 'R0402'             | '(R0402-0201)'                 | '39'      | '1%'    | '1/16W'  | 'IO'       | 'RES CHIP 39 1/16W +-1%(0402)DAL_AEC'              | 'CHIPR0402'    | ''          | ''            | '20160706'
 '42.2'       | '1%'      | '1/16W'  | '0402LF'  | 'CHIP'   | 'CS04222FB04'(!)        = ''              | ''                 | 'CS04222FB04'           | 'R0402'             | '(R0402-0201)'                 | '42.2'    | '1%'    | '1/16W'  | 'DISCRETE' | 'RES CHIP 42.2 1/16W +-1%(0402)DAL_AEC'            | 'CHIPR0402'    | ''          | ''            | '20160706'
 '42.2'       | '1%'      | '1/16W'  | '0402LF'  | 'EMPTY'  | 'CS04222FB04'(!)        = ''              | ''                 | 'CS04222FB04'           | 'R0402'             | '(R0402-0201)'                 | '42.2'    | '1%'    | '1/16W'  | 'IO'       | 'RES CHIP 42.2 1/16W +-1%(0402)DAL_AEC'            | 'CHIPR0402'    | ''          | ''            | '20160706'
 '43'         | '1%'      | '1/16W'  | '0402LF'  | 'CHIP'   | 'CS04302FB02'(!)        = ''              | ''                 | 'CS04302FB02'           | 'R0402'             | '(R0402-0201)'                 | '43'      | '1%'    | '1/16W'  | 'DISCRETE' | 'RES CHIP 43 1/16W +-1%(0402)DAL_AEC'              | 'CHIPR0402'    | ''          | ''            | '20160706'
 '43'         | '1%'      | '1/16W'  | '0402LF'  | 'EMPTY'  | 'CS04302FB02'(!)        = ''              | ''                 | 'CS04302FB02'           | 'R0402'             | '(R0402-0201)'                 | '43'      | '1%'    | '1/16W'  | 'IO'       | 'RES CHIP 43 1/16W +-1%(0402)DAL_AEC'              | 'CHIPR0402'    | ''          | ''            | '20160706'
 '64.9'       | '1%'      | '1/16W'  | '0402LF'  | 'CHIP'   | 'CS06492FB04'(!)        = ''              | ''                 | 'CS06492FB04'           | 'R0402'             | '(R0402-0201)'                 | '64.9'    | '1%'    | '1/16W'  | 'DISCRETE' | 'RES CHIP 64.9 1/16W +-1%(0402)DAL_AEC'            | 'CHIPR0402'    | ''          | ''            | '20160706'
 '64.9'       | '1%'      | '1/16W'  | '0402LF'  | 'EMPTY'  | 'CS06492FB04'(!)        = ''              | ''                 | 'CS06492FB04'           | 'R0402'             | '(R0402-0201)'                 | '64.9'    | '1%'    | '1/16W'  | 'IO'       | 'RES CHIP 64.9 1/16W +-1%(0402)DAL_AEC'            | 'CHIPR0402'    | ''          | ''            | '20160706'
 '75'         | '1%'      | '1/16W'  | '0402LF'  | 'CHIP'   | 'CS07502FB06'(!)        = ''              | ''                 | 'CS07502FB06'           | 'R0402'             | '(R0402-0201)'                 | '75'      | '1%'    | '1/16W'  | 'DISCRETE' | 'RES CHIP 75 1/16W +-1%(0402)DAL_AEC'              | 'CHIPR0402'    | ''          | ''            | '20160706'
 '75'         | '1%'      | '1/16W'  | '0402LF'  | 'EMPTY'  | 'CS07502FB06'(!)        = ''              | ''                 | 'CS07502FB06'           | 'R0402'             | '(R0402-0201)'                 | '75'      | '1%'    | '1/16W'  | 'IO'       | 'RES CHIP 75 1/16W +-1%(0402)DAL_AEC'              | 'CHIPR0402'    | ''          | ''            | '20160706'
 '90.9'       | '1%'      | '1/16W'  | '0402LF'  | 'CHIP'   | 'CS09092FB05'(!)        = ''              | ''                 | 'CS09092FB05'           | 'R0402'             | '(R0402-0201)'                 | '90.9'    | '1%'    | '1/16W'  | 'DISCRETE' | 'RES CHIP 90.9 1/16W +-1%(0402)DAL_AEC'            | 'CHIPR0402'    | ''          | ''            | '20160706'
 '90.9'       | '1%'      | '1/16W'  | '0402LF'  | 'EMPTY'  | 'CS09092FB05'(!)        = ''              | ''                 | 'CS09092FB05'           | 'R0402'             | '(R0402-0201)'                 | '90.9'    | '1%'    | '1/16W'  | 'IO'       | 'RES CHIP 90.9 1/16W +-1%(0402)DAL_AEC'            | 'CHIPR0402'    | ''          | ''            | '20160706'
 '1'          | '1%'      | '1/16W'  | '0402LF'  | 'CHIP'   | 'CS-1002FB10'(!)        = 'Non-Preferred' | 'End of Life'      | 'CS-1002FB10'           | 'R0402_EOL'         | '(R0402-0201)'                 | '1'       | '1%'    | '1/16W'  | 'DISCRETE' | 'RES CHIP 1 1/16W +-1%(0402) DAL_AEC'              | 'CHIPR0402'    | ''          | ''            | '20160706'
 '1'          | '1%'      | '1/16W'  | '0402LF'  | 'EMPTY'  | 'CS-1002FB10'(!)        = 'Non-Preferred' | 'End of Life'      | 'CS-1002FB10'           | 'R0402_EOL'         | '(R0402-0201)'                 | '1'       | '1%'    | '1/16W'  | 'IO'       | 'RES CHIP 1 1/16W +-1%(0402) DAL_AEC'              | 'CHIPR0402'    | ''          | ''            | '20160706'
 '100'        | '1%'      | '1/16W'  | '0402LF'  | 'CHIP'   | 'CS11002FB12'(!)        = ''              | ''                 | 'CS11002FB12'           | 'R0402'             | '(R0402-0201)'                 | '100'     | '1%'    | '1/16W'  | 'DISCRETE' | 'RES CHIP 100 1/16W +-1%(0402) DAL_AEC'            | 'CHIPR0402'    | ''          | ''            | '20160706'
 '100'        | '1%'      | '1/16W'  | '0402LF'  | 'EMPTY'  | 'CS11002FB12'(!)        = ''              | ''                 | 'CS11002FB12'           | 'R0402'             | '(R0402-0201)'                 | '100'     | '1%'    | '1/16W'  | 'IO'       | 'RES CHIP 100 1/16W +-1%(0402) DAL_AEC'            | 'CHIPR0402'    | ''          | ''            | '20160706'
 '113'        | '1%'      | '1/16W'  | '0402LF'  | 'CHIP'   | 'CS11132FB05'(!)        = ''              | ''                 | 'CS11132FB05'           | 'R0402'             | '(R0402-0201)'                 | '113'     | '1%'    | '1/16W'  | 'DISCRETE' | 'RES CHIP 113 1/16W +-1%(0402)DAL_AEC'             | 'CHIPR0402'    | ''          | ''            | '20160706'
 '113'        | '1%'      | '1/16W'  | '0402LF'  | 'EMPTY'  | 'CS11132FB05'(!)        = ''              | ''                 | 'CS11132FB05'           | 'R0402'             | '(R0402-0201)'                 | '113'     | '1%'    | '1/16W'  | 'IO'       | 'RES CHIP 113 1/16W +-1%(0402)DAL_AEC'             | 'CHIPR0402'    | ''          | ''            | '20160706'
 '120'        | '1%'      | '1/16W'  | '0402LF'  | 'CHIP'   | 'CS11202FB05'(!)        = ''              | ''                 | 'CS11202FB05'           | 'R0402'             | '(R0402-0201)'                 | '120'     | '1%'    | '1/16W'  | 'DISCRETE' | 'RES CHIP 120 1/16W +-1%(0402)DAL_AEC'             | 'CHIPR0402'    | ''          | ''            | '20160706'
 '120'        | '1%'      | '1/16W'  | '0402LF'  | 'EMPTY'  | 'CS11202FB05'(!)        = ''              | ''                 | 'CS11202FB05'           | 'R0402'             | '(R0402-0201)'                 | '120'     | '1%'    | '1/16W'  | 'IO'       | 'RES CHIP 120 1/16W +-1%(0402)DAL_AEC'             | 'CHIPR0402'    | ''          | ''            | '20160706'
 '137'        | '1%'      | '1/16W'  | '0402LF'  | 'CHIP'   | 'CS11372FB02'(!)        = ''              | ''                 | 'CS11372FB02'           | 'R0402'             | '(R0402-0201)'                 | '137'     | '1%'    | '1/16W'  | 'DISCRETE' | 'RES CHIP 137 1/16W +1%(0402)DAL_AEC'              | 'CHIPR0402'    | ''          | ''            | '20160706'
 '137'        | '1%'      | '1/16W'  | '0402LF'  | 'EMPTY'  | 'CS11372FB02'(!)        = ''              | ''                 | 'CS11372FB02'           | 'R0402'             | '(R0402-0201)'                 | '137'     | '1%'    | '1/16W'  | 'IO'       | 'RES CHIP 137 1/16W +1%(0402)DAL_AEC'              | 'CHIPR0402'    | ''          | ''            | '20160706'
 '150'        | '1%'      | '1/16W'  | '0402LF'  | 'CHIP'   | 'CS11502FB09'(!)        = ''              | ''                 | 'CS11502FB09'           | 'R0402'             | '(R0402-0201)'                 | '150'     | '1%'    | '1/16W'  | 'DISCRETE' | 'RES CHIP 150 1/16W +-1%(0402)DAL_AEC'             | 'CHIPR0402'    | ''          | ''            | '20160706'
 '150'        | '1%'      | '1/16W'  | '0402LF'  | 'EMPTY'  | 'CS11502FB09'(!)        = ''              | ''                 | 'CS11502FB09'           | 'R0402'             | '(R0402-0201)'                 | '150'     | '1%'    | '1/16W'  | 'IO'       | 'RES CHIP 150 1/16W +-1%(0402)DAL_AEC'             | 'CHIPR0402'    | ''          | ''            | '20160706'
 '169'        | '1%'      | '1/16W'  | '0402LF'  | 'CHIP'   | 'CS11692FB03'(!)        = ''              | ''                 | 'CS11692FB03'           | 'R0402'             | '(R0402-0201)'                 | '169'     | '1%'    | '1/16W'  | 'DISCRETE' | 'RES CHIP 169 1/16W +-1%(0402)DAL_AEC'             | 'CHIPR0402'    | ''          | ''            | '20160706'
 '169'        | '1%'      | '1/16W'  | '0402LF'  | 'EMPTY'  | 'CS11692FB03'(!)        = ''              | ''                 | 'CS11692FB03'           | 'R0402'             | '(R0402-0201)'                 | '169'     | '1%'    | '1/16W'  | 'IO'       | 'RES CHIP 169 1/16W +-1%(0402)DAL_AEC'             | 'CHIPR0402'    | ''          | ''            | '20160706'
 '200'        | '1%'      | '1/16W'  | '0402LF'  | 'CHIP'   | 'CS12002FB13'(!)        = ''              | ''                 | 'CS12002FB13'           | 'R0402'             | '(R0402-0201)'                 | '200'     | '1%'    | '1/16W'  | 'DISCRETE' | 'RES CHIP 200 1/16W +-1%(0402)DAL_AEC'             | 'CHIPR0402'    | ''          | ''            | '20160706'
 '200'        | '1%'      | '1/16W'  | '0402LF'  | 'EMPTY'  | 'CS12002FB13'(!)        = ''              | ''                 | 'CS12002FB13'           | 'R0402'             | '(R0402-0201)'                 | '200'     | '1%'    | '1/16W'  | 'IO'       | 'RES CHIP 200 1/16W +-1%(0402)DAL_AEC'             | 'CHIPR0402'    | ''          | ''            | '20160706'
 '220'        | '1%'      | '1/16W'  | '0402LF'  | 'CHIP'   | 'CS12202FB02'(!)        = ''              | ''                 | 'CS12202FB02'           | 'R0402'             | '(R0402-0201)'                 | '220'     | '1%'    | '1/16W'  | 'DISCRETE' | 'RES CHIP 220 1/16W +-1%(0402)DAL_AEC'             | 'CHIPR0402'    | ''          | ''            | '20160706'
 '220'        | '1%'      | '1/16W'  | '0402LF'  | 'EMPTY'  | 'CS12202FB02'(!)        = ''              | ''                 | 'CS12202FB02'           | 'R0402'             | '(R0402-0201)'                 | '220'     | '1%'    | '1/16W'  | 'IO'       | 'RES CHIP 220 1/16W +-1%(0402)DAL_AEC'             | 'CHIPR0402'    | ''          | ''            | '20160706'
 '240'        | '1%'      | '1/16W'  | '0402LF'  | 'CHIP'   | 'CS12402FB04'(!)        = ''              | ''                 | 'CS12402FB04'           | 'R0402'             | '(R0402-0201)'                 | '240'     | '1%'    | '1/16W'  | 'DISCRETE' | 'RES CHIP 240 1/16W +-1%(0402)DAL_AEC'             | 'CHIPR0402'    | ''          | ''            | '20160706'
 '240'        | '1%'      | '1/16W'  | '0402LF'  | 'EMPTY'  | 'CS12402FB04'(!)        = ''              | ''                 | 'CS12402FB04'           | 'R0402'             | '(R0402-0201)'                 | '240'     | '1%'    | '1/16W'  | 'IO'       | 'RES CHIP 240 1/16W +-1%(0402)DAL_AEC'             | 'CHIPR0402'    | ''          | ''            | '20160706'
 '330'        | '1%'      | '1/16W'  | '0402LF'  | 'CHIP'   | 'CS13302FB03'(!)        = ''              | ''                 | 'CS13302FB03'           | 'R0402'             | '(R0402-0201)'                 | '330'     | '1%'    | '1/16W'  | 'DISCRETE' | 'RES CHIP 330 1/16W +-1%(0402)DAL_AEC'             | 'CHIPR0402'    | ''          | ''            | '20160706'
 '330'        | '1%'      | '1/16W'  | '0402LF'  | 'EMPTY'  | 'CS13302FB03'(!)        = ''              | ''                 | 'CS13302FB03'           | 'R0402'             | '(R0402-0201)'                 | '330'     | '1%'    | '1/16W'  | 'IO'       | 'RES CHIP 330 1/16W +-1%(0402)DAL_AEC'             | 'CHIPR0402'    | ''          | ''            | '20160706'
 '332'        | '1%'      | '1/16W'  | '0402LF'  | 'CHIP'   | 'CS13322FB07'(!)        = ''              | ''                 | 'CS13322FB07'           | 'R0402'             | '(R0402-0201)'                 | '332'     | '1%'    | '1/16W'  | 'DISCRETE' | 'RES CHIP 332 1/16W +-1%(0402)DAL_AEC'             | 'CHIPR0402'    | ''          | ''            | '20160706'
 '332'        | '1%'      | '1/16W'  | '0402LF'  | 'EMPTY'  | 'CS13322FB07'(!)        = ''              | ''                 | 'CS13322FB07'           | 'R0402'             | '(R0402-0201)'                 | '332'     | '1%'    | '1/16W'  | 'IO'       | 'RES CHIP 332 1/16W +-1%(0402)DAL_AEC'             | 'CHIPR0402'    | ''          | ''            | '20160706'
 '348'        | '1%'      | '1/16W'  | '0402LF'  | 'CHIP'   | 'CS13482FB05'(!)        = ''              | ''                 | 'CS13482FB05'           | 'R0402'             | '(R0402-0201)'                 | '348'     | '1%'    | '1/16W'  | 'DISCRETE' | 'RES CHIP 348 1/16W +-1%(0402)DAL_AEC'             | 'CHIPR0402'    | ''          | ''            | '20160706'
 '348'        | '1%'      | '1/16W'  | '0402LF'  | 'EMPTY'  | 'CS13482FB05'(!)        = ''              | ''                 | 'CS13482FB05'           | 'R0402'             | '(R0402-0201)'                 | '348'     | '1%'    | '1/16W'  | 'IO'       | 'RES CHIP 348 1/16W +-1%(0402)DAL_AEC'             | 'CHIPR0402'    | ''          | ''            | '20160706'
 '412'        | '1%'      | '1/16W'  | '0402LF'  | 'CHIP'   | 'CS14122FB03'(!)        = ''              | ''                 | 'CS14122FB03'           | 'R0402'             | '(R0402-0201)'                 | '412'     | '1%'    | '1/16W'  | 'DISCRETE' | 'RES CHIP 412 1/16W +-1%(0402)DAL_AEC'             | 'CHIPR0402'    | ''          | ''            | '20160706'
 '412'        | '1%'      | '1/16W'  | '0402LF'  | 'EMPTY'  | 'CS14122FB03'(!)        = ''              | ''                 | 'CS14122FB03'           | 'R0402'             | '(R0402-0201)'                 | '412'     | '1%'    | '1/16W'  | 'IO'       | 'RES CHIP 412 1/16W +-1%(0402)DAL_AEC'             | 'CHIPR0402'    | ''          | ''            | '20160706'
 '475'        | '1%'      | '1/16W'  | '0402LF'  | 'CHIP'   | 'CS14752FB10'(!)        = ''              | ''                 | 'CS14752FB10'           | 'R0402'             | '(R0402-0201)'                 | '475'     | '1%'    | '1/16W'  | 'DISCRETE' | 'RES CHIP 475 1/16W +-1%(0402)DAL_AEC'             | 'CHIPR0402'    | ''          | ''            | '20160711'
 '475'        | '1%'      | '1/16W'  | '0402LF'  | 'EMPTY'  | 'CS14752FB10'(!)        = ''              | ''                 | 'CS14752FB10'           | 'R0402'             | '(R0402-0201)'                 | '475'     | '1%'    | '1/16W'  | 'IO'       | 'RES CHIP 475 1/16W +-1%(0402)DAL_AEC'             | 'CHIPR0402'    | ''          | ''            | '20160711'
 '511'        | '1%'      | '1/16W'  | '0402LF'  | 'CHIP'   | 'CS15112FB06'(!)        = ''              | ''                 | 'CS15112FB06'           | 'R0402'             | '(R0402-0201)'                 | '511'     | '1%'    | '1/16W'  | 'DISCRETE' | 'RES CHIP 511 1/16W +-1%(0402)DAL_AEC'             | 'CHIPR0402'    | ''          | ''            | '20160711'
 '511'        | '1%'      | '1/16W'  | '0402LF'  | 'EMPTY'  | 'CS15112FB06'(!)        = ''              | ''                 | 'CS15112FB06'           | 'R0402'             | '(R0402-0201)'                 | '511'     | '1%'    | '1/16W'  | 'IO'       | 'RES CHIP 511 1/16W +-1%(0402)DAL_AEC'             | 'CHIPR0402'    | ''          | ''            | '20160711'
 '845'        | '1%'      | '1/16W'  | '0402LF'  | 'CHIP'   | 'CS18452FB04'(!)        = ''              | ''                 | 'CS18452FB04'           | 'R0402'             | '(R0402-0201)'                 | '845'     | '1%'    | '1/16W'  | 'DISCRETE' | 'RES CHIP 845 1/16W +-1%(0402)DAL_AEC'             | 'CHIPR0402'    | ''          | ''            | '20160713'
 '845'        | '1%'      | '1/16W'  | '0402LF'  | 'EMPTY'  | 'CS18452FB04'(!)        = ''              | ''                 | 'CS18452FB04'           | 'R0402'             | '(R0402-0201)'                 | '845'     | '1%'    | '1/16W'  | 'IO'       | 'RES CHIP 845 1/16W +-1%(0402)DAL_AEC'             | 'CHIPR0402'    | ''          | ''            | '20160713'
 '2'          | '1%'      | '1/16W'  | '0402LF'  | 'CHIP'   | 'CS-2002FB04'(!)        = 'End of Design' | 'Comp-Approve'     | 'CS-2002FB04'           | 'R0402'             | '(R0402-0201)'                 | '2'       | '1%'    | '1/16W'  | 'DISCRETE' | 'RES CHIP 2 1/16W +-1%(0402)DAL_AEC'               | 'CHIPR0402'    | ''          | ''            | '20160713'
 '2'          | '1%'      | '1/16W'  | '0402LF'  | 'EMPTY'  | 'CS-2002FB04'(!)        = 'End of Design' | 'Comp-Approve'     | 'CS-2002FB04'           | 'R0402'             | '(R0402-0201)'                 | '2'       | '1%'    | '1/16W'  | 'IO'       | 'RES CHIP 2 1/16W +-1%(0402)DAL_AEC'               | 'CHIPR0402'    | ''          | ''            | '20160713'
 '2.2K'       | '1%'      | '1/16W'  | '0402LF'  | 'CHIP'   | 'CS22202FB03'(!)        = ''              | ''                 | 'CS22202FB03'           | 'R0402'             | '(R0402-0201)'                 | '2.2K'    | '1%'    | '1/16W'  | 'DISCRETE' | 'RES CHIP 2.2K 1/16W +-1%(0402)DAL_AEC'            | 'CHIPR0402'    | ''          | ''            | '20160713'
 '2.2K'       | '1%'      | '1/16W'  | '0402LF'  | 'EMPTY'  | 'CS22202FB03'(!)        = ''              | ''                 | 'CS22202FB03'           | 'R0402'             | '(R0402-0201)'                 | '2.2K'    | '1%'    | '1/16W'  | 'IO'       | 'RES CHIP 2.2K 1/16W +-1%(0402)DAL_AEC'            | 'CHIPR0402'    | ''          | ''            | '20160713'
 '2.21K'      | '1%'      | '1/16W'  | '0402LF'  | 'CHIP'   | 'CS22212FB08'(!)        = ''              | ''                 | 'CS22212FB08'           | 'R0402'             | '(R0402-0201)'                 | '2.21K'   | '1%'    | '1/16W'  | 'DISCRETE' | 'RES CHIP 2.21K 1/16W +-1%(0402)DAL_AEC'           | 'CHIPR0402'    | ''          | ''            | '20160713'
 '2.21K'      | '1%'      | '1/16W'  | '0402LF'  | 'EMPTY'  | 'CS22212FB08'(!)        = ''              | ''                 | 'CS22212FB08'           | 'R0402'             | '(R0402-0201)'                 | '2.21K'   | '1%'    | '1/16W'  | 'IO'       | 'RES CHIP 2.21K 1/16W +-1%(0402)DAL_AEC'           | 'CHIPR0402'    | ''          | ''            | '20160713'
 '49.9'       | '1%'      | '1/10W'  | '0603LF'  | 'CHIP'   | 'CS04993F908'(!)        = ''              | ''                 | 'CS04993F908'           | 'R0603'             | '(SMR0603AW)'                  | '49.9'    | '1%'    | '1/10W'  | 'DISCRETE' | 'RES CHIP 49.9 1/10W +-1%(0603)DAL_AEC'            | 'CHIPR0603'    | ''          | ''            | '20160713'
 '49.9'       | '1%'      | '1/10W'  | '0603LF'  | 'EMPTY'  | 'CS04993F908'(!)        = ''              | ''                 | 'CS04993F908'           | 'R0603'             | '(SMR0603AW)'                  | '49.9'    | '1%'    | '1/10W'  | 'IO'       | 'RES CHIP 49.9 1/10W +-1%(0603)DAL_AEC'            | 'CHIPR0603'    | ''          | ''            | '20160713'
 '0.0002'     | '1%'      | '9W'     | '3921LF'  | 'CHIP'   | 'CS0000KFY00'(!)        = ''              | ''                 | 'CS0000KFY00'           | 'R3921'             | '(SMR3921AW)'                  | '0.0002'  | '1%'    | '9W'     | 'DISCRETE' | 'RES CHIP 0.0002 9W +-1%(3921)DAL_AEC'             | 'CHIPR3921'    | ''          | ''            | '20160725'
 '0.0002'     | '1%'      | '9W'     | '3921LF'  | 'EMPTY'  | 'CS0000KFY00'(!)        = ''              | ''                 | 'CS0000KFY00'           | 'R3921'             | '(SMR3921AW)'                  | '0.0002'  | '1%'    | '9W'     | 'IO'       | 'RES CHIP 0.0002 9W +-1%(3921)DAL_AEC'             | 'CHIPR3921'    | ''          | ''            | '20160725'
 '1K'         | '1%'      | '1/16W'  | '0402LF'  | 'CHIP'   | 'CS21002FB13'(!)        = ''              | ''                 | 'CS21002FB13'           | 'R0402'             | '(R0402-0201)'                 | '1K'      | '1%'    | '1/16W'  | 'DISCRETE' | 'RES CHIP 1K 1/16W +-1%(0402)DAL_AEC'              | 'CHIPR0402'    | ''          | ''            | '20160725'
 '1K'         | '1%'      | '1/16W'  | '0402LF'  | 'EMPTY'  | 'CS21002FB13'(!)        = ''              | ''                 | 'CS21002FB13'           | 'R0402'             | '(R0402-0201)'                 | '1K'      | '1%'    | '1/16W'  | 'IO'       | 'RES CHIP 1K 1/16W +-1%(0402)DAL_AEC'              | 'CHIPR0402'    | ''          | ''            | '20160725'
 '2.55K'      | '1%'      | '1/16W'  | '0402LF'  | 'CHIP'   | 'CS22552FB03'(!)        = ''              | ''                 | 'CS22552FB03'           | 'R0402'             | '(R0402-0201)'                 | '2.55K'   | '1%'    | '1/16W'  | 'DISCRETE' | 'RES CHIP 2.55K 1/16W +-1%(0402)DAL_AEC'           | 'CHIPR0402'    | ''          | ''            | '20160725'
 '2.55K'      | '1%'      | '1/16W'  | '0402LF'  | 'EMPTY'  | 'CS22552FB03'(!)        = ''              | ''                 | 'CS22552FB03'           | 'R0402'             | '(R0402-0201)'                 | '2.55K'   | '1%'    | '1/16W'  | 'IO'       | 'RES CHIP 2.55K 1/16W +-1%(0402)DAL_AEC'           | 'CHIPR0402'    | ''          | ''            | '20160725'
 '3.01K'      | '1%'      | '1/16W'  | '0402LF'  | 'CHIP'   | 'CS23012FB10'(!)        = ''              | ''                 | 'CS23012FB10'           | 'R0402'             | '(R0402-0201)'                 | '3.01K'   | '1%'    | '1/16W'  | 'DISCRETE' | 'RES CHIP 3.01K 1/16W +-1%(0402)DAL_AEC'           | 'CHIPR0402'    | ''          | ''            | '20160725'
 '3.01K'      | '1%'      | '1/16W'  | '0402LF'  | 'EMPTY'  | 'CS23012FB10'(!)        = ''              | ''                 | 'CS23012FB10'           | 'R0402'             | '(R0402-0201)'                 | '3.01K'   | '1%'    | '1/16W'  | 'IO'       | 'RES CHIP 3.01K 1/16W +-1%(0402)DAL_AEC'           | 'CHIPR0402'    | ''          | ''            | '20160725'
 '3.3K'       | '1%'      | '1/16W'  | '0402LF'  | 'CHIP'   | 'CS23302FB03'(!)        = ''              | ''                 | 'CS23302FB03'           | 'R0402'             | '(R0402-0201)'                 | '3.3K'    | '1%'    | '1/16W'  | 'DISCRETE' | 'RES CHIP 3.3K 1/16W +-1%(0402)DAL_AEC'            | 'CHIPR0402'    | ''          | ''            | '20160725'
 '3.3K'       | '1%'      | '1/16W'  | '0402LF'  | 'EMPTY'  | 'CS23302FB03'(!)        = ''              | ''                 | 'CS23302FB03'           | 'R0402'             | '(R0402-0201)'                 | '3.3K'    | '1%'    | '1/16W'  | 'IO'       | 'RES CHIP 3.3K 1/16W +-1%(0402)DAL_AEC'            | 'CHIPR0402'    | ''          | ''            | '20160725'
 '3.32K'      | '1%'      | '1/16W'  | '0402LF'  | 'CHIP'   | 'CS23322FB07'(!)        = ''              | ''                 | 'CS23322FB07'           | 'R0402'             | '(R0402-0201)'                 | '3.32K'   | '1%'    | '1/16W'  | 'DISCRETE' | 'RES CHIP 3.32K 1/16W +-1% (0402)DAL_AEC'          | 'CHIPR0402'    | ''          | ''            | '20160725'
 '3.32K'      | '1%'      | '1/16W'  | '0402LF'  | 'EMPTY'  | 'CS23322FB07'(!)        = ''              | ''                 | 'CS23322FB07'           | 'R0402'             | '(R0402-0201)'                 | '3.32K'   | '1%'    | '1/16W'  | 'IO'       | 'RES CHIP 3.32K 1/16W +-1% (0402)DAL_AEC'          | 'CHIPR0402'    | ''          | ''            | '20160725'
 '3.4K'       | '1%'      | '1/16W'  | '0402LF'  | 'CHIP'   | 'CS23402FB03'(!)        = ''              | ''                 | 'CS23402FB03'           | 'R0402'             | '(R0402-0201)'                 | '3.4K'    | '1%'    | '1/16W'  | 'DISCRETE' | 'RES CHIP 3.4K 1/16W +-1%(0402)DAL_AEC'            | 'CHIPR0402'    | ''          | ''            | '20160725'
 '3.4K'       | '1%'      | '1/16W'  | '0402LF'  | 'EMPTY'  | 'CS23402FB03'(!)        = ''              | ''                 | 'CS23402FB03'           | 'R0402'             | '(R0402-0201)'                 | '3.4K'    | '1%'    | '1/16W'  | 'IO'       | 'RES CHIP 3.4K 1/16W +-1%(0402)DAL_AEC'            | 'CHIPR0402'    | ''          | ''            | '20160725'
 '3.57K'      | '1%'      | '1/16W'  | '0402LF'  | 'CHIP'   | 'CS23572FB07'(!)        = ''              | ''                 | 'CS23572FB07'           | 'R0402'             | '(R0402-0201)'                 | '3.57K'   | '1%'    | '1/16W'  | 'DISCRETE' | 'RES CHIP 3.57K 1/16W +-1%(0402)DAL_AEC'           | 'CHIPR0402'    | ''          | ''            | '20160725'
 '3.57K'      | '1%'      | '1/16W'  | '0402LF'  | 'EMPTY'  | 'CS23572FB07'(!)        = ''              | ''                 | 'CS23572FB07'           | 'R0402'             | '(R0402-0201)'                 | '3.57K'   | '1%'    | '1/16W'  | 'IO'       | 'RES CHIP 3.57K 1/16W +-1%(0402)DAL_AEC'           | 'CHIPR0402'    | ''          | ''            | '20160725'
 '4.02K'      | '1%'      | '1/16W'  | '0402LF'  | 'CHIP'   | 'CS24022FB07'(!)        = ''              | ''                 | 'CS24022FB07'           | 'R0402'             | '(R0402-0201)'                 | '4.02K'   | '1%'    | '1/16W'  | 'DISCRETE' | 'RES CHIP 4.02K 1/16W +-1%(0402)DAL_AEC'           | 'CHIPR0402'    | ''          | ''            | '20160725'
 '4.02K'      | '1%'      | '1/16W'  | '0402LF'  | 'EMPTY'  | 'CS24022FB07'(!)        = ''              | ''                 | 'CS24022FB07'           | 'R0402'             | '(R0402-0201)'                 | '4.02K'   | '1%'    | '1/16W'  | 'IO'       | 'RES CHIP 4.02K 1/16W +-1%(0402)DAL_AEC'           | 'CHIPR0402'    | ''          | ''            | '20160725'
 '4.12K'      | '1%'      | '1/16W'  | '0402LF'  | 'CHIP'   | 'CS24122FB03'(!)        = ''              | ''                 | 'CS24122FB03'           | 'R0402'             | '(R0402-0201)'                 | '4.12K'   | '1%'    | '1/16W'  | 'DISCRETE' | 'RES CHIP 4.12K 1/16W +-1%(0402)DAL_AEC'           | 'CHIPR0402'    | ''          | ''            | '20160725'
 '4.12K'      | '1%'      | '1/16W'  | '0402LF'  | 'EMPTY'  | 'CS24122FB03'(!)        = ''              | ''                 | 'CS24122FB03'           | 'R0402'             | '(R0402-0201)'                 | '4.12K'   | '1%'    | '1/16W'  | 'IO'       | 'RES CHIP 4.12K 1/16W +-1%(0402)DAL_AEC'           | 'CHIPR0402'    | ''          | ''            | '20160725'
 '1.1K'       | '1%'      | '1/16W'  | '0402LF'  | 'CHIP'   | 'CS21102FB06'(!)        = ''              | ''                 | 'CS21102FB06'           | 'R0402'             | '(R0402-0201)'                 | '1.1K'    | '1%'    | '1/16W'  | 'DISCRETE' | 'RES CHIP 1.1K 1/16W +1% (0402)DAL_AEC'            | 'CHIPR0402'    | ''          | ''            | '20160725'
 '1.1K'       | '1%'      | '1/16W'  | '0402LF'  | 'EMPTY'  | 'CS21102FB06'(!)        = ''              | ''                 | 'CS21102FB06'           | 'R0402'             | '(R0402-0201)'                 | '1.1K'    | '1%'    | '1/16W'  | 'IO'       | 'RES CHIP 1.1K 1/16W +1% (0402)DAL_AEC'            | 'CHIPR0402'    | ''          | ''            | '20160725'
 '51.1'       | '1%'      | '1/20W'  | '0201LF'  | 'CHIP'   | 'CS05111FE00'(!)        = ''              | ''                 | 'CS05111FE00'           | 'R0201'             | '(SMR0201AW)'                  | '51.1'    | '1%'    | '1/20W'  | 'DISCRETE' | 'RES CHIP 51.1 1/20W +-1%(0201)'                   | 'CHIPR0201'    | ''          | ''            | '20160725'
 '51.1'       | '1%'      | '1/20W'  | '0201LF'  | 'EMPTY'  | 'CS05111FE00'(!)        = ''              | ''                 | 'CS05111FE00'           | 'R0201'             | '(SMR0201AW)'                  | '51.1'    | '1%'    | '1/20W'  | 'IO'       | 'RES CHIP 51.1 1/20W +-1%(0201)'                   | 'CHIPR0201'    | ''          | ''            | '20160725'
 '1.5K'       | '1%'      | '1/16W'  | '0402LF'  | 'CHIP'   | 'CS21502FB09'(!)        = ''              | ''                 | 'CS21502FB09'           | 'R0402'             | '(R0402-0201)'                 | '1.5K'    | '1%'    | '1/16W'  | 'DISCRETE' | 'RES CHIP 1.5K 1/16W +1% (0402)DAL_AEC'            | 'CHIPR0402'    | ''          | ''            | '20160727'
 '1.5K'       | '1%'      | '1/16W'  | '0402LF'  | 'EMPTY'  | 'CS21502FB09'(!)        = ''              | ''                 | 'CS21502FB09'           | 'R0402'             | '(R0402-0201)'                 | '1.5K'    | '1%'    | '1/16W'  | 'IO'       | 'RES CHIP 1.5K 1/16W +1% (0402)DAL_AEC'            | 'CHIPR0402'    | ''          | ''            | '20160727'
 '1.69K'      | '1%'      | '1/16W'  | '0402LF'  | 'CHIP'   | 'CS21692FB03'(!)        = ''              | ''                 | 'CS21692FB03'           | 'R0402'             | '(R0402-0201)'                 | '1.69K'   | '1%'    | '1/16W'  | 'DISCRETE' | 'RES CHIP 1.69K 1/16W +-1%(0402)DAL_AEC'           | 'CHIPR0402'    | ''          | ''            | '20160727'
 '1.69K'      | '1%'      | '1/16W'  | '0402LF'  | 'EMPTY'  | 'CS21692FB03'(!)        = ''              | ''                 | 'CS21692FB03'           | 'R0402'             | '(R0402-0201)'                 | '1.69K'   | '1%'    | '1/16W'  | 'IO'       | 'RES CHIP 1.69K 1/16W +-1%(0402)DAL_AEC'           | 'CHIPR0402'    | ''          | ''            | '20160727'
 '1.8K'       | '1%'      | '1/16W'  | '0402LF'  | 'CHIP'   | 'CS21802FB04'(!)        = ''              | ''                 | 'CS21802FB04'           | 'R0402'             | '(R0402-0201)'                 | '1.8K'    | '1%'    | '1/16W'  | 'DISCRETE' | 'RES CHIP 1.8K 1/16W +-1%(0402) DAL_AEC'           | 'CHIPR0402'    | ''          | ''            | '20160727'
 '1.8K'       | '1%'      | '1/16W'  | '0402LF'  | 'EMPTY'  | 'CS21802FB04'(!)        = ''              | ''                 | 'CS21802FB04'           | 'R0402'             | '(R0402-0201)'                 | '1.8K'    | '1%'    | '1/16W'  | 'IO'       | 'RES CHIP 1.8K 1/16W +-1%(0402) DAL_AEC'           | 'CHIPR0402'    | ''          | ''            | '20160727'
 '2K'         | '1%'      | '1/16W'  | '0402LF'  | 'CHIP'   | 'CS22002FB12'(!)        = ''              | ''                 | 'CS22002FB12'           | 'R0402'             | '(R0402-0201)'                 | '2K'      | '1%'    | '1/16W'  | 'DISCRETE' | 'RES CHIP 2K 1/16W +-1%(0402)DAL_AEC'              | 'CHIPR0402'    | ''          | ''            | '20160727'
 '2K'         | '1%'      | '1/16W'  | '0402LF'  | 'EMPTY'  | 'CS22002FB12'(!)        = ''              | ''                 | 'CS22002FB12'           | 'R0402'             | '(R0402-0201)'                 | '2K'      | '1%'    | '1/16W'  | 'IO'       | 'RES CHIP 2K 1/16W +-1%(0402)DAL_AEC'              | 'CHIPR0402'    | ''          | ''            | '20160727'
 '2.2'        | '1%'      | '1/16W'  | '0402LF'  | 'CHIP'   | 'CS-2202FB03'(!)        = 'End of Design' | 'Comp-Approve'     | 'CS-2202FB03'           | 'R0402'             | '(R0402-0201)'                 | '2.2'     | '1%'    | '1/16W'  | 'DISCRETE' | 'RES CHIP 2.2 1/16W +-1%(0402)DAL_AEC'             | 'CHIPR0402'    | ''          | ''            | '20160727'
 '2.2'        | '1%'      | '1/16W'  | '0402LF'  | 'EMPTY'  | 'CS-2202FB03'(!)        = 'End of Design' | 'Comp-Approve'     | 'CS-2202FB03'           | 'R0402'             | '(R0402-0201)'                 | '2.2'     | '1%'    | '1/16W'  | 'IO'       | 'RES CHIP 2.2 1/16W +-1%(0402)DAL_AEC'             | 'CHIPR0402'    | ''          | ''            | '20160727'
 '4.75K'      | '1%'      | '1/16W'  | '0402LF'  | 'CHIP'   | 'CS24752FB06'(!)        = ''              | ''                 | 'CS24752FB06'           | 'R0402'             | '(R0402-0201)'                 | '4.75K'   | '1%'    | '1/16W'  | 'DISCRETE' | 'RES CHIP 4.75K 1/16W +-1%(0402)DAL_AEC'           | 'CHIPR0402'    | ''          | ''            | '20160727'
 '4.75K'      | '1%'      | '1/16W'  | '0402LF'  | 'EMPTY'  | 'CS24752FB06'(!)        = ''              | ''                 | 'CS24752FB06'           | 'R0402'             | '(R0402-0201)'                 | '4.75K'   | '1%'    | '1/16W'  | 'IO'       | 'RES CHIP 4.75K 1/16W +-1%(0402)DAL_AEC'           | 'CHIPR0402'    | ''          | ''            | '20160727'
 '4.87K'      | '1%'      | '1/16W'  | '0402LF'  | 'CHIP'   | 'CS24872FB03'(!)        = ''              | ''                 | 'CS24872FB03'           | 'R0402'             | '(R0402-0201)'                 | '4.87K'   | '1%'    | '1/16W'  | 'DISCRETE' | 'RES CHIP 4.87K 1/16W+-1%(0402)DAL_AEC'            | 'CHIPR0402'    | ''          | ''            | '20160727'
 '4.87K'      | '1%'      | '1/16W'  | '0402LF'  | 'EMPTY'  | 'CS24872FB03'(!)        = ''              | ''                 | 'CS24872FB03'           | 'R0402'             | '(R0402-0201)'                 | '4.87K'   | '1%'    | '1/16W'  | 'IO'       | 'RES CHIP 4.87K 1/16W+-1%(0402)DAL_AEC'            | 'CHIPR0402'    | ''          | ''            | '20160727'
 '4.99K'      | '1%'      | '1/16W'  | '0402LF'  | 'CHIP'   | 'CS24992FB09'(!)        = ''              | ''                 | 'CS24992FB09'           | 'R0402'             | '(R0402-0201)'                 | '4.99K'   | '1%'    | '1/16W'  | 'DISCRETE' | 'RES CHIP 4.99K 1/16W +-1%(0402)DAL_AEC'           | 'CHIPR0402'    | ''          | ''            | '20160727'
 '4.99K'      | '1%'      | '1/16W'  | '0402LF'  | 'EMPTY'  | 'CS24992FB09'(!)        = ''              | ''                 | 'CS24992FB09'           | 'R0402'             | '(R0402-0201)'                 | '4.99K'   | '1%'    | '1/16W'  | 'IO'       | 'RES CHIP 4.99K 1/16W +-1%(0402)DAL_AEC'           | 'CHIPR0402'    | ''          | ''            | '20160727'
 '5.76K'      | '1%'      | '1/16W'  | '0402LF'  | 'CHIP'   | 'CS25762FB05'(!)        = ''              | ''                 | 'CS25762FB05'           | 'R0402'             | '(R0402-0201)'                 | '5.76K'   | '1%'    | '1/16W'  | 'DISCRETE' | 'RES CHIP 5.76K 1/16W +-1%(0402)DAL_AEC'           | 'CHIPR0402'    | ''          | ''            | '20160727'
 '5.76K'      | '1%'      | '1/16W'  | '0402LF'  | 'EMPTY'  | 'CS25762FB05'(!)        = ''              | ''                 | 'CS25762FB05'           | 'R0402'             | '(R0402-0201)'                 | '5.76K'   | '1%'    | '1/16W'  | 'IO'       | 'RES CHIP 5.76K 1/16W +-1%(0402)DAL_AEC'           | 'CHIPR0402'    | ''          | ''            | '20160727'
 '6.81K'      | '1%'      | '1/16W'  | '0402LF'  | 'CHIP'   | 'CS26812FB07'(!)        = ''              | ''                 | 'CS26812FB07'           | 'R0402'             | '(R0402-0201)'                 | '6.81K'   | '1%'    | '1/16W'  | 'DISCRETE' | 'RES CHIP 6.81K 1/16W +-1%(0402)DAL_AEC'           | 'CHIPR0402'    | ''          | ''            | '20160727'
 '6.81K'      | '1%'      | '1/16W'  | '0402LF'  | 'EMPTY'  | 'CS26812FB07'(!)        = ''              | ''                 | 'CS26812FB07'           | 'R0402'             | '(R0402-0201)'                 | '6.81K'   | '1%'    | '1/16W'  | 'IO'       | 'RES CHIP 6.81K 1/16W +-1%(0402)DAL_AEC'           | 'CHIPR0402'    | ''          | ''            | '20160727'
 '6.98K'      | '1%'      | '1/16W'  | '0402LF'  | 'CHIP'   | 'CS26982FB05'(!)        = ''              | ''                 | 'CS26982FB05'           | 'R0402'             | '(R0402-0201)'                 | '6.98K'   | '1%'    | '1/16W'  | 'DISCRETE' | 'RES CHIP 6.98K 1/16W +-1% (0402)DAL_AEC'          | 'CHIPR0402'    | ''          | ''            | '20160727'
 '6.98K'      | '1%'      | '1/16W'  | '0402LF'  | 'EMPTY'  | 'CS26982FB05'(!)        = ''              | ''                 | 'CS26982FB05'           | 'R0402'             | '(R0402-0201)'                 | '6.98K'   | '1%'    | '1/16W'  | 'IO'       | 'RES CHIP 6.98K 1/16W +-1% (0402)DAL_AEC'          | 'CHIPR0402'    | ''          | ''            | '20160727'
 '8.25K'      | '1%'      | '1/16W'  | '0402LF'  | 'CHIP'   | 'CS28252FB05'(!)        = ''              | ''                 | 'CS28252FB05'           | 'R0402'             | '(R0402-0201)'                 | '8.25K'   | '1%'    | '1/16W'  | 'DISCRETE' | 'RES CHIP 8.25K 1/16W+-1%(0402)DAL_AEC'            | 'CHIPR0402'    | ''          | ''            | '20160727'
 '8.25K'      | '1%'      | '1/16W'  | '0402LF'  | 'EMPTY'  | 'CS28252FB05'(!)        = ''              | ''                 | 'CS28252FB05'           | 'R0402'             | '(R0402-0201)'                 | '8.25K'   | '1%'    | '1/16W'  | 'IO'       | 'RES CHIP 8.25K 1/16W+-1%(0402)DAL_AEC'            | 'CHIPR0402'    | ''          | ''            | '20160727'
 '10K'        | '1%'      | '1/16W'  | '0402LF'  | 'CHIP'   | 'CS31002FB14'(!)        = ''              | ''                 | 'CS31002FB14'           | 'R0402'             | '(R0402-0201)'                 | '10K'     | '1%'    | '1/16W'  | 'DISCRETE' | 'RES CHIP 10K 1/16W +-1%(0402)DAL_AEC'             | 'CHIPR0402'    | ''          | ''            | '20160727'
 '10K'        | '1%'      | '1/16W'  | '0402LF'  | 'EMPTY'  | 'CS31002FB14'(!)        = ''              | ''                 | 'CS31002FB14'           | 'R0402'             | '(R0402-0201)'                 | '10K'     | '1%'    | '1/16W'  | 'IO'       | 'RES CHIP 10K 1/16W +-1%(0402)DAL_AEC'             | 'CHIPR0402'    | ''          | ''            | '20160727'
 '11K'        | '1%'      | '1/16W'  | '0402LF'  | 'CHIP'   | 'CS31102FB07'(!)        = ''              | ''                 | 'CS31102FB07'           | 'R0402'             | '(R0402-0201)'                 | '11K'     | '1%'    | '1/16W'  | 'DISCRETE' | 'RES CHIP 11K 1/16W +-1% (0402)DAL_AEC'            | 'CHIPR0402'    | ''          | ''            | '20160727'
 '11K'        | '1%'      | '1/16W'  | '0402LF'  | 'EMPTY'  | 'CS31102FB07'(!)        = ''              | ''                 | 'CS31102FB07'           | 'R0402'             | '(R0402-0201)'                 | '11K'     | '1%'    | '1/16W'  | 'IO'       | 'RES CHIP 11K 1/16W +-1% (0402)DAL_AEC'            | 'CHIPR0402'    | ''          | ''            | '20160727'
 '12K'        | '1%'      | '1/16W'  | '0402LF'  | 'CHIP'   | 'CS31202FB06'(!)        = ''              | ''                 | 'CS31202FB06'           | 'R0402'             | '(R0402-0201)'                 | '12K'     | '1%'    | '1/16W'  | 'DISCRETE' | 'RES CHIP 12K 1/16W +-1%(0402)DAL_AEC'             | 'CHIPR0402'    | ''          | ''            | '20160727'
 '12K'        | '1%'      | '1/16W'  | '0402LF'  | 'EMPTY'  | 'CS31202FB06'(!)        = ''              | ''                 | 'CS31202FB06'           | 'R0402'             | '(R0402-0201)'                 | '12K'     | '1%'    | '1/16W'  | 'IO'       | 'RES CHIP 12K 1/16W +-1%(0402)DAL_AEC'             | 'CHIPR0402'    | ''          | ''            | '20160727'
 '12.1K'      | '1%'      | '1/16W'  | '0402LF'  | 'CHIP'   | 'CS31212FB07'(!)        = ''              | ''                 | 'CS31212FB07'           | 'R0402'             | '(R0402-0201)'                 | '12.1K'   | '1%'    | '1/16W'  | 'DISCRETE' | 'RES CHIP 12.1K 1/16W +1%(0402)DAL_AEC'            | 'CHIPR0402'    | ''          | ''            | '20160727'
 '12.1K'      | '1%'      | '1/16W'  | '0402LF'  | 'EMPTY'  | 'CS31212FB07'(!)        = ''              | ''                 | 'CS31212FB07'           | 'R0402'             | '(R0402-0201)'                 | '12.1K'   | '1%'    | '1/16W'  | 'IO'       | 'RES CHIP 12.1K 1/16W +1%(0402)DAL_AEC'            | 'CHIPR0402'    | ''          | ''            | '20160727'
 '13.7K'      | '1%'      | '1/16W'  | '0402LF'  | 'CHIP'   | 'CS31372FB04'(!)        = ''              | ''                 | 'CS31372FB04'           | 'R0402'             | '(R0402-0201)'                 | '13.7K'   | '1%'    | '1/16W'  | 'DISCRETE' | 'RES CHIP 13.7K 1/16W +-1%(0402)DAL_AEC'           | 'CHIPR0402'    | ''          | ''            | '20160727'
 '13.7K'      | '1%'      | '1/16W'  | '0402LF'  | 'EMPTY'  | 'CS31372FB04'(!)        = ''              | ''                 | 'CS31372FB04'           | 'R0402'             | '(R0402-0201)'                 | '13.7K'   | '1%'    | '1/16W'  | 'IO'       | 'RES CHIP 13.7K 1/16W +-1%(0402)DAL_AEC'           | 'CHIPR0402'    | ''          | ''            | '20160727'
 '15K'        | '1%'      | '1/16W'  | '0402LF'  | 'CHIP'   | 'CS31502FB07'(!)        = ''              | ''                 | 'CS31502FB07'           | 'R0402'             | '(R0402-0201)'                 | '15K'     | '1%'    | '1/16W'  | 'DISCRETE' | 'RES CHIP 15K 1/16W +-1%(0402)DAL_AEC'             | 'CHIPR0402'    | ''          | ''            | '20160727'
 '15K'        | '1%'      | '1/16W'  | '0402LF'  | 'EMPTY'  | 'CS31502FB07'(!)        = ''              | ''                 | 'CS31502FB07'           | 'R0402'             | '(R0402-0201)'                 | '15K'     | '1%'    | '1/16W'  | 'IO'       | 'RES CHIP 15K 1/16W +-1%(0402)DAL_AEC'             | 'CHIPR0402'    | ''          | ''            | '20160727'
 '15.4K'      | '1%'      | '1/16W'  | '0402LF'  | 'CHIP'   | 'CS31542FB03'(!)        = ''              | ''                 | 'CS31542FB03'           | 'R0402'             | '(R0402-0201)'                 | '15.4K'   | '1%'    | '1/16W'  | 'DISCRETE' | 'RES CHIP 15.4K 1/16W +1%(0402)DAL_AEC'            | 'CHIPR0402'    | ''          | ''            | '20160727'
 '15.4K'      | '1%'      | '1/16W'  | '0402LF'  | 'EMPTY'  | 'CS31542FB03'(!)        = ''              | ''                 | 'CS31542FB03'           | 'R0402'             | '(R0402-0201)'                 | '15.4K'   | '1%'    | '1/16W'  | 'IO'       | 'RES CHIP 15.4K 1/16W +1%(0402)DAL_AEC'            | 'CHIPR0402'    | ''          | ''            | '20160727'
 '15.8K'      | '1%'      | '1/16W'  | '0402LF'  | 'CHIP'   | 'CS31582FB05'(!)        = ''              | ''                 | 'CS31582FB05'           | 'R0402'             | '(R0402-0201)'                 | '15.8K'   | '1%'    | '1/16W'  | 'DISCRETE' | 'RES CHIP 15.8K 1/16W +-1% (0402)DAL_AEC'          | 'CHIPR0402'    | ''          | ''            | '20160727'
 '15.8K'      | '1%'      | '1/16W'  | '0402LF'  | 'EMPTY'  | 'CS31582FB05'(!)        = ''              | ''                 | 'CS31582FB05'           | 'R0402'             | '(R0402-0201)'                 | '15.8K'   | '1%'    | '1/16W'  | 'IO'       | 'RES CHIP 15.8K 1/16W +-1% (0402)DAL_AEC'          | 'CHIPR0402'    | ''          | ''            | '20160727'
 '16K'        | '1%'      | '1/16W'  | '0402LF'  | 'CHIP'   | 'CS31602FB03'(!)        = ''              | ''                 | 'CS31602FB03'           | 'R0402'             | '(R0402-0201)'                 | '16K'     | '1%'    | '1/16W'  | 'DISCRETE' | 'RES CHIP 16K 1/16W +-1%(0402)DAL_AEC'             | 'CHIPR0402'    | ''          | ''            | '20160727'
 '16K'        | '1%'      | '1/16W'  | '0402LF'  | 'EMPTY'  | 'CS31602FB03'(!)        = ''              | ''                 | 'CS31602FB03'           | 'R0402'             | '(R0402-0201)'                 | '16K'     | '1%'    | '1/16W'  | 'IO'       | 'RES CHIP 16K 1/16W +-1%(0402)DAL_AEC'             | 'CHIPR0402'    | ''          | ''            | '20160727'
 '20K'        | '1%'      | '1/16W'  | '0402LF'  | 'CHIP'   | 'CS32002FB13'(!)        = ''              | ''                 | 'CS32002FB13'           | 'R0402'             | '(R0402-0201)'                 | '20K'     | '1%'    | '1/16W'  | 'DISCRETE' | 'RES CHIP 20K 1/16W +-1%(0402)DAL_AEC'             | 'CHIPR0402'    | ''          | ''            | '20160727'
 '20K'        | '1%'      | '1/16W'  | '0402LF'  | 'EMPTY'  | 'CS32002FB13'(!)        = ''              | ''                 | 'CS32002FB13'           | 'R0402'             | '(R0402-0201)'                 | '20K'     | '1%'    | '1/16W'  | 'IO'       | 'RES CHIP 20K 1/16W +-1%(0402)DAL_AEC'             | 'CHIPR0402'    | ''          | ''            | '20160727'
 '21K'        | '1%'      | '1/16W'  | '0402LF'  | 'CHIP'   | 'CS32102FB04'(!)        = ''              | ''                 | 'CS32102FB04'           | 'R0402'             | '(R0402-0201)'                 | '21K'     | '1%'    | '1/16W'  | 'DISCRETE' | 'RES CHIP 21K 1/16W +-1%(0402)DAL_AEC'             | 'CHIPR0402'    | ''          | ''            | '20160727'
 '21K'        | '1%'      | '1/16W'  | '0402LF'  | 'EMPTY'  | 'CS32102FB04'(!)        = ''              | ''                 | 'CS32102FB04'           | 'R0402'             | '(R0402-0201)'                 | '21K'     | '1%'    | '1/16W'  | 'IO'       | 'RES CHIP 21K 1/16W +-1%(0402)DAL_AEC'             | 'CHIPR0402'    | ''          | ''            | '20160727'
 '22.1K'      | '1%'      | '1/16W'  | '0402LF'  | 'CHIP'   | 'CS32212FB03'(!)        = ''              | ''                 | 'CS32212FB03'           | 'R0402'             | '(R0402-0201)'                 | '22.1K'   | '1%'    | '1/16W'  | 'DISCRETE' | 'RES CHIP 22.1K 1/16W +-1%(0402)DAL_AEC'           | 'CHIPR0402'    | ''          | ''            | '20160727'
 '22.1K'      | '1%'      | '1/16W'  | '0402LF'  | 'EMPTY'  | 'CS32212FB03'(!)        = ''              | ''                 | 'CS32212FB03'           | 'R0402'             | '(R0402-0201)'                 | '22.1K'   | '1%'    | '1/16W'  | 'IO'       | 'RES CHIP 22.1K 1/16W +-1%(0402)DAL_AEC'           | 'CHIPR0402'    | ''          | ''            | '20160727'
 '3.3'        | '1%'      | '1/16W'  | '0402LF'  | 'CHIP'   | 'CS-3302FB03'(!)        = ''              | ''                 | 'CS-3302FB03'           | 'R0402'             | '(R0402-0201)'                 | '3.3'     | '1%'    | '1/16W'  | 'DISCRETE' | 'RES CHIP 3.3 1/16W +-1%(0402)DAL_AEC'             | 'CHIPR0402'    | ''          | ''            | '20160727'
 '3.3'        | '1%'      | '1/16W'  | '0402LF'  | 'EMPTY'  | 'CS-3302FB03'(!)        = ''              | ''                 | 'CS-3302FB03'           | 'R0402'             | '(R0402-0201)'                 | '3.3'     | '1%'    | '1/16W'  | 'IO'       | 'RES CHIP 3.3 1/16W +-1%(0402)DAL_AEC'             | 'CHIPR0402'    | ''          | ''            | '20160727'
 '237'        | '1%'      | '1/16W'  | '0402LF'  | 'CHIP'   | 'CS12372FB00'(!)        = 'End of Design' | 'Comp-Approve'     | 'CS12372FB00'           | 'R0402'             | '(R0402-0201)'                 | '237'     | '1%'    | '1/16W'  | 'DISCRETE' | 'RES CHIP 237 1/16W +-1%(0402)'                    | 'CHIPR0402'    | ''          | ''            | '20160727'
 '237'        | '1%'      | '1/16W'  | '0402LF'  | 'EMPTY'  | 'CS12372FB00'(!)        = 'End of Design' | 'Comp-Approve'     | 'CS12372FB00'           | 'R0402'             | '(R0402-0201)'                 | '237'     | '1%'    | '1/16W'  | 'IO'       | 'RES CHIP 237 1/16W +-1%(0402)'                    | 'CHIPR0402'    | ''          | ''            | '20160727'
 '31.6K'      | '1%'      | '1/16W'  | '0402LF'  | 'CHIP'   | 'CS33162FB03'(!)        = ''              | ''                 | 'CS33162FB03'           | 'R0402'             | '(R0402-0201)'                 | '31.6K'   | '1%'    | '1/16W'  | 'DISCRETE' | 'RES CHIP 31.6K 1/16W +1%(0402)DAL_AEC'            | 'CHIPR0402'    | ''          | ''            | '20160802'
 '31.6K'      | '1%'      | '1/16W'  | '0402LF'  | 'EMPTY'  | 'CS33162FB03'(!)        = ''              | ''                 | 'CS33162FB03'           | 'R0402'             | '(R0402-0201)'                 | '31.6K'   | '1%'    | '1/16W'  | 'IO'       | 'RES CHIP 31.6K 1/16W +1%(0402)DAL_AEC'            | 'CHIPR0402'    | ''          | ''            | '20160802'
 '27K'        | '1%'      | '1/16W'  | '0402LF'  | 'CHIP'   | 'CS32702FB02'(!)        = ''              | ''                 | 'CS32702FB02'           | 'R0402'             | '(R0402-0201)'                 | '27K'     | '1%'    | '1/16W'  | 'DISCRETE' | 'RES CHIP 27K 1/16W +-1%(0402)DAL_AEC'             | 'CHIPR0402'    | ''          | ''            | '20160802'
 '27K'        | '1%'      | '1/16W'  | '0402LF'  | 'EMPTY'  | 'CS32702FB02'(!)        = ''              | ''                 | 'CS32702FB02'           | 'R0402'             | '(R0402-0201)'                 | '27K'     | '1%'    | '1/16W'  | 'IO'       | 'RES CHIP 27K 1/16W +-1%(0402)DAL_AEC'             | 'CHIPR0402'    | ''          | ''            | '20160802'
 '27.4K'      | '1%'      | '1/16W'  | '0402LF'  | 'CHIP'   | 'CS32742FB05'(!)        = ''              | ''                 | 'CS32742FB05'           | 'R0402'             | '(R0402-0201)'                 | '27.4K'   | '1%'    | '1/16W'  | 'DISCRETE' | 'RES CHIP 27.4K 1/16W +-1%(0402)DAL_AEC'           | 'CHIPR0402'    | ''          | ''            | '20160802'
 '27.4K'      | '1%'      | '1/16W'  | '0402LF'  | 'EMPTY'  | 'CS32742FB05'(!)        = ''              | ''                 | 'CS32742FB05'           | 'R0402'             | '(R0402-0201)'                 | '27.4K'   | '1%'    | '1/16W'  | 'IO'       | 'RES CHIP 27.4K 1/16W +-1%(0402)DAL_AEC'           | 'CHIPR0402'    | ''          | ''            | '20160802'
 '25.5K'      | '1%'      | '1/16W'  | '0402LF'  | 'CHIP'   | 'CS32552FB05'(!)        = ''              | ''                 | 'CS32552FB05'           | 'R0402'             | '(R0402-0201)'                 | '25.5K'   | '1%'    | '1/16W'  | 'DISCRETE' | 'RES CHIP 25.5K 1/16W +-1%(0402)DAL_AEC'           | 'CHIPR0402'    | ''          | ''            | '20160802'
 '25.5K'      | '1%'      | '1/16W'  | '0402LF'  | 'EMPTY'  | 'CS32552FB05'(!)        = ''              | ''                 | 'CS32552FB05'           | 'R0402'             | '(R0402-0201)'                 | '25.5K'   | '1%'    | '1/16W'  | 'IO'       | 'RES CHIP 25.5K 1/16W +-1%(0402)DAL_AEC'           | 'CHIPR0402'    | ''          | ''            | '20160802'
 '41.2K'      | '1%'      | '1/16W'  | '0402LF'  | 'CHIP'   | 'CS34122FB02'(!)        = ''              | ''                 | 'CS34122FB02'           | 'R0402'             | '(R0402-0201)'                 | '41.2K'   | '1%'    | '1/16W'  | 'DISCRETE' | 'RES CHIP 41.2K 1/16W +-1%(0402)DAL_AEC'           | 'CHIPR0402'    | ''          | ''            | '20160802'
 '41.2K'      | '1%'      | '1/16W'  | '0402LF'  | 'EMPTY'  | 'CS34122FB02'(!)        = ''              | ''                 | 'CS34122FB02'           | 'R0402'             | '(R0402-0201)'                 | '41.2K'   | '1%'    | '1/16W'  | 'IO'       | 'RES CHIP 41.2K 1/16W +-1%(0402)DAL_AEC'           | 'CHIPR0402'    | ''          | ''            | '20160802'
 '37.4K'      | '1%'      | '1/16W'  | '0402LF'  | 'CHIP'   | 'CS33742FB07'(!)        = ''              | ''                 | 'CS33742FB07'           | 'R0402'             | '(R0402-0201)'                 | '37.4K'   | '1%'    | '1/16W'  | 'DISCRETE' | 'RES CHIP 37.4K 1/16W +-1% (0402)DAL_AEC'          | 'CHIPR0402'    | ''          | ''            | '20160802'
 '37.4K'      | '1%'      | '1/16W'  | '0402LF'  | 'EMPTY'  | 'CS33742FB07'(!)        = ''              | ''                 | 'CS33742FB07'           | 'R0402'             | '(R0402-0201)'                 | '37.4K'   | '1%'    | '1/16W'  | 'IO'       | 'RES CHIP 37.4K 1/16W +-1% (0402)DAL_AEC'          | 'CHIPR0402'    | ''          | ''            | '20160802'
 '34K'        | '1%'      | '1/16W'  | '0402LF'  | 'CHIP'   | 'CS33402FB04'(!)        = ''              | ''                 | 'CS33402FB04'           | 'R0402'             | '(R0402-0201)'                 | '34K'     | '1%'    | '1/16W'  | 'DISCRETE' | 'RES CHIP 34K 1/16W +-1%(0402)DAL_AEC'             | 'CHIPR0402'    | ''          | ''            | '20160802'
 '34K'        | '1%'      | '1/16W'  | '0402LF'  | 'EMPTY'  | 'CS33402FB04'(!)        = ''              | ''                 | 'CS33402FB04'           | 'R0402'             | '(R0402-0201)'                 | '34K'     | '1%'    | '1/16W'  | 'IO'       | 'RES CHIP 34K 1/16W +-1%(0402)DAL_AEC'             | 'CHIPR0402'    | ''          | ''            | '20160802'
 '34.8K'      | '1%'      | '1/16W'  | '0402LF'  | 'CHIP'   | 'CS33482FB02'(!)        = ''              | ''                 | 'CS33482FB02'           | 'R0402'             | '(R0402-0201)'                 | '34.8K'   | '1%'    | '1/16W'  | 'DISCRETE' | 'RES CHIP 34.8K 1/16W +-1% (0402)DAL_AEC'          | 'CHIPR0402'    | ''          | ''            | '20160803'
 '34.8K'      | '1%'      | '1/16W'  | '0402LF'  | 'EMPTY'  | 'CS33482FB02'(!)        = ''              | ''                 | 'CS33482FB02'           | 'R0402'             | '(R0402-0201)'                 | '34.8K'   | '1%'    | '1/16W'  | 'IO'       | 'RES CHIP 34.8K 1/16W +-1% (0402)DAL_AEC'          | 'CHIPR0402'    | ''          | ''            | '20160803'
 '47K'        | '1%'      | '1/16W'  | '0402LF'  | 'CHIP'   | 'CS34702FB04'(!)        = ''              | ''                 | 'CS34702FB04'           | 'R0402'             | '(R0402-0201)'                 | '47K'     | '1%'    | '1/16W'  | 'DISCRETE' | 'RES CHIP 47K 1/16W +-1%(0402)DAL_AEC'             | 'CHIPR0402'    | ''          | ''            | '20160803'
 '47K'        | '1%'      | '1/16W'  | '0402LF'  | 'EMPTY'  | 'CS34702FB04'(!)        = ''              | ''                 | 'CS34702FB04'           | 'R0402'             | '(R0402-0201)'                 | '47K'     | '1%'    | '1/16W'  | 'IO'       | 'RES CHIP 47K 1/16W +-1%(0402)DAL_AEC'             | 'CHIPR0402'    | ''          | ''            | '20160803'
 '45.3K'      | '1%'      | '1/16W'  | '0402LF'  | 'CHIP'   | 'CS34532FB06'(!)        = ''              | ''                 | 'CS34532FB06'           | 'R0402'             | '(R0402-0201)'                 | '45.3K'   | '1%'    | '1/16W'  | 'DISCRETE' | 'RES CHIP 45.3K 1/16W +-1% (0402)DAL_AEC'          | 'CHIPR0402'    | ''          | ''            | '20160803'
 '45.3K'      | '1%'      | '1/16W'  | '0402LF'  | 'EMPTY'  | 'CS34532FB06'(!)        = ''              | ''                 | 'CS34532FB06'           | 'R0402'             | '(R0402-0201)'                 | '45.3K'   | '1%'    | '1/16W'  | 'IO'       | 'RES CHIP 45.3K 1/16W +-1% (0402)DAL_AEC'          | 'CHIPR0402'    | ''          | ''            | '20160803'
 '64.9K'      | '1%'      | '1/16W'  | '0402LF'  | 'CHIP'   | 'CS36492FB04'(!)        = ''              | ''                 | 'CS36492FB04'           | 'R0402'             | '(R0402-0201)'                 | '64.9K'   | '1%'    | '1/16W'  | 'DISCRETE' | 'RES CHIP 64.9K 1/16W +1%(0402)DAL_AEC'            | 'CHIPR0402'    | ''          | ''            | '20160803'
 '64.9K'      | '1%'      | '1/16W'  | '0402LF'  | 'EMPTY'  | 'CS36492FB04'(!)        = ''              | ''                 | 'CS36492FB04'           | 'R0402'             | '(R0402-0201)'                 | '64.9K'   | '1%'    | '1/16W'  | 'IO'       | 'RES CHIP 64.9K 1/16W +1%(0402)DAL_AEC'            | 'CHIPR0402'    | ''          | ''            | '20160803'
 '60.4K'      | '1%'      | '1/16W'  | '0402LF'  | 'CHIP'   | 'CS36042FB05'(!)        = ''              | ''                 | 'CS36042FB05'           | 'R0402'             | '(R0402-0201)'                 | '60.4K'   | '1%'    | '1/16W'  | 'DISCRETE' | 'RES CHIP 60.4K 1/16W +-1%(0402)DAL_AEC'           | 'CHIPR0402'    | ''          | ''            | '20160803'
 '60.4K'      | '1%'      | '1/16W'  | '0402LF'  | 'EMPTY'  | 'CS36042FB05'(!)        = ''              | ''                 | 'CS36042FB05'           | 'R0402'             | '(R0402-0201)'                 | '60.4K'   | '1%'    | '1/16W'  | 'IO'       | 'RES CHIP 60.4K 1/16W +-1%(0402)DAL_AEC'           | 'CHIPR0402'    | ''          | ''            | '20160803'
 '53.6K'      | '1%'      | '1/16W'  | '0402LF'  | 'CHIP'   | 'CS35362FB04'(!)        = ''              | ''                 | 'CS35362FB04'           | 'R0402'             | '(R0402-0201)'                 | '53.6K'   | '1%'    | '1/16W'  | 'DISCRETE' | 'RES CHIP 53.6K 1/16W +1%(0402)DAL_AEC'            | 'CHIPR0402'    | ''          | ''            | '20160803'
 '53.6K'      | '1%'      | '1/16W'  | '0402LF'  | 'EMPTY'  | 'CS35362FB04'(!)        = ''              | ''                 | 'CS35362FB04'           | 'R0402'             | '(R0402-0201)'                 | '53.6K'   | '1%'    | '1/16W'  | 'IO'       | 'RES CHIP 53.6K 1/16W +1%(0402)DAL_AEC'            | 'CHIPR0402'    | ''          | ''            | '20160803'
 '56.2K'      | '1%'      | '1/16W'  | '0402LF'  | 'CHIP'   | 'CS35622FB04'(!)        = ''              | ''                 | 'CS35622FB04'           | 'R0402'             | '(R0402-0201)'                 | '56.2K'   | '1%'    | '1/16W'  | 'DISCRETE' | 'RES CHIP 56.2K 1/16W +-1% (0402)DAL_AEC'          | 'CHIPR0402'    | ''          | ''            | '20160803'
 '56.2K'      | '1%'      | '1/16W'  | '0402LF'  | 'EMPTY'  | 'CS35622FB04'(!)        = ''              | ''                 | 'CS35622FB04'           | 'R0402'             | '(R0402-0201)'                 | '56.2K'   | '1%'    | '1/16W'  | 'IO'       | 'RES CHIP 56.2K 1/16W +-1% (0402)DAL_AEC'          | 'CHIPR0402'    | ''          | ''            | '20160803'
 '49.9K'      | '1%'      | '1/16W'  | '0402LF'  | 'CHIP'   | 'CS34992FB07'(!)        = ''              | ''                 | 'CS34992FB07'           | 'R0402'             | '(R0402-0201)'                 | '49.9K'   | '1%'    | '1/16W'  | 'DISCRETE' | 'RES CHIP 49.9K 1/16W +-1%(0402)DAL_AEC'           | 'CHIPR0402'    | ''          | ''            | '20160803'
 '49.9K'      | '1%'      | '1/16W'  | '0402LF'  | 'EMPTY'  | 'CS34992FB07'(!)        = ''              | ''                 | 'CS34992FB07'           | 'R0402'             | '(R0402-0201)'                 | '49.9K'   | '1%'    | '1/16W'  | 'IO'       | 'RES CHIP 49.9K 1/16W +-1%(0402)DAL_AEC'           | 'CHIPR0402'    | ''          | ''            | '20160803'
 '68K'        | '1%'      | '1/16W'  | '0402LF'  | 'CHIP'   | 'CS36802FB03'(!)        = ''              | ''                 | 'CS36802FB03'           | 'R0402'             | '(R0402-0201)'                 | '68K'     | '1%'    | '1/16W'  | 'DISCRETE' | 'RES CHIP 68K 1/16W +1%(0402)DAL_AEC'              | 'CHIPR0402'    | ''          | ''            | '20160803'
 '68K'        | '1%'      | '1/16W'  | '0402LF'  | 'EMPTY'  | 'CS36802FB03'(!)        = ''              | ''                 | 'CS36802FB03'           | 'R0402'             | '(R0402-0201)'                 | '68K'     | '1%'    | '1/16W'  | 'IO'       | 'RES CHIP 68K 1/16W +1%(0402)DAL_AEC'              | 'CHIPR0402'    | ''          | ''            | '20160803'
 '66.5K'      | '1%'      | '1/16W'  | '0402LF'  | 'CHIP'   | 'CS36652FB02'(!)        = ''              | ''                 | 'CS36652FB02'           | 'R0402'             | '(R0402-0201)'                 | '66.5K'   | '1%'    | '1/16W'  | 'DISCRETE' | 'RES CHIP 66.5K 1/16W +-1%(0402)DAL_AEC'           | 'CHIPR0402'    | ''          | ''            | '20160803'
 '66.5K'      | '1%'      | '1/16W'  | '0402LF'  | 'EMPTY'  | 'CS36652FB02'(!)        = ''              | ''                 | 'CS36652FB02'           | 'R0402'             | '(R0402-0201)'                 | '66.5K'   | '1%'    | '1/16W'  | 'IO'       | 'RES CHIP 66.5K 1/16W +-1%(0402)DAL_AEC'           | 'CHIPR0402'    | ''          | ''            | '20160803'
 '82K'        | '1%'      | '1/16W'  | '0402LF'  | 'CHIP'   | 'CS38202FB00'(!)        = ''              | ''                 | 'CS38202FB00'           | 'R0402'             | '(R0402-0201)'                 | '82K'     | '1%'    | '1/16W'  | 'DISCRETE' | 'RES CHIP 82K 1/16W +1%(0402)DAL_AEC'              | 'CHIPR0402'    | ''          | ''            | '20160803'
 '82K'        | '1%'      | '1/16W'  | '0402LF'  | 'EMPTY'  | 'CS38202FB00'(!)        = ''              | ''                 | 'CS38202FB00'           | 'R0402'             | '(R0402-0201)'                 | '82K'     | '1%'    | '1/16W'  | 'IO'       | 'RES CHIP 82K 1/16W +1%(0402)DAL_AEC'              | 'CHIPR0402'    | ''          | ''            | '20160803'
 '86.6K'      | '1%'      | '1/16W'  | '0402LF'  | 'CHIP'   | 'CS38662FB03'(!)        = ''              | ''                 | 'CS38662FB03'           | 'R0402'             | '(R0402-0201)'                 | '86.6K'   | '1%'    | '1/16W'  | 'DISCRETE' | 'RES CHIP 86.6K 1/16W +-1%(0402)DAL_AEC'           | 'CHIPR0402'    | ''          | ''            | '20160803'
 '86.6K'      | '1%'      | '1/16W'  | '0402LF'  | 'EMPTY'  | 'CS38662FB03'(!)        = ''              | ''                 | 'CS38662FB03'           | 'R0402'             | '(R0402-0201)'                 | '86.6K'   | '1%'    | '1/16W'  | 'IO'       | 'RES CHIP 86.6K 1/16W +-1%(0402)DAL_AEC'           | 'CHIPR0402'    | ''          | ''            | '20160803'
 '75K'        | '1%'      | '1/16W'  | '0402LF'  | 'CHIP'   | 'CS37502FB06'(!)        = ''              | ''                 | 'CS37502FB06'           | 'R0402'             | '(R0402-0201)'                 | '75K'     | '1%'    | '1/16W'  | 'DISCRETE' | 'RES CHIP 75K 1/16W +-1%(0402)DAL_AEC'             | 'CHIPR0402'    | ''          | ''            | '20160803'
 '75K'        | '1%'      | '1/16W'  | '0402LF'  | 'EMPTY'  | 'CS37502FB06'(!)        = ''              | ''                 | 'CS37502FB06'           | 'R0402'             | '(R0402-0201)'                 | '75K'     | '1%'    | '1/16W'  | 'IO'       | 'RES CHIP 75K 1/16W +-1%(0402)DAL_AEC'             | 'CHIPR0402'    | ''          | ''            | '20160803'
 '80.6K'      | '1%'      | '1/16W'  | '0402LF'  | 'CHIP'   | 'CS38062FB07'(!)        = ''              | ''                 | 'CS38062FB07'           | 'R0402'             | '(R0402-0201)'                 | '80.6K'   | '1%'    | '1/16W'  | 'DISCRETE' | 'RES CHIP 80.6K 1/16W +-1% (0402)DAL_AEC'          | 'CHIPR0402'    | ''          | ''            | '20160803'
 '80.6K'      | '1%'      | '1/16W'  | '0402LF'  | 'EMPTY'  | 'CS38062FB07'(!)        = ''              | ''                 | 'CS38062FB07'           | 'R0402'             | '(R0402-0201)'                 | '80.6K'   | '1%'    | '1/16W'  | 'IO'       | 'RES CHIP 80.6K 1/16W +-1% (0402)DAL_AEC'          | 'CHIPR0402'    | ''          | ''            | '20160803'
 '69.8K'      | '1%'      | '1/16W'  | '0402LF'  | 'CHIP'   | 'CS36982FB05'(!)        = ''              | ''                 | 'CS36982FB05'           | 'R0402'             | '(R0402-0201)'                 | '69.8K'   | '1%'    | '1/16W'  | 'DISCRETE' | 'RES CHIP 69.8K 1/16W +-1% (0402)DAL_AEC'          | 'CHIPR0402'    | ''          | ''            | '20160803'
 '69.8K'      | '1%'      | '1/16W'  | '0402LF'  | 'EMPTY'  | 'CS36982FB05'(!)        = ''              | ''                 | 'CS36982FB05'           | 'R0402'             | '(R0402-0201)'                 | '69.8K'   | '1%'    | '1/16W'  | 'IO'       | 'RES CHIP 69.8K 1/16W +-1% (0402)DAL_AEC'          | 'CHIPR0402'    | ''          | ''            | '20160803'
 '100K'       | '1%'      | '1/16W'  | '0402LF'  | 'CHIP'   | 'CS41002FB17'(!)        = ''              | ''                 | 'CS41002FB17'           | 'R0402'             | '(R0402-0201)'                 | '100K'    | '1%'    | '1/16W'  | 'DISCRETE' | 'RES CHIP 100K 1/16W +-1%(0402) DAL_AEC'           | 'CHIPR0402'    | ''          | ''            | '20160803'
 '100K'       | '1%'      | '1/16W'  | '0402LF'  | 'EMPTY'  | 'CS41002FB17'(!)        = ''              | ''                 | 'CS41002FB17'           | 'R0402'             | '(R0402-0201)'                 | '100K'    | '1%'    | '1/16W'  | 'IO'       | 'RES CHIP 100K 1/16W +-1%(0402) DAL_AEC'           | 'CHIPR0402'    | ''          | ''            | '20160803'
 '107K'       | '1%'      | '1/16W'  | '0402LF'  | 'CHIP'   | 'CS41072FB01'(!)        = ''              | ''                 | 'CS41072FB01'           | 'R0402'             | '(R0402-0201)'                 | '107K'    | '1%'    | '1/16W'  | 'DISCRETE' | 'RES CHIP 107K 1/16W +1%(0402)DAL_AEC'             | 'CHIPR0402'    | ''          | ''            | '20160805'
 '107K'       | '1%'      | '1/16W'  | '0402LF'  | 'EMPTY'  | 'CS41072FB01'(!)        = ''              | ''                 | 'CS41072FB01'           | 'R0402'             | '(R0402-0201)'                 | '107K'    | '1%'    | '1/16W'  | 'IO'       | 'RES CHIP 107K 1/16W +1%(0402)DAL_AEC'             | 'CHIPR0402'    | ''          | ''            | '20160805'
 '150K'       | '1%'      | '1/16W'  | '0402LF'  | 'CHIP'   | 'CS41502FB06'(!)        = ''              | ''                 | 'CS41502FB06'           | 'R0402'             | '(R0402-0201)'                 | '150K'    | '1%'    | '1/16W'  | 'DISCRETE' | 'RES CHIP 150K 1/16W +-1%(0402)DAL_AEC'            | 'CHIPR0402'    | ''          | ''            | '20160805'
 '150K'       | '1%'      | '1/16W'  | '0402LF'  | 'EMPTY'  | 'CS41502FB06'(!)        = ''              | ''                 | 'CS41502FB06'           | 'R0402'             | '(R0402-0201)'                 | '150K'    | '1%'    | '1/16W'  | 'IO'       | 'RES CHIP 150K 1/16W +-1%(0402)DAL_AEC'            | 'CHIPR0402'    | ''          | ''            | '20160805'
 '147K'       | '1%'      | '1/16W'  | '0402LF'  | 'CHIP'   | 'CS41472FB05'(!)        = ''              | ''                 | 'CS41472FB05'           | 'R0402'             | '(R0402-0201)'                 | '147K'    | '1%'    | '1/16W'  | 'DISCRETE' | 'RES CHIP 147K 1/16W +-1%(0402)DAL_AEC'            | 'CHIPR0402'    | ''          | ''            | '20160805'
 '147K'       | '1%'      | '1/16W'  | '0402LF'  | 'EMPTY'  | 'CS41472FB05'(!)        = ''              | ''                 | 'CS41472FB05'           | 'R0402'             | '(R0402-0201)'                 | '147K'    | '1%'    | '1/16W'  | 'IO'       | 'RES CHIP 147K 1/16W +-1%(0402)DAL_AEC'            | 'CHIPR0402'    | ''          | ''            | '20160805'
 '143K'       | '1%'      | '1/16W'  | '0402LF'  | 'CHIP'   | 'CS41432FB03'(!)        = ''              | ''                 | 'CS41432FB03'           | 'R0402'             | '(R0402-0201)'                 | '143K'    | '1%'    | '1/16W'  | 'DISCRETE' | 'RES CHIP 143K 1/16W +-1%(0402)DAL_AEC'            | 'CHIPR0402'    | ''          | ''            | '20160805'
 '143K'       | '1%'      | '1/16W'  | '0402LF'  | 'EMPTY'  | 'CS41432FB03'(!)        = ''              | ''                 | 'CS41432FB03'           | 'R0402'             | '(R0402-0201)'                 | '143K'    | '1%'    | '1/16W'  | 'IO'       | 'RES CHIP 143K 1/16W +-1%(0402)DAL_AEC'            | 'CHIPR0402'    | ''          | ''            | '20160805'
 '115K'       | '1%'      | '1/16W'  | '0402LF'  | 'CHIP'   | 'CS41152FB02'(!)        = ''              | ''                 | 'CS41152FB02'           | 'R0402'             | '(R0402-0201)'                 | '115K'    | '1%'    | '1/16W'  | 'DISCRETE' | 'RES CHIP 115K 1/16W +-1%(0402)DAL_AEC'            | 'CHIPR0402'    | ''          | ''            | '20160805'
 '115K'       | '1%'      | '1/16W'  | '0402LF'  | 'EMPTY'  | 'CS41152FB02'(!)        = ''              | ''                 | 'CS41152FB02'           | 'R0402'             | '(R0402-0201)'                 | '115K'    | '1%'    | '1/16W'  | 'IO'       | 'RES CHIP 115K 1/16W +-1%(0402)DAL_AEC'            | 'CHIPR0402'    | ''          | ''            | '20160805'
 '118K'       | '1%'      | '1/16W'  | '0402LF'  | 'CHIP'   | 'CS41182FB03'(!)        = ''              | ''                 | 'CS41182FB03'           | 'R0402'             | '(R0402-0201)'                 | '118K'    | '1%'    | '1/16W'  | 'DISCRETE' | 'RES CHIP 118K 1/16W +-1%(0402)DAL_AEC'            | 'CHIPR0402'    | ''          | ''            | '20160805'
 '118K'       | '1%'      | '1/16W'  | '0402LF'  | 'EMPTY'  | 'CS41182FB03'(!)        = ''              | ''                 | 'CS41182FB03'           | 'R0402'             | '(R0402-0201)'                 | '118K'    | '1%'    | '1/16W'  | 'IO'       | 'RES CHIP 118K 1/16W +-1%(0402)DAL_AEC'            | 'CHIPR0402'    | ''          | ''            | '20160805'
 '120K'       | '1%'      | '1/16W'  | '0402LF'  | 'CHIP'   | 'CS41202FB02'(!)        = ''              | ''                 | 'CS41202FB02'           | 'R0402'             | '(R0402-0201)'                 | '120K'    | '1%'    | '1/16W'  | 'DISCRETE' | 'RES CHIP 120K 1/16W +-1%( 0402)DAL_AEC'           | 'CHIPR0402'    | ''          | ''            | '20160805'
 '120K'       | '1%'      | '1/16W'  | '0402LF'  | 'EMPTY'  | 'CS41202FB02'(!)        = ''              | ''                 | 'CS41202FB02'           | 'R0402'             | '(R0402-0201)'                 | '120K'    | '1%'    | '1/16W'  | 'IO'       | 'RES CHIP 120K 1/16W +-1%( 0402)DAL_AEC'           | 'CHIPR0402'    | ''          | ''            | '20160805'
 '133K'       | '1%'      | '1/16W'  | '0402LF'  | 'CHIP'   | 'CS41332FB03'(!)        = ''              | ''                 | 'CS41332FB03'           | 'R0402'             | '(R0402-0201)'                 | '133K'    | '1%'    | '1/16W'  | 'DISCRETE' | 'RES CHIP 133K 1/16W +-1%(0402)DAL_AEC'            | 'CHIPR0402'    | ''          | ''            | '20160805'
 '133K'       | '1%'      | '1/16W'  | '0402LF'  | 'EMPTY'  | 'CS41332FB03'(!)        = ''              | ''                 | 'CS41332FB03'           | 'R0402'             | '(R0402-0201)'                 | '133K'    | '1%'    | '1/16W'  | 'IO'       | 'RES CHIP 133K 1/16W +-1%(0402)DAL_AEC'            | 'CHIPR0402'    | ''          | ''            | '20160805'
 '154K'       | '1%'      | '1/16W'  | '0402LF'  | 'CHIP'   | 'CS41542FB07'(!)        = ''              | ''                 | 'CS41542FB07'           | 'R0402'             | '(R0402-0201)'                 | '154K'    | '1%'    | '1/16W'  | 'DISCRETE' | 'RES CHIP 154K 1/16W +-1%(0402)DAL_AEC'            | 'CHIPR0402'    | ''          | ''            | '20160805'
 '154K'       | '1%'      | '1/16W'  | '0402LF'  | 'EMPTY'  | 'CS41542FB07'(!)        = ''              | ''                 | 'CS41542FB07'           | 'R0402'             | '(R0402-0201)'                 | '154K'    | '1%'    | '1/16W'  | 'IO'       | 'RES CHIP 154K 1/16W +-1%(0402)DAL_AEC'            | 'CHIPR0402'    | ''          | ''            | '20160805'
 '162K'       | '1%'      | '1/16W'  | '0402LF'  | 'CHIP'   | 'CS41622FB04'(!)        = ''              | ''                 | 'CS41622FB04'           | 'R0402'             | '(R0402-0201)'                 | '162K'    | '1%'    | '1/16W'  | 'DISCRETE' | 'RES CHIP 162K 1/16W +-1% (0402)DAL_AEC'           | 'CHIPR0402'    | ''          | ''            | '20160805'
 '162K'       | '1%'      | '1/16W'  | '0402LF'  | 'EMPTY'  | 'CS41622FB04'(!)        = ''              | ''                 | 'CS41622FB04'           | 'R0402'             | '(R0402-0201)'                 | '162K'    | '1%'    | '1/16W'  | 'IO'       | 'RES CHIP 162K 1/16W +-1% (0402)DAL_AEC'           | 'CHIPR0402'    | ''          | ''            | '20160805'
 '200K'       | '1%'      | '1/16W'  | '0402LF'  | 'CHIP'   | 'CS42002FB11'(!)        = ''              | ''                 | 'CS42002FB11'           | 'R0402'             | '(R0402-0201)'                 | '200K'    | '1%'    | '1/16W'  | 'DISCRETE' | 'RES CHIP 200K 1/16W +-1%(0402)DAL_AEC'            | 'CHIPR0402'    | ''          | ''            | '20160805'
 '200K'       | '1%'      | '1/16W'  | '0402LF'  | 'EMPTY'  | 'CS42002FB11'(!)        = ''              | ''                 | 'CS42002FB11'           | 'R0402'             | '(R0402-0201)'                 | '200K'    | '1%'    | '1/16W'  | 'IO'       | 'RES CHIP 200K 1/16W +-1%(0402)DAL_AEC'            | 'CHIPR0402'    | ''          | ''            | '20160805'
 '255K'       | '1%'      | '1/16W'  | '0402LF'  | 'CHIP'   | 'CS42552FB04'(!)        = ''              | ''                 | 'CS42552FB04'           | 'R0402'             | '(R0402-0201)'                 | '255K'    | '1%'    | '1/16W'  | 'DISCRETE' | 'RES CHIP 255K 1/16W +-1%(0402)DAL_AEC'            | 'CHIPR0402'    | ''          | ''            | '20160805'
 '255K'       | '1%'      | '1/16W'  | '0402LF'  | 'EMPTY'  | 'CS42552FB04'(!)        = ''              | ''                 | 'CS42552FB04'           | 'R0402'             | '(R0402-0201)'                 | '255K'    | '1%'    | '1/16W'  | 'IO'       | 'RES CHIP 255K 1/16W +-1%(0402)DAL_AEC'            | 'CHIPR0402'    | ''          | ''            | '20160805'
 '20M'        | '5%'      | '1/16W'  | '0402LF'  | 'CHIP'   | 'CS62002JB18'(!)        = ''              | ''                 | 'CS62002JB18'           | 'R0402'             | '(R0402-0201)'                 | '20M'     | '5%'    | '1/16W'  | 'DISCRETE' | 'RES CHIP 20M 1/16W +-5%(0402)'                    | 'CHIPR0402'    | ''          | ''            | '20160808'
 '20M'        | '5%'      | '1/16W'  | '0402LF'  | 'EMPTY'  | 'CS62002JB18'(!)        = ''              | ''                 | 'CS62002JB18'           | 'R0402'             | '(R0402-0201)'                 | '20M'     | '5%'    | '1/16W'  | 'IO'       | 'RES CHIP 20M 1/16W +-5%(0402)'                    | 'CHIPR0402'    | ''          | ''            | '20160808'
 '24'         | '1%'      | '1/16W'  | '0402LF'  | 'CHIP'   | 'CS02402FB00'(!)        = 'End of Design' | 'Comp-Approve'     | 'CS02402FB00'           | 'R0402'             | '(R0402-0201)'                 | '24'      | '1%'    | '1/16W'  | 'DISCRETE' | 'RES CHIP 24 1/16W +-1%(0402)DAL_AEC'              | 'CHIPR0402'    | ''          | ''            | '20160808'
 '24'         | '1%'      | '1/16W'  | '0402LF'  | 'EMPTY'  | 'CS02402FB00'(!)        = 'End of Design' | 'Comp-Approve'     | 'CS02402FB00'           | 'R0402'             | '(R0402-0201)'                 | '24'      | '1%'    | '1/16W'  | 'IO'       | 'RES CHIP 24 1/16W +-1%(0402)DAL_AEC'              | 'CHIPR0402'    | ''          | ''            | '20160808'
 '280K'       | '1%'      | '1/16W'  | '0402LF'  | 'CHIP'   | 'CS42802FB04'(!)        = ''              | ''                 | 'CS42802FB04'           | 'R0402'             | '(R0402-0201)'                 | '280K'    | '1%'    | '1/16W'  | 'DISCRETE' | 'RES CHIP 280K 1/16W +-1%(0402)DAL_AEC'            | 'CHIPR0402'    | ''          | ''            | '20160809'
 '280K'       | '1%'      | '1/16W'  | '0402LF'  | 'EMPTY'  | 'CS42802FB04'(!)        = ''              | ''                 | 'CS42802FB04'           | 'R0402'             | '(R0402-0201)'                 | '280K'    | '1%'    | '1/16W'  | 'IO'       | 'RES CHIP 280K 1/16W +-1%(0402)DAL_AEC'            | 'CHIPR0402'    | ''          | ''            | '20160809'
 '348K'       | '1%'      | '1/16W'  | '0402LF'  | 'CHIP'   | 'CS43482FB03'(!)        = ''              | ''                 | 'CS43482FB03'           | 'R0402'             | '(R0402-0201)'                 | '348K'    | '1%'    | '1/16W'  | 'DISCRETE' | 'RES CHIP 348K 1/16W +-1%( 0402)DAL_AEC'           | 'CHIPR0402'    | ''          | ''            | '20160809'
 '348K'       | '1%'      | '1/16W'  | '0402LF'  | 'EMPTY'  | 'CS43482FB03'(!)        = ''              | ''                 | 'CS43482FB03'           | 'R0402'             | '(R0402-0201)'                 | '348K'    | '1%'    | '1/16W'  | 'IO'       | 'RES CHIP 348K 1/16W +-1%( 0402)DAL_AEC'           | 'CHIPR0402'    | ''          | ''            | '20160809'
 '475K'       | '1%'      | '1/16W'  | '0402LF'  | 'CHIP'   | 'CS44752FB04'(!)        = ''              | ''                 | 'CS44752FB04'           | 'R0402'             | '(R0402-0201)'                 | '475K'    | '1%'    | '1/16W'  | 'DISCRETE' | 'RES CHIP 475K 1/16W +-1%(0402)DAL_AEC'            | 'CHIPR0402'    | ''          | ''            | '20160809'
 '475K'       | '1%'      | '1/16W'  | '0402LF'  | 'EMPTY'  | 'CS44752FB04'(!)        = ''              | ''                 | 'CS44752FB04'           | 'R0402'             | '(R0402-0201)'                 | '475K'    | '1%'    | '1/16W'  | 'IO'       | 'RES CHIP 475K 1/16W +-1%(0402)DAL_AEC'            | 'CHIPR0402'    | ''          | ''            | '20160809'
 '499K'       | '1%'      | '1/16W'  | '0402LF'  | 'CHIP'   | 'CS44992FB02'(!)        = ''              | ''                 | 'CS44992FB02'           | 'R0402'             | '(R0402-0201)'                 | '499K'    | '1%'    | '1/16W'  | 'DISCRETE' | 'RES CHIP 499K 1/16W +1% (0402)DAL_AEC'            | 'CHIPR0402'    | ''          | ''            | '20160809'
 '499K'       | '1%'      | '1/16W'  | '0402LF'  | 'EMPTY'  | 'CS44992FB02'(!)        = ''              | ''                 | 'CS44992FB02'           | 'R0402'             | '(R0402-0201)'                 | '499K'    | '1%'    | '1/16W'  | 'IO'       | 'RES CHIP 499K 1/16W +1% (0402)DAL_AEC'            | 'CHIPR0402'    | ''          | ''            | '20160809'
 '681K'       | '1%'      | '1/16W'  | '0402LF'  | 'CHIP'   | 'CS46812FB04'(!)        = ''              | ''                 | 'CS46812FB04'           | 'R0402'             | '(R0402-0201)'                 | '681K'    | '1%'    | '1/16W'  | 'DISCRETE' | 'RES CHIP 681K 1/16W +-1%(0402)DAL_AEC'            | 'CHIPR0402'    | ''          | ''            | '20160809'
 '681K'       | '1%'      | '1/16W'  | '0402LF'  | 'EMPTY'  | 'CS46812FB04'(!)        = ''              | ''                 | 'CS46812FB04'           | 'R0402'             | '(R0402-0201)'                 | '681K'    | '1%'    | '1/16W'  | 'IO'       | 'RES CHIP 681K 1/16W +-1%(0402)DAL_AEC'            | 'CHIPR0402'    | ''          | ''            | '20160809'
 '1M'         | '1%'      | '1/16W'  | '0402LF'  | 'CHIP'   | 'CS51002FB07'(!)        = ''              | ''                 | 'CS51002FB07'           | 'R0402'             | '(R0402-0201)'                 | '1M'      | '1%'    | '1/16W'  | 'DISCRETE' | 'RES CHIP 1M 1/16W +-1%(0402)DAL_AEC'              | 'CHIPR0402'    | ''          | ''            | '20160809'
 '1M'         | '1%'      | '1/16W'  | '0402LF'  | 'EMPTY'  | 'CS51002FB07'(!)        = ''              | ''                 | 'CS51002FB07'           | 'R0402'             | '(R0402-0201)'                 | '1M'      | '1%'    | '1/16W'  | 'IO'       | 'RES CHIP 1M 1/16W +-1%(0402)DAL_AEC'              | 'CHIPR0402'    | ''          | ''            | '20160809'
 '1.69M'      | '1%'      | '1/16W'  | '0402LF'  | 'CHIP'   | 'CS51692FB02'(!)        = ''              | ''                 | 'CS51692FB02'           | 'R0402'             | '(R0402-0201)'                 | '1.69M'   | '1%'    | '1/16W'  | 'DISCRETE' | 'RES CHIP 1.69M,1/16W +-1%(0402)DAL_AEC'           | 'CHIPR0402'    | ''          | ''            | '20160809'
 '1.69M'      | '1%'      | '1/16W'  | '0402LF'  | 'EMPTY'  | 'CS51692FB02'(!)        = ''              | ''                 | 'CS51692FB02'           | 'R0402'             | '(R0402-0201)'                 | '1.69M'   | '1%'    | '1/16W'  | 'IO'       | 'RES CHIP 1.69M,1/16W +-1%(0402)DAL_AEC'           | 'CHIPR0402'    | ''          | ''            | '20160809'
 '10M'        | '1%'      | '1/16W'  | '0402LF'  | 'CHIP'   | 'CS61002FB01'(!)        = ''              | ''                 | 'CS61002FB01'           | 'R0402'             | '(R0402-0201)'                 | '10M'     | '1%'    | '1/16W'  | 'DISCRETE' | 'RES CHIP 10M 1/16W +-1%(0402)DAL_AEC'             | 'CHIPR0402'    | ''          | ''            | '20160809'
 '10M'        | '1%'      | '1/16W'  | '0402LF'  | 'EMPTY'  | 'CS61002FB01'(!)        = ''              | ''                 | 'CS61002FB01'           | 'R0402'             | '(R0402-0201)'                 | '10M'     | '1%'    | '1/16W'  | 'IO'       | 'RES CHIP 10M 1/16W +-1%(0402)DAL_AEC'             | 'CHIPR0402'    | ''          | ''            | '20160809'
 '100K'       | '0.1%'    | '1/8W'   | '0805LF'  | 'CHIP'   | 'CS41004BA00'(!)        = ''              | ''                 | 'CS41004BA00'           | 'R0805'             | '(SMR0805AW)'                  | '100K'    | '0.1%'  | '1/8W'   | 'DISCRETE' | 'RES CHIP 100K 1/8W +-0.1%(0805)AEC'               | 'CHIPR0805'    | ''          | ''            | '20160818'
 '100K'       | '0.1%'    | '1/8W'   | '0805LF'  | 'EMPTY'  | 'CS41004BA00'(!)        = ''              | ''                 | 'CS41004BA00'           | 'R0805'             | '(SMR0805AW)'                  | '100K'    | '0.1%'  | '1/8W'   | 'IO'       | 'RES CHIP 100K 1/8W +-0.1%(0805)AEC'               | 'CHIPR0805'    | ''          | ''            | '20160818'
 '165K'       | '1%'      | '1/16W'  | '0402LF'  | 'CHIP'   | 'CS41652FB14'(!)        = 'End of Design' | 'Comp-Approve'     | 'CS41652FB14'           | 'R0402'             | '(R0402-0201)'                 | '165K'    | '1%'    | '1/16W'  | 'DISCRETE' | 'RES CHIP 165K 1/16W +-1%(0402)'                   | 'CHIPR0402'    | ''          | ''            | '20140618'
 '165K'       | '1%'      | '1/16W'  | '0402LF'  | 'EMPTY'  | 'CS41652FB14'(!)        = 'End of Design' | 'Comp-Approve'     | 'CS41652FB14'           | 'R0402'             | '(R0402-0201)'                 | '165K'    | '1%'    | '1/16W'  | 'IO'       | 'RES CHIP 165K 1/16W +-1%(0402)'                   | 'CHIPR0402'    | ''          | ''            | '20140618'
 '0.0005'     | '1%'      | '1W'     | '2512LF'  | 'CHIP'   | 'CS00008FR04'(!)        = ''              | ''                 | 'CS00008FR04'           | 'R2512A'            | '(SMR2512AW)'                  | '0.0005'  | '1%'    | '1W'     | 'DISCRETE' | 'RES CHIP 0.0005 1W +-1%(2512)DAL_AEC'             | 'CHIPR2512'    | ''          | ''            | '20160822'
 '0.0005'     | '1%'      | '1W'     | '2512LF'  | 'EMPTY'  | 'CS00008FR04'(!)        = ''              | ''                 | 'CS00008FR04'           | 'R2512A'            | '(SMR2512AW)'                  | '0.0005'  | '1%'    | '1W'     | 'IO'       | 'RES CHIP 0.0005 1W +-1%(2512)DAL_AEC'             | 'CHIPR2512'    | ''          | ''            | '20160822'
 '0.001'      | '1%'      | '1W'     | '2512LF'  | 'CHIP'   | 'CS+0018FR06'(!)        = ''              | ''                 | 'CS+0018FR06'           | 'R2512A'            | '(SMR2512AW)'                  | '0.001'   | '1%'    | '1W'     | 'DISCRETE' | 'RES CHIP 0.001 1W +-1%(2512)DAL_AEC'              | 'CHIPR2512'    | ''          | ''            | '20160822'
 '0.001'      | '1%'      | '1W'     | '2512LF'  | 'EMPTY'  | 'CS+0018FR06'(!)        = ''              | ''                 | 'CS+0018FR06'           | 'R2512A'            | '(SMR2512AW)'                  | '0.001'   | '1%'    | '1W'     | 'IO'       | 'RES CHIP 0.001 1W +-1%(2512)DAL_AEC'              | 'CHIPR2512'    | ''          | ''            | '20160822'
 '0.001'      | '1%'      | '3W'     | '2512LF'  | 'CHIP'   | 'CS+001DFR04'(!)        = ''              | ''                 | 'CS+001DFR04'           | 'R2512A'            | '(SMR2512AW)'                  | '0.001'   | '1%'    | '3W'     | 'DISCRETE' | 'RES CHIP 0.001 3W +-1%(2512)DAL_AEC'              | 'CHIPR2512'    | ''          | ''            | '20160822'
 '0.001'      | '1%'      | '3W'     | '2512LF'  | 'EMPTY'  | 'CS+001DFR04'(!)        = ''              | ''                 | 'CS+001DFR04'           | 'R2512A'            | '(SMR2512AW)'                  | '0.001'   | '1%'    | '3W'     | 'IO'       | 'RES CHIP 0.001 3W +-1%(2512)DAL_AEC'              | 'CHIPR2512'    | ''          | ''            | '20160822'
 '1'          | '1%'      | '1W'     | '2512LF'  | 'CHIP'   | 'CS-1008FR01'(!)        = ''              | ''                 | 'CS-1008FR01'           | 'R2512XN'           | '(SMR2512AW)'                  | '1'       | '1%'    | '1W'     | 'DISCRETE' | 'RES CHIP 1 1W +-1%(2512) DAL_AEC'                 | 'CHIPR2512'    | ''          | ''            | '20160822'
 '1'          | '1%'      | '1W'     | '2512LF'  | 'EMPTY'  | 'CS-1008FR01'(!)        = ''              | ''                 | 'CS-1008FR01'           | 'R2512XN'           | '(SMR2512AW)'                  | '1'       | '1%'    | '1W'     | 'IO'       | 'RES CHIP 1 1W +-1%(2512) DAL_AEC'                 | 'CHIPR2512'    | ''          | ''            | '20160822'
 '1K'         | '1%'      | '1/16W'  | '0402LF'  | 'CHIP'   | 'SP_CS21002FB24_1'(!)   = 'End of Design' | 'Comp-Approve'     | 'CS21002FB24'           | 'R0402_SMDC25_SM30' | '(R0402-0201)'                 | '1K'      | '1%'    | '1/16W'  | 'DISCRETE' | 'RES CHIP 1K 1/16W +-1% (0402)_FOR AMD CIRCLE PAD' | 'CHIPR0402'    | ''          | ''            | '20160824'
 '1K'         | '1%'      | '1/16W'  | '0402LF'  | 'EMPTY'  | 'SP_CS21002FB24_1'(!)   = 'End of Design' | 'Comp-Approve'     | 'CS21002FB24'           | 'R0402_SMDC25_SM30' | '(R0402-0201)'                 | '1K'      | '1%'    | '1/16W'  | 'IO'       | 'RES CHIP 1K 1/16W +-1% (0402)_FOR AMD CIRCLE PAD' | 'CHIPR0402'    | ''          | ''            | '20160824'
 '59K'        | '1%'      | '1/16W'  | '0402LF'  | 'CHIP'   | 'CS35902FB11'(!)        = 'End of Design' | 'Comp-Approve'     | 'CS35902FB11'           | 'R0402'             | '(R0402-0201)'                 | '59K'     | '1%'    | '1/16W'  | 'DISCRETE' | 'RESISTOR CHIP 59K 1/16W +-1%(0402)EP'             | 'CHIPR0402'    | ''          | ''            | '20120710'
 '59K'        | '1%'      | '1/16W'  | '0402LF'  | 'EMPTY'  | 'CS35902FB11'(!)        = 'End of Design' | 'Comp-Approve'     | 'CS35902FB11'           | 'R0402'             | '(R0402-0201)'                 | '59K'     | '1%'    | '1/16W'  | 'IO'       | 'RESISTOR CHIP 59K 1/16W +-1%(0402)EP'             | 'CHIPR0402'    | ''          | ''            | '20120710'
 '2.2'        | '1%'      | '1/4W'   | '1206LF'  | 'CHIP'   | 'CS-2206F202'(!)        = ''              | ''                 | 'CS-2206F202'           | 'R1206XC'           | '(SMR1206AW)'                  | '2.2'     | '1%'    | '1/4W'   | 'DISCRETE' | 'RES CHIP 2.2 1/4W +-1%(1206)DAL_AEC'              | 'CHIPR1206'    | ''          | ''            | '20160920'
 '2.2'        | '1%'      | '1/4W'   | '1206LF'  | 'EMPTY'  | 'CS-2206F202'(!)        = ''              | ''                 | 'CS-2206F202'           | 'R1206XC'           | '(SMR1206AW)'                  | '2.2'     | '1%'    | '1/4W'   | 'IO'       | 'RES CHIP 2.2 1/4W +-1%(1206)DAL_AEC'              | 'CHIPR1206'    | ''          | ''            | '20160920'
 '221'        | '1%'      | '1/16W'  | '0402LF'  | 'CHIP'   | 'CS12212FB05'(!)        = ''              | ''                 | 'CS12212FB05'           | 'R0402'             | '(R0402-0201)'                 | '221'     | '1%'    | '1/16W'  | 'DISCRETE' | 'RES CHIP 221 1/16W +-1%(0402)DAL_AEC'             | 'CHIPR0402'    | ''          | ''            | '20160929'
 '221'        | '1%'      | '1/16W'  | '0402LF'  | 'EMPTY'  | 'CS12212FB05'(!)        = ''              | ''                 | 'CS12212FB05'           | 'R0402'             | '(R0402-0201)'                 | '221'     | '1%'    | '1/16W'  | 'IO'       | 'RES CHIP 221 1/16W +-1%(0402)DAL_AEC'             | 'CHIPR0402'    | ''          | ''            | '20160929'
 '0.001'      | '1%'      | '2W'     | '2512LF'  | 'CHIP'   | 'CS+001AFR03'(!)        = ''              | ''                 | 'CS+001AFR03'           | 'R2512XG'           | '(SMR2512AW)'                  | '0.001'   | '1%'    | '2W'     | 'DISCRETE' | 'RES CHIP 0.001 2W +-1%(2512)'                     | 'CHIPR2512'    | ''          | ''            | '20161007'
 '0.001'      | '1%'      | '2W'     | '2512LF'  | 'EMPTY'  | 'CS+001AFR03'(!)        = ''              | ''                 | 'CS+001AFR03'           | 'R2512XG'           | '(SMR2512AW)'                  | '0.001'   | '1%'    | '2W'     | 'IO'       | 'RES CHIP 0.001 2W +-1%(2512)'                     | 'CHIPR2512'    | ''          | ''            | '20161007'
 '309K'       | '1%'      | '1/8W'   | '0805LF'  | 'CHIP'   | 'CS43094FA00'(!)        = ''              | ''                 | 'CS43094FA00'           | 'R0805'             | '(SMR0805AW)'                  | '309K'    | '1%'    | '1/8W'   | 'DISCRETE' | 'RES CHIP 309K 1/8W +-1%(0805)'                    | 'CHIPR0805'    | ''          | ''            | '20161013'
 '309K'       | '1%'      | '1/8W'   | '0805LF'  | 'EMPTY'  | 'CS43094FA00'(!)        = ''              | ''                 | 'CS43094FA00'           | 'R0805'             | '(SMR0805AW)'                  | '309K'    | '1%'    | '1/8W'   | 'IO'       | 'RES CHIP 309K 1/8W +-1%(0805)'                    | 'CHIPR0805'    | ''          | ''            | '20161013'
 '374K'       | '1%'      | '1/8W'   | '0805LF'  | 'CHIP'   | 'CS43744FA00'(!)        = ''              | ''                 | 'CS43744FA00'           | 'R0805'             | '(SMR0805AW)'                  | '374K'    | '1%'    | '1/8W'   | 'DISCRETE' | 'RES CHIP 374K 1/8W +-1%(0805)'                    | 'CHIPR0805'    | ''          | ''            | '20161013'
 '374K'       | '1%'      | '1/8W'   | '0805LF'  | 'EMPTY'  | 'CS43744FA00'(!)        = ''              | ''                 | 'CS43744FA00'           | 'R0805'             | '(SMR0805AW)'                  | '374K'    | '1%'    | '1/8W'   | 'IO'       | 'RES CHIP 374K 1/8W +-1%(0805)'                    | 'CHIPR0805'    | ''          | ''            | '20161013'
 '1.5M'       | '1%'      | '1/16W'  | '0402LF'  | 'CHIP'   | 'CS51502FB02'(!)        = ''              | ''                 | 'CS51502FB02'           | 'R0402'             | '(R0402-0201)'                 | '1.5M'    | '1%'    | '1/16W'  | 'DISCRETE' | 'RES CHIP 1.5M 1/16W +-1%(0402)DAL_AEC'            | 'CHIPR0402'    | ''          | ''            | '20161017'
 '1.5M'       | '1%'      | '1/16W'  | '0402LF'  | 'EMPTY'  | 'CS51502FB02'(!)        = ''              | ''                 | 'CS51502FB02'           | 'R0402'             | '(R0402-0201)'                 | '1.5M'    | '1%'    | '1/16W'  | 'IO'       | 'RES CHIP 1.5M 1/16W +-1%(0402)DAL_AEC'            | 'CHIPR0402'    | ''          | ''            | '20161017'
 '562K'       | '1%'      | '1/16W'  | '0402LF'  | 'CHIP'   | 'CS45622FB02'(!)        = ''              | ''                 | 'CS45622FB02'           | 'R0402'             | '(R0402-0201)'                 | '562K'    | '1%'    | '1/16W'  | 'DISCRETE' | 'RES CHIP 562K 1/16W +-1%(0402)DAL_AEC'            | 'CHIPR0402'    | ''          | ''            | '20161017'
 '562K'       | '1%'      | '1/16W'  | '0402LF'  | 'EMPTY'  | 'CS45622FB02'(!)        = ''              | ''                 | 'CS45622FB02'           | 'R0402'             | '(R0402-0201)'                 | '562K'    | '1%'    | '1/16W'  | 'IO'       | 'RES CHIP 562K 1/16W +-1%(0402)DAL_AEC'            | 'CHIPR0402'    | ''          | ''            | '20161017'
 '267K'       | '1%'      | '1/16W'  | '0402LF'  | 'CHIP'   | 'CS42672FB02'(!)        = ''              | ''                 | 'CS42672FB02'           | 'R0402'             | '(R0402-0201)'                 | '267K'    | '1%'    | '1/16W'  | 'DISCRETE' | 'RES CHIP 267K 1/16W +-1%(0402)DAL_AEC'            | 'CHIPR0402'    | ''          | ''            | '20161017'
 '267K'       | '1%'      | '1/16W'  | '0402LF'  | 'EMPTY'  | 'CS42672FB02'(!)        = ''              | ''                 | 'CS42672FB02'           | 'R0402'             | '(R0402-0201)'                 | '267K'    | '1%'    | '1/16W'  | 'IO'       | 'RES CHIP 267K 1/16W +-1%(0402)DAL_AEC'            | 'CHIPR0402'    | ''          | ''            | '20161017'
 '29.4K'      | '1%'      | '1/16W'  | '0402LF'  | 'CHIP'   | 'CS32942FB04'(!)        = ''              | ''                 | 'CS32942FB04'           | 'R0402'             | '(R0402-0201)'                 | '29.4K'   | '1%'    | '1/16W'  | 'DISCRETE' | 'RES CHIP 29.4K 1/16W +-1%(0402)DAL_AEC'           | 'CHIPR0402'    | ''          | ''            | '20161017'
 '29.4K'      | '1%'      | '1/16W'  | '0402LF'  | 'EMPTY'  | 'CS32942FB04'(!)        = ''              | ''                 | 'CS32942FB04'           | 'R0402'             | '(R0402-0201)'                 | '29.4K'   | '1%'    | '1/16W'  | 'IO'       | 'RES CHIP 29.4K 1/16W +-1%(0402)DAL_AEC'           | 'CHIPR0402'    | ''          | ''            | '20161017'
 '3K'         | '1%'      | '1/16W'  | '0402LF'  | 'CHIP'   | 'CS23002FB04'(!)        = ''              | ''                 | 'CS23002FB04'           | 'R0402'             | '(R0402-0201)'                 | '3K'      | '1%'    | '1/16W'  | 'DISCRETE' | 'RES CHIP 3K 1/16W +-1%(0402)DAL_AEC'              | 'CHIPR0402'    | ''          | ''            | '20161017'
 '3K'         | '1%'      | '1/16W'  | '0402LF'  | 'EMPTY'  | 'CS23002FB04'(!)        = ''              | ''                 | 'CS23002FB04'           | 'R0402'             | '(R0402-0201)'                 | '3K'      | '1%'    | '1/16W'  | 'IO'       | 'RES CHIP 3K 1/16W +-1%(0402)DAL_AEC'              | 'CHIPR0402'    | ''          | ''            | '20161017'
 '442K'       | '1%'      | '1/16W'  | '0402LF'  | 'CHIP'   | 'CS44422FB00'(!)        = 'End of Design' | 'Comp-Approve'     | 'CS44422FB00'           | 'R0402'             | '(R0402-0201)'                 | '442K'    | '1%'    | '1/16W'  | 'DISCRETE' | 'RES CHIP 442K 1/16W +-1%(0402)'                   | 'CHIPR0402'    | ''          | ''            | '20161104'
 '442K'       | '1%'      | '1/16W'  | '0402LF'  | 'EMPTY'  | 'CS44422FB00'(!)        = 'End of Design' | 'Comp-Approve'     | 'CS44422FB00'           | 'R0402'             | '(R0402-0201)'                 | '442K'    | '1%'    | '1/16W'  | 'IO'       | 'RES CHIP 442K 1/16W +-1%(0402)'                   | 'CHIPR0402'    | ''          | ''            | '20161104'
 '182'        | '1%'      | '1/16W'  | '0402LF'  | 'CHIP'   | 'CS11822FB21'(!)        = 'End of Design' | 'Comp-Approve'     | 'CS11822FB21'           | 'R0402'             | '(R0402-0201)'                 | '182'     | '1%'    | '1/16W'  | 'DISCRETE' | 'RES CHIP 182 1/16W +-1%(0402)'                    | 'CHIPR0402'    | ''          | ''            | '20161110'
 '182'        | '1%'      | '1/16W'  | '0402LF'  | 'EMPTY'  | 'CS11822FB21'(!)        = 'End of Design' | 'Comp-Approve'     | 'CS11822FB21'           | 'R0402'             | '(R0402-0201)'                 | '182'     | '1%'    | '1/16W'  | 'IO'       | 'RES CHIP 182 1/16W +-1%(0402)'                    | 'CHIPR0402'    | ''          | ''            | '20161110'
 '332'        | '1%'      | '1/16W'  | '0402LF'  | 'CHIP'   | 'CS13322FB01'(!)        = ''              | ''                 | 'CS13322FB01'           | 'R0402'             | '(R0402-0201)'                 | '332'     | '1%'    | '1/16W'  | 'DISCRETE' | 'RES CHIP 332 1/16W +-1%(0402)'                    | 'CHIPR0402'    | ''          | ''            | '20161114'
 '332'        | '1%'      | '1/16W'  | '0402LF'  | 'EMPTY'  | 'CS13322FB01'(!)        = ''              | ''                 | 'CS13322FB01'           | 'R0402'             | '(R0402-0201)'                 | '332'     | '1%'    | '1/16W'  | 'IO'       | 'RES CHIP 332 1/16W +-1%(0402)'                    | 'CHIPR0402'    | ''          | ''            | '20161114'
 '0.001'      | '1%'      | '1W'     | '1206LF'  | 'CHIP'   | 'CS+0018F200'(!)        = ''              | ''                 | 'CS+0018F200'           | 'R1206XA'           | '(SMR1206AW)'                  | '0.001'   | '1%'    | '1W'     | 'DISCRETE' | 'RES CHIP 0.001 1W +-1%(1206)'                     | 'CHIPR1206'    | ''          | ''            | '20161118'
 '0.001'      | '1%'      | '1W'     | '1206LF'  | 'EMPTY'  | 'CS+0018F200'(!)        = ''              | ''                 | 'CS+0018F200'           | 'R1206XA'           | '(SMR1206AW)'                  | '0.001'   | '1%'    | '1W'     | 'IO'       | 'RES CHIP 0.001 1W +-1%(1206)'                     | 'CHIPR1206'    | ''          | ''            | '20161118'
 '75'         | '1%'      | '1/8W'   | '0402LF'  | 'CHIP'   | 'CS07504FB00'(!)        = ''              | ''                 | 'CS07504FB00'           | 'R0402'             | '(R0402-0201)'                 | '75'      | '1%'    | '1/8W'   | 'DISCRETE' | 'RES CHIP 75 1/8W +-1%(0402)'                      | 'CHIPR0402'    | ''          | ''            | '20161128'
 '75'         | '1%'      | '1/8W'   | '0402LF'  | 'EMPTY'  | 'CS07504FB00'(!)        = ''              | ''                 | 'CS07504FB00'           | 'R0402'             | '(R0402-0201)'                 | '75'      | '1%'    | '1/8W'   | 'IO'       | 'RES CHIP 75 1/8W +-1%(0402)'                      | 'CHIPR0402'    | ''          | ''            | '20161128'
 '56.2K'      | '0.1%'    | '1/16W'  | '0402LF'  | 'CHIP'   | 'CS35622BB00'(!)        = ''              | ''                 | 'CS35622BB00'           | 'R0402'             | '(R0402-0201)'                 | '56.2K'   | '0.1%'  | '1/16W'  | 'DISCRETE' | 'RES CHIP 56.2K 1/16W +-0.1%(0402)'                | 'CHIPR0402'    | ''          | ''            | '20161128'
 '56.2K'      | '0.1%'    | '1/16W'  | '0402LF'  | 'EMPTY'  | 'CS35622BB00'(!)        = ''              | ''                 | 'CS35622BB00'           | 'R0402'             | '(R0402-0201)'                 | '56.2K'   | '0.1%'  | '1/16W'  | 'IO'       | 'RES CHIP 56.2K 1/16W +-0.1%(0402)'                | 'CHIPR0402'    | ''          | ''            | '20161128'
 '1M'         | '1%'      | '1/4W'   | '1206LF'  | 'CHIP'   | 'CS51006F200'(!)        = ''              | ''                 | 'CS51006F200'           | 'R1206XF'           | '(SMR1206AW)'                  | '1M'      | '1%'    | '1/4W'   | 'DISCRETE' | 'RES CHIP 1M 1/4W +-1%(1206)'                      | 'CHIPR1206'    | ''          | ''            | '20170207'
 '1M'         | '1%'      | '1/4W'   | '1206LF'  | 'EMPTY'  | 'CS51006F200'(!)        = ''              | ''                 | 'CS51006F200'           | 'R1206XF'           | '(SMR1206AW)'                  | '1M'      | '1%'    | '1/4W'   | 'IO'       | 'RES CHIP 1M 1/4W +-1%(1206)'                      | 'CHIPR1206'    | ''          | ''            | '20170207'
 '0.01'       | '1%'      | '1/2W'   | '1206LF'  | 'CHIP'   | 'CS+0107F211'(!)        = ''              | ''                 | 'CS+0107F211'           | 'R1206XG'           | '(SMR1206AW)'                  | '0.01'    | '1%'    | '1/2W'   | 'DISCRETE' | 'RES CHIP 0.01 1/2W +-1%(1206)'                    | 'CHIPR1206'    | ''          | ''            | '20170213'
 '0.01'       | '1%'      | '1/2W'   | '1206LF'  | 'EMPTY'  | 'CS+0107F211'(!)        = ''              | ''                 | 'CS+0107F211'           | 'R1206XG'           | '(SMR1206AW)'                  | '0.01'    | '1%'    | '1/2W'   | 'IO'       | 'RES CHIP 0.01 1/2W +-1%(1206)'                    | 'CHIPR1206'    | ''          | ''            | '20170213'
 '0.01'       | '1%'      | '1W'     | '3720LF'  | 'CHIP'   | 'CS+0108FL09'(!)        = ''              | ''                 | 'CS+0108FL09'           | 'R3720XA'           | '(SMR3720AW)'                  | '0.01'    | '1%'    | '1W'     | 'DISCRETE' | 'RESISTOR CHIP 0.01 1W +-1%(3720)'                 | 'CHIP3720'     | ''          | ''            | '20170216'
 '0.01'       | '1%'      | '1W'     | '3720LF'  | 'EMPTY'  | 'CS+0108FL09'(!)        = ''              | ''                 | 'CS+0108FL09'           | 'R3720XA'           | '(SMR3720AW)'                  | '0.01'    | '1%'    | '1W'     | 'IO'       | 'RESISTOR CHIP 0.01 1W +-1%(3720)'                 | 'CHIP3720'     | ''          | ''            | '20170216'
 '160'        | '5%'      | '1/16W'  | '0402LF'  | 'CHIP'   | 'CS11602JB02'(!)        = 'End of Design' | 'Comp-Approve'     | 'CS11602JB02'           | 'R0402'             | '(R0402-0201)'                 | '160'     | '5%'    | '1/16W'  | 'DISCRETE' | 'RES CHIP 160 1/16W +-5%(0402)'                    | 'CHIPR0402'    | ''          | ''            | '20170216'
 '160'        | '5%'      | '1/16W'  | '0402LF'  | 'EMPTY'  | 'CS11602JB02'(!)        = 'End of Design' | 'Comp-Approve'     | 'CS11602JB02'           | 'R0402'             | '(R0402-0201)'                 | '160'     | '5%'    | '1/16W'  | 'IO'       | 'RES CHIP 160 1/16W +-5%(0402)'                    | 'CHIPR0402'    | ''          | ''            | '20170216'
 '16.5'       | '1%'      | '1/16W'  | '0402LF'  | 'CHIP'   | 'CS01652FB00'(!)        = 'End of Design' | 'Comp-Approve'     | 'CS01652FB00'           | 'R0402'             | '(R0402-0201)'                 | '16.5'    | '1%'    | '1/16W'  | 'DISCRETE' | 'RES CHIP 16.5 1/16W +-1%(0402)'                   | 'CHIPR0402'    | ''          | ''            | '20170412'
 '16.5'       | '1%'      | '1/16W'  | '0402LF'  | 'EMPTY'  | 'CS01652FB00'(!)        = 'End of Design' | 'Comp-Approve'     | 'CS01652FB00'           | 'R0402'             | '(R0402-0201)'                 | '16.5'    | '1%'    | '1/16W'  | 'IO'       | 'RES CHIP 16.5 1/16W +-1%(0402)'                   | 'CHIPR0402'    | ''          | ''            | '20170412'
 '10'         | '5%'      | '1/16W'  | '0402LF'  | 'CHIP'   | 'CS01002JB06'(!)        = ''              | 'End of Life'      | 'CS01002JB06'           | 'R0402_EOL'         | '(R0402-0201)'                 | '10'      | '5%'    | '1/16W'  | 'DISCRETE' | 'RES CHIP 10 1/16W +-5%(0402)'                     | 'CHIPR0402'    | ''          | ''            | '20170504'
 '10'         | '5%'      | '1/16W'  | '0402LF'  | 'EMPTY'  | 'CS01002JB06'(!)        = ''              | 'End of Life'      | 'CS01002JB06'           | 'R0402_EOL'         | '(R0402-0201)'                 | '10'      | '5%'    | '1/16W'  | 'IO'       | 'RES CHIP 10 1/16W +-5%(0402)'                     | 'CHIPR0402'    | ''          | ''            | '20170504'
 '6.34K'      | '1%'      | '1/16W'  | '0402LF'  | 'CHIP'   | 'CS26342FB04'(!)        = ''              | ''                 | 'CS26342FB04'           | 'R0402'             | '(R0402-0201)'                 | '6.34K'   | '1%'    | '1/16W'  | 'DISCRETE' | 'RES CHIP 6.34K 1/16W +-1%(0402)DAL_AEC'           | 'CHIPR0402'    | ''          | ''            | '20170524'
 '6.34K'      | '1%'      | '1/16W'  | '0402LF'  | 'EMPTY'  | 'CS26342FB04'(!)        = ''              | ''                 | 'CS26342FB04'           | 'R0402'             | '(R0402-0201)'                 | '6.34K'   | '1%'    | '1/16W'  | 'IO'       | 'RES CHIP 6.34K 1/16W +-1%(0402)DAL_AEC'           | 'CHIPR0402'    | ''          | ''            | '20170524'
 '49.9'       | '1%'      | '1/16W'  | '0402LF'  | 'CHIP'   | 'CS04992FB11'(!)        = ''              | ''                 | 'CS04992FB11'           | 'R0402'             | '(R0402-0201)'                 | '49.9'    | '1%'    | '1/16W'  | 'DISCRETE' | 'RES CHIP 49.9 1/16W +-1% (0402)DAL_AEC'           | 'CHIPR0402'    | ''          | ''            | '20170524'
 '49.9'       | '1%'      | '1/16W'  | '0402LF'  | 'EMPTY'  | 'CS04992FB11'(!)        = ''              | ''                 | 'CS04992FB11'           | 'R0402'             | '(R0402-0201)'                 | '49.9'    | '1%'    | '1/16W'  | 'IO'       | 'RES CHIP 49.9 1/16W +-1% (0402)DAL_AEC'           | 'CHIPR0402'    | ''          | ''            | '20170524'
 '0.020'      | '1%'      | '3W'     | '2512LF'  | 'CHIP'   | 'CS+020DFR00'(!)        = ''              | ''                 | 'CS+020DFR00'           | 'R2512XL'           | '(SMR2512AW)'                  | '0.020'   | '1%'    | '3W'     | 'DISCRETE' | 'RES CHIP 0.020 3W +-1%(2512)'                     | 'CHIPR2512'    | ''          | ''            | '20170524'
 '0.020'      | '1%'      | '3W'     | '2512LF'  | 'EMPTY'  | 'CS+020DFR00'(!)        = ''              | ''                 | 'CS+020DFR00'           | 'R2512XL'           | '(SMR2512AW)'                  | '0.020'   | '1%'    | '3W'     | 'IO'       | 'RES CHIP 0.020 3W +-1%(2512)'                     | 'CHIPR2512'    | ''          | ''            | '20170524'
 '15'         | '5%'      | '1W'     | '2512LF'  | 'CHIP'   | 'CS01508JR00'(!)        = ''              | ''                 | 'CS01508JR00'           | 'R2512XK'           | '(SMR2512AW)'                  | '15'      | '5%'    | '1W'     | 'DISCRETE' | 'RES CHIP 15,5%,1W(2512)'                          | 'CHIPR2512'    | ''          | ''            | '20170524'
 '15'         | '5%'      | '1W'     | '2512LF'  | 'EMPTY'  | 'CS01508JR00'(!)        = ''              | ''                 | 'CS01508JR00'           | 'R2512XK'           | '(SMR2512AW)'                  | '15'      | '5%'    | '1W'     | 'IO'       | 'RES CHIP 15,5%,1W(2512)'                          | 'CHIPR2512'    | ''          | ''            | '20170524'
 '1.3M'       | '1%'      | '1/10W'  | '0603LF'  | 'CHIP'   | 'CS51303F901'(!)        = ''              | ''                 | 'CS51303F901'           | 'R0603'             | '(SMR0603AW)'                  | '1.3M'    | '1%'    | '1/10W'  | 'DISCRETE' | 'RES CHIP 1.3M 1/10W +-1%(0603)'                   | 'CHIPR0603'    | ''          | ''            | '20170602'
 '1.3M'       | '1%'      | '1/10W'  | '0603LF'  | 'EMPTY'  | 'CS51303F901'(!)        = ''              | ''                 | 'CS51303F901'           | 'R0603'             | '(SMR0603AW)'                  | '1.3M'    | '1%'    | '1/10W'  | 'IO'       | 'RES CHIP 1.3M 1/10W +-1%(0603)'                   | 'CHIPR0603'    | ''          | ''            | '20170602'
 '0'          | ''        | '1/8W'   | '0805LF'  | 'CHIP'   | 'CS00004TA03'(!)        = ''              | ''                 | 'CS00004TA03'           | 'R0805'             | '(SMR0805AW)'                  | '0'       | ''      | '1/8W'   | 'DISCRETE' | 'RES CHIP 0 1/8W (0805) DAL_AEC'                   | 'CHIPR0805'    | ''          | ''            | '20170606'
 '0'          | ''        | '1/8W'   | '0805LF'  | 'EMPTY'  | 'CS00004TA03'(!)        = ''              | ''                 | 'CS00004TA03'           | 'R0805'             | '(SMR0805AW)'                  | '0'       | ''      | '1/8W'   | 'IO'       | 'RES CHIP 0 1/8W (0805) DAL_AEC'                   | 'CHIPR0805'    | ''          | ''            | '20170606'
 '1'          | '1%'      | '1/4W'   | '1206LF'  | 'CHIP'   | 'CS-1006F201'(!)        = ''              | ''                 | 'CS-1006F201'           | 'R1206XC'           | '(SMRR1206AW)'                 | '1'       | '1%'    | '1/4W'   | 'DISCRETE' | 'RES CHIP 1 1/4W +-1%(1206)DAL_AEC'                | 'CHIPR1206'    | ''          | ''            | '20170606'
 '1'          | '1%'      | '1/4W'   | '1206LF'  | 'EMPTY'  | 'CS-1006F201'(!)        = ''              | ''                 | 'CS-1006F201'           | 'R1206XC'           | '(SMRR1206AW)'                 | '1'       | '1%'    | '1/4W'   | 'IO'       | 'RES CHIP 1 1/4W +-1%(1206)DAL_AEC'                | 'CHIPR1206'    | ''          | ''            | '20170606'
 '1K'         | '1%'      | '1/8W'   | '0805LF'  | 'CHIP'   | 'CS21004FA03'(!)        = ''              | ''                 | 'CS21004FA03'           | 'R0805'             | '(SMR0805AW)'                  | '1K'      | '1%'    | '1/8W'   | 'DISCRETE' | 'RES CHIP 1K 1/8W +-1%(0805)DAL_AEC'               | 'CHIPR0805'    | ''          | ''            | '20170606'
 '1K'         | '1%'      | '1/8W'   | '0805LF'  | 'EMPTY'  | 'CS21004FA03'(!)        = ''              | ''                 | 'CS21004FA03'           | 'R0805'             | '(SMR0805AW)'                  | '1K'      | '1%'    | '1/8W'   | 'IO'       | 'RES CHIP 1K 1/8W +-1%(0805)DAL_AEC'               | 'CHIPR0805'    | ''          | ''            | '20170606'
 '2.2'        | '1%'      | '1/8W'   | '0805LF'  | 'CHIP'   | 'CS-2204FA04'(!)        = ''              | ''                 | 'CS-2204FA04'           | 'R0805'             | '(SMR0805AW)'                  | '2.2'     | '1%'    | '1/8W'   | 'DISCRETE' | 'RES CHIP 2.2 1/8W +-1%(0805)DAL_AEC'              | 'CHIPR0805'    | ''          | ''            | '20170606'
 '2.2'        | '1%'      | '1/8W'   | '0805LF'  | 'EMPTY'  | 'CS-2204FA04'(!)        = ''              | ''                 | 'CS-2204FA04'           | 'R0805'             | '(SMR0805AW)'                  | '2.2'     | '1%'    | '1/8W'   | 'IO'       | 'RES CHIP 2.2 1/8W +-1%(0805)DAL_AEC'              | 'CHIPR0805'    | ''          | ''            | '20170606'
 '0.0005'     | '1%'      | '3W'     | '2512LF'  | 'CHIP'   | 'CS0000DFR05'(!)        = ''              | ''                 | 'CS0000DFR05'           | 'R2512XO'           | '(SMR2512AW)'                  | '0.0005'  | '1%'    | '3W'     | 'DISCRETE' | 'RES CHIP 0.0005 3W +-1%(2512)CYN'                 | 'CHIPR2512'    | ''          | ''            | '20170607'
 '0.0005'     | '1%'      | '3W'     | '2512LF'  | 'EMPTY'  | 'CS0000DFR05'(!)        = ''              | ''                 | 'CS0000DFR05'           | 'R2512XO'           | '(SMR2512AW)'                  | '0.0005'  | '1%'    | '3W'     | 'IO'       | 'RES CHIP 0.0005 3W +-1%(2512)CYN'                 | 'CHIPR2512'    | ''          | ''            | '20170607'
 '7.5K'       | '1%'      | '1/8W'   | '0805LF'  | 'CHIP'   | 'CS27504FA00'(!)        = ''              | ''                 | 'CS27504FA00'           | 'R0805'             | '(SMR0805AW)'                  | '7.5K'    | '1%'    | '1/8W'   | 'DISCRETE' | 'RES CHIP 7.5K 1/8W +-1% (0805)'                   | 'CHIPR0805'    | ''          | ''            | '20170706'
 '7.5K'       | '1%'      | '1/8W'   | '0805LF'  | 'EMPTY'  | 'CS27504FA00'(!)        = ''              | ''                 | 'CS27504FA00'           | 'R0805'             | '(SMR0805AW)'                  | '7.5K'    | '1%'    | '1/8W'   | 'IO'       | 'RES CHIP 7.5K 1/8W +-1% (0805)'                   | 'CHIPR0805'    | ''          | ''            | '20170706'
 '1'          | '5%'      | '1/8W'   | '0805LF'  | 'CHIP'   | 'CS-1004JA37'(!)        = ''              | ''                 | 'CS-1004JA37'           | 'R0805'             | '(SMR0805AW)'                  | '1'       | '5%'    | '1/8W'   | 'DISCRETE' | 'RES CHIP 1 1/8W+-5%(0805)'                        | 'CHIPR0805'    | ''          | ''            | '20170711'
 '1'          | '5%'      | '1/8W'   | '0805LF'  | 'EMPTY'  | 'CS-1004JA37'(!)        = ''              | ''                 | 'CS-1004JA37'           | 'R0805'             | '(SMR0805AW)'                  | '1'       | '5%'    | '1/8W'   | 'IO'       | 'RES CHIP 1 1/8W+-5%(0805)'                        | 'CHIPR0805'    | ''          | ''            | '20170711'
 '3.9'        | '5%'      | '1/4W'   | '1206LF'  | 'CHIP'   | 'CS-3906J209'(!)        = ''              | ''                 | 'CS-3906J209'           | 'R1206XI'           | '(SMRR1206AW)'                 | '3.9'     | '5%'    | '1/4W'   | 'DISCRETE' | 'RES CHIP 3.9 1/4W +-5%(1206)'                     | 'CHIPR1206'    | ''          | ''            | '20170711'
 '3.9'        | '5%'      | '1/4W'   | '1206LF'  | 'EMPTY'  | 'CS-3906J209'(!)        = ''              | ''                 | 'CS-3906J209'           | 'R1206XI'           | '(SMRR1206AW)'                 | '3.9'     | '5%'    | '1/4W'   | 'IO'       | 'RES CHIP 3.9 1/4W +-5%(1206)'                     | 'CHIPR1206'    | ''          | ''            | '20170711'
 '665'        | '1%'      | '1/8W'   | '0805LF'  | 'CHIP'   | 'CS16654FA08'(!)        = ''              | ''                 | 'CS16654FA08'           | 'R0805'             | '(SMR0805AW)'                  | '665'     | '1%'    | '1/8W'   | 'DISCRETE' | 'RES CHIP 665 1/8W +-1%(0805)'                     | 'CHIPR0805'    | ''          | ''            | '20170711'
 '665'        | '1%'      | '1/8W'   | '0805LF'  | 'EMPTY'  | 'CS16654FA08'(!)        = ''              | ''                 | 'CS16654FA08'           | 'R0805'             | '(SMR0805AW)'                  | '665'     | '1%'    | '1/8W'   | 'IO'       | 'RES CHIP 665 1/8W +-1%(0805)'                     | 'CHIPR0805'    | ''          | ''            | '20170711'
 '1'          | '1%'      | '1/16W'  | '0402LF'  | 'CHIP'   | 'CS-1002FB11'(!)        = ''              | ''                 | 'CS-1002FB11'           | 'R0402'             | '(R0402-0201)'                 | '1'       | '1%'    | '1/16W'  | 'DISCRETE' | 'RES CHIP 1 1/16W +-1%(0402)DAL_AEC'               | 'CHIPR0402'    | ''          | ''            | '20170711'
 '1'          | '1%'      | '1/16W'  | '0402LF'  | 'EMPTY'  | 'CS-1002FB11'(!)        = ''              | ''                 | 'CS-1002FB11'           | 'R0402'             | '(R0402-0201)'                 | '1'       | '1%'    | '1/16W'  | 'IO'       | 'RES CHIP 1 1/16W +-1%(0402)DAL_AEC'               | 'CHIPR0402'    | ''          | ''            | '20170711'
 '1K'         | '0.1%'    | '1/16W'  | '0402LF'  | 'CHIP'   | 'CS21002BB07'(!)        = ''              | ''                 | 'CS21002BB07'           | 'R0402'             | '(R0402-0201)'                 | '1K'      | '0.1%'  | '1/16W'  | 'DISCRETE' | 'RES CHIP 1K 1/16W +-0.1%(0402)DAL_AEC'            | 'CHIPR0402'    | ''          | ''            | '20170711'
 '1K'         | '0.1%'    | '1/16W'  | '0402LF'  | 'EMPTY'  | 'CS21002BB07'(!)        = ''              | ''                 | 'CS21002BB07'           | 'R0402'             | '(R0402-0201)'                 | '1K'      | '0.1%'  | '1/16W'  | 'IO'       | 'RES CHIP 1K 1/16W +-0.1%(0402)DAL_AEC'            | 'CHIPR0402'    | ''          | ''            | '20170711'
 '4.7K'       | '1%'      | '1/16W'  | '0402LF'  | 'CHIP'   | 'CS24702FB07'(!)        = ''              | ''                 | 'CS24702FB07'           | 'R0402'             | '(R0402-0201)'                 | '4.7K'    | '1%'    | '1/16W'  | 'DISCRETE' | 'RES CHIP 4.7K 1/16W +-1%(0402)DAL_AEC'            | 'CHIPR0402'    | ''          | ''            | '20170712'
 '4.7K'       | '1%'      | '1/16W'  | '0402LF'  | 'EMPTY'  | 'CS24702FB07'(!)        = ''              | ''                 | 'CS24702FB07'           | 'R0402'             | '(R0402-0201)'                 | '4.7K'    | '1%'    | '1/16W'  | 'IO'       | 'RES CHIP 4.7K 1/16W +-1%(0402)DAL_AEC'            | 'CHIPR0402'    | ''          | ''            | '20170712'
 '20K'        | '0.1%'    | '1/16W'  | '0402LF'  | 'CHIP'   | 'CS32002BB04'(!)        = ''              | ''                 | 'CS32002BB04'           | 'R0402'             | '(R0402-0201)'                 | '20K'     | '0.1%'  | '1/16W'  | 'DISCRETE' | 'RES CHIP 20K 1/16W +-0.1%(0402)DAL_AEC'           | 'CHIPR0402'    | ''          | ''            | '20170712'
 '20K'        | '0.1%'    | '1/16W'  | '0402LF'  | 'EMPTY'  | 'CS32002BB04'(!)        = ''              | ''                 | 'CS32002BB04'           | 'R0402'             | '(R0402-0201)'                 | '20K'     | '0.1%'  | '1/16W'  | 'IO'       | 'RES CHIP 20K 1/16W +-0.1%(0402)DAL_AEC'           | 'CHIPR0402'    | ''          | ''            | '20170712'
 '26.7K'      | '0.1%'    | '1/16W'  | '0402LF'  | 'CHIP'   | 'CS32672BB02'(!)        = ''              | ''                 | 'CS32672BB02'           | 'R0402'             | '(R0402-0201)'                 | '26.7K'   | '0.1%'  | '1/16W'  | 'DISCRETE' | 'RES CHIP 26.7K 1/16W +-0.1%(0402)DAL_AEC'         | 'CHIPR0402'    | ''          | ''            | '20170712'
 '26.7K'      | '0.1%'    | '1/16W'  | '0402LF'  | 'EMPTY'  | 'CS32672BB02'(!)        = ''              | ''                 | 'CS32672BB02'           | 'R0402'             | '(R0402-0201)'                 | '26.7K'   | '0.1%'  | '1/16W'  | 'IO'       | 'RES CHIP 26.7K 1/16W +-0.1%(0402)DAL_AEC'         | 'CHIPR0402'    | ''          | ''            | '20170712'
 '118K'       | '0.1%'    | '1/16W'  | '0402LF'  | 'CHIP'   | 'CS41182BB01'(!)        = ''              | ''                 | 'CS41182BB01'           | 'R0402'             | '(R0402-0201)'                 | '118K'    | '0.1%'  | '1/16W'  | 'DISCRETE' | 'RES CHIP 118K 1/16W +-0.1% (0402)DAL_AEC'         | 'CHIPR0402'    | ''          | ''            | '20170712'
 '118K'       | '0.1%'    | '1/16W'  | '0402LF'  | 'EMPTY'  | 'CS41182BB01'(!)        = ''              | ''                 | 'CS41182BB01'           | 'R0402'             | '(R0402-0201)'                 | '118K'    | '0.1%'  | '1/16W'  | 'IO'       | 'RES CHIP 118K 1/16W +-0.1% (0402)DAL_AEC'         | 'CHIPR0402'    | ''          | ''            | '20170712'
 '133K'       | '0.1%'    | '1/16W'  | '0402LF'  | 'CHIP'   | 'CS41332BB01'(!)        = ''              | ''                 | 'CS41332BB01'           | 'R0402'             | '(R0402-0201)'                 | '133K'    | '0.1%'  | '1/16W'  | 'DISCRETE' | 'RES CHIP 133K 1/16W +-0.1%(0402)DAL_AEC'          | 'CHIPR0402'    | ''          | ''            | '20170712'
 '133K'       | '0.1%'    | '1/16W'  | '0402LF'  | 'EMPTY'  | 'CS41332BB01'(!)        = ''              | ''                 | 'CS41332BB01'           | 'R0402'             | '(R0402-0201)'                 | '133K'    | '0.1%'  | '1/16W'  | 'IO'       | 'RES CHIP 133K 1/16W +-0.1%(0402)DAL_AEC'          | 'CHIPR0402'    | ''          | ''            | '20170712'
 '147K'       | '0.1%'    | '1/16W'  | '0402LF'  | 'CHIP'   | 'CS41472BB01'(!)        = 'End of Design' | 'Comp-Release Qty' | 'CS41472BB01'           | 'R0402'             | '(R0402-0201)'                 | '147K'    | '0.1%'  | '1/16W'  | 'DISCRETE' | 'RES CHIP 147K 1/16W +-0.1% (0402)DAL_AEC'         | 'CHIPR0402'    | ''          | ''            | '20170712'
 '147K'       | '0.1%'    | '1/16W'  | '0402LF'  | 'EMPTY'  | 'CS41472BB01'(!)        = 'End of Design' | 'Comp-Release Qty' | 'CS41472BB01'           | 'R0402'             | '(R0402-0201)'                 | '147K'    | '0.1%'  | '1/16W'  | 'IO'       | 'RES CHIP 147K 1/16W +-0.1% (0402)DAL_AEC'         | 'CHIPR0402'    | ''          | ''            | '20170712'
 '511K'       | '1%'      | '1/16W'  | '0402LF'  | 'CHIP'   | 'CS45112FB04'(!)        = ''              | ''                 | 'CS45112FB04'           | 'R0402'             | '(R0402-0201)'                 | '511K'    | '1%'    | '1/16W'  | 'DISCRETE' | 'RES CHIP 511K 1/16W +-1%(0402)DAL_AEC'            | 'CHIPR0402'    | ''          | ''            | '20170712'
 '511K'       | '1%'      | '1/16W'  | '0402LF'  | 'EMPTY'  | 'CS45112FB04'(!)        = ''              | ''                 | 'CS45112FB04'           | 'R0402'             | '(R0402-0201)'                 | '511K'    | '1%'    | '1/16W'  | 'IO'       | 'RES CHIP 511K 1/16W +-1%(0402)DAL_AEC'            | 'CHIPR0402'    | ''          | ''            | '20170712'
 '26.1K'      | '1%'      | '1/16W'  | '0402LF'  | 'CHIP'   | 'CS32612FB03'(!)        = ''              | ''                 | 'CS32612FB03'           | 'R0402'             | '(R0402-0201)'                 | '26.1K'   | '1%'    | '1/16W'  | 'DISCRETE' | 'RES CHIP 26.1K 1/16W +-1%(0402)DAL_AEC'           | 'CHIPR0402'    | ''          | ''            | '20170713'
 '26.1K'      | '1%'      | '1/16W'  | '0402LF'  | 'EMPTY'  | 'CS32612FB03'(!)        = ''              | ''                 | 'CS32612FB03'           | 'R0402'             | '(R0402-0201)'                 | '26.1K'   | '1%'    | '1/16W'  | 'IO'       | 'RES CHIP 26.1K 1/16W +-1%(0402)DAL_AEC'           | 'CHIPR0402'    | ''          | ''            | '20170713'
 '3.74K'      | '1%'      | '1/16W'  | '0402LF'  | 'CHIP'   | 'CS23742FB04'(!)        = ''              | ''                 | 'CS23742FB04'           | 'R0402'             | '(R0402-0201)'                 | '3.74K'   | '1%'    | '1/16W'  | 'DISCRETE' | 'RES CHIP 3.74K 1/16W +-1%(0402)DAL_AEC'           | 'CHIPR0402'    | ''          | ''            | '20170713'
 '3.74K'      | '1%'      | '1/16W'  | '0402LF'  | 'EMPTY'  | 'CS23742FB04'(!)        = ''              | ''                 | 'CS23742FB04'           | 'R0402'             | '(R0402-0201)'                 | '3.74K'   | '1%'    | '1/16W'  | 'IO'       | 'RES CHIP 3.74K 1/16W +-1%(0402)DAL_AEC'           | 'CHIPR0402'    | ''          | ''            | '20170713'
 '0'          | ''        | '1/10W'  | '0603LF'  | 'CHIP'   | 'CS00003T901'(!)        = ''              | ''                 | 'CS00003T901'           | 'R0603'             | '(SMR0603AW)'                  | '0'       | ''      | '1/10W'  | 'DISCRETE' | 'RES CHIP 0 1/10W (0603)DAL_AEC'                   | 'CHIPR0603'    | ''          | ''            | '20170714'
 '0'          | ''        | '1/10W'  | '0603LF'  | 'EMPTY'  | 'CS00003T901'(!)        = ''              | ''                 | 'CS00003T901'           | 'R0603'             | '(SMR0603AW)'                  | '0'       | ''      | '1/10W'  | 'IO'       | 'RES CHIP 0 1/10W (0603)DAL_AEC'                   | 'CHIPR0603'    | ''          | ''            | '20170714'
 '1'          | '1%'      | '1/10W'  | '0603LF'  | 'CHIP'   | 'CS-1003F902'(!)        = ''              | ''                 | 'CS-1003F902'           | 'R0603'             | '(SMR0603AW)'                  | '1'       | '1%'    | '1/10W'  | 'DISCRETE' | 'RES CHIP 1 1/10W +-1%(0603)DAL_AEC'               | 'CHIPR0603'    | ''          | ''            | '20170717'
 '1'          | '1%'      | '1/10W'  | '0603LF'  | 'EMPTY'  | 'CS-1003F902'(!)        = ''              | ''                 | 'CS-1003F902'           | 'R0603'             | '(SMR0603AW)'                  | '1'       | '1%'    | '1/10W'  | 'IO'       | 'RES CHIP 1 1/10W +-1%(0603)DAL_AEC'               | 'CHIPR0603'    | ''          | ''            | '20170717'
 '330'        | '1%'      | '1/10W'  | '0603LF'  | 'CHIP'   | 'CS13303F901'(!)        = ''              | ''                 | 'CS13303F901'           | 'R0603'             | '(SMR0603AW)'                  | '330'     | '1%'    | '1/10W'  | 'DISCRETE' | 'RES CHIP 330 1/10W +-1%(0603)DAL_AEC'             | 'CHIPR0603'    | ''          | ''            | '20170717'
 '330'        | '1%'      | '1/10W'  | '0603LF'  | 'EMPTY'  | 'CS13303F901'(!)        = ''              | ''                 | 'CS13303F901'           | 'R0603'             | '(SMR0603AW)'                  | '330'     | '1%'    | '1/10W'  | 'IO'       | 'RES CHIP 330 1/10W +-1%(0603)DAL_AEC'             | 'CHIPR0603'    | ''          | ''            | '20170717'
 '2.2'        | '1%'      | '1/10W'  | '0603LF'  | 'CHIP'   | 'CS-2203F904'(!)        = ''              | ''                 | 'CS-2203F904'           | 'R0603'             | '(SMR0603AW)'                  | '2.2'     | '1%'    | '1/10W'  | 'DISCRETE' | 'RES CHIP 2.2 1/10W +-1%(0603)DAL_AEC'             | 'CHIPR0603'    | ''          | ''            | '20170717'
 '2.2'        | '1%'      | '1/10W'  | '0603LF'  | 'EMPTY'  | 'CS-2203F904'(!)        = ''              | ''                 | 'CS-2203F904'           | 'R0603'             | '(SMR0603AW)'                  | '2.2'     | '1%'    | '1/10W'  | 'IO'       | 'RES CHIP 2.2 1/10W +-1%(0603)DAL_AEC'             | 'CHIPR0603'    | ''          | ''            | '20170717'
 '4.7K'       | '1%'      | '1/10W'  | '0603LF'  | 'CHIP'   | 'CS24703F902'(!)        = ''              | ''                 | 'CS24703F902'           | 'R0603'             | '(SMR0603AW)'                  | '4.7K'    | '1%'    | '1/10W'  | 'DISCRETE' | 'RES CHIP 4.7K 1/10W +-1%(0603)DAL_AEC'            | 'CHIPR0603'    | ''          | ''            | '20170717'
 '4.7K'       | '1%'      | '1/10W'  | '0603LF'  | 'EMPTY'  | 'CS24703F902'(!)        = ''              | ''                 | 'CS24703F902'           | 'R0603'             | '(SMR0603AW)'                  | '4.7K'    | '1%'    | '1/10W'  | 'IO'       | 'RES CHIP 4.7K 1/10W +-1%(0603)DAL_AEC'            | 'CHIPR0603'    | ''          | ''            | '20170717'
 '10K'        | '1%'      | '1/10W'  | '0603LF'  | 'CHIP'   | 'CS31003F907'(!)        = ''              | ''                 | 'CS31003F907'           | 'R0603'             | '(SMR0603AW)'                  | '10K'     | '1%'    | '1/10W'  | 'DISCRETE' | 'RES CHIP 10K 1/10W+1%(0603)DAL_AEC'               | 'CHIPR0603'    | ''          | ''            | '20170717'
 '10K'        | '1%'      | '1/10W'  | '0603LF'  | 'EMPTY'  | 'CS31003F907'(!)        = ''              | ''                 | 'CS31003F907'           | 'R0603'             | '(SMR0603AW)'                  | '10K'     | '1%'    | '1/10W'  | 'IO'       | 'RES CHIP 10K 1/10W+1%(0603)DAL_AEC'               | 'CHIPR0603'    | ''          | ''            | '20170717'
 '100K'       | '1%'      | '1/10W'  | '0603LF'  | 'CHIP'   | 'CS41003F905'(!)        = ''              | ''                 | 'CS41003F905'           | 'R0603'             | '(SMR0603AW)'                  | '100K'    | '1%'    | '1/10W'  | 'DISCRETE' | 'RES CHIP 100K 1/10W +-1%(0603) DAL_AEC'           | 'CHIPR0603'    | ''          | ''            | '20170717'
 '100K'       | '1%'      | '1/10W'  | '0603LF'  | 'EMPTY'  | 'CS41003F905'(!)        = ''              | ''                 | 'CS41003F905'           | 'R0603'             | '(SMR0603AW)'                  | '100K'    | '1%'    | '1/10W'  | 'IO'       | 'RES CHIP 100K 1/10W +-1%(0603) DAL_AEC'           | 'CHIPR0603'    | ''          | ''            | '20170717'
 '200K'       | '0.1%'    | '1/10W'  | '0603LF'  | 'CHIP'   | 'CS42003B904'(!)        = 'Non-Preferred' | 'End of Life'      | 'CS42003B904'           | 'R0603_EOL'         | '(SMR0603AW)'                  | '200K'    | '0.1%'  | '1/10W'  | 'DISCRETE' | 'RES CHIP 200K 1/10W +-0.1%(0603)DAL_AEC'          | 'CHIPR0603'    | ''          | ''            | '20170717'
 '200K'       | '0.1%'    | '1/10W'  | '0603LF'  | 'EMPTY'  | 'CS42003B904'(!)        = 'Non-Preferred' | 'End of Life'      | 'CS42003B904'           | 'R0603_EOL'         | '(SMR0603AW)'                  | '200K'    | '0.1%'  | '1/10W'  | 'IO'       | 'RES CHIP 200K 1/10W +-0.1%(0603)DAL_AEC'          | 'CHIPR0603'    | ''          | ''            | '20170717'
 '10M'        | '1%'      | '1/10W'  | '0603LF'  | 'CHIP'   | 'CS61003F903'(!)        = ''              | ''                 | 'CS61003F903'           | 'R0603'             | '(SMR0603AW)'                  | '10M'     | '1%'    | '1/10W'  | 'DISCRETE' | 'RES CHIP 10M 1/10W +-1%(0603)DAL_AEC'             | 'CHIPR0603'    | ''          | ''            | '20170717'
 '10M'        | '1%'      | '1/10W'  | '0603LF'  | 'EMPTY'  | 'CS61003F903'(!)        = ''              | ''                 | 'CS61003F903'           | 'R0603'             | '(SMR0603AW)'                  | '10M'     | '1%'    | '1/10W'  | 'IO'       | 'RES CHIP 10M 1/10W +-1%(0603)DAL_AEC'             | 'CHIPR0603'    | ''          | ''            | '20170717'
 '2K'         | '1%'      | '1/20W'  | '0201LF'  | 'CHIP'   | 'CS22001FE15'(!)        = ''              | ''                 | 'CS22001FE15'           | 'R0201'             | '(SMR0201AW)'                  | '2K'      | '1%'    | '1/20W'  | 'DISCRETE' | 'RES CHIP 2K(1/20W,+-1%,0201)'                     | 'CHIPR0201'    | ''          | ''            | '20170718'
 '2K'         | '1%'      | '1/20W'  | '0201LF'  | 'EMPTY'  | 'CS22001FE15'(!)        = ''              | ''                 | 'CS22001FE15'           | 'R0201'             | '(SMR0201AW)'                  | '2K'      | '1%'    | '1/20W'  | 'IO'       | 'RES CHIP 2K(1/20W,+-1%,0201)'                     | 'CHIPR0201'    | ''          | ''            | '20170718'
 '412K'       | '1%'      | '1/16W'  | '0402LF'  | 'CHIP'   | 'CS44122FB00'(!)        = 'End of Design' | 'Comp-Approve'     | 'CS44122FB00'           | 'R0402'             | '(R0402-0201)'                 | '412K'    | '1%'    | '1/16W'  | 'DISCRETE' | 'RES CHIP 412K 1/16W +-1%(0402)'                   | 'CHIPR0402'    | ''          | ''            | '20170718'
 '412K'       | '1%'      | '1/16W'  | '0402LF'  | 'EMPTY'  | 'CS44122FB00'(!)        = 'End of Design' | 'Comp-Approve'     | 'CS44122FB00'           | 'R0402'             | '(R0402-0201)'                 | '412K'    | '1%'    | '1/16W'  | 'IO'       | 'RES CHIP 412K 1/16W +-1%(0402)'                   | 'CHIPR0402'    | ''          | ''            | '20170718'
 '1'          | '1%'      | '1/2W'   | '1206LF'  | 'CHIP'   | 'CS-1007F200'(!)        = ''              | ''                 | 'CS-1007F200'           | 'R1206XJ'           | '(SMRR1206AW)'                 | '1'       | '1%'    | '1/2W'   | 'DISCRETE' | 'RES CHIP 1 1/2W +-1%(1206)'                       | 'CHIPR1206'    | ''          | ''            | '20170725'
 '1'          | '1%'      | '1/2W'   | '1206LF'  | 'EMPTY'  | 'CS-1007F200'(!)        = ''              | ''                 | 'CS-1007F200'           | 'R1206XJ'           | '(SMRR1206AW)'                 | '1'       | '1%'    | '1/2W'   | 'IO'       | 'RES CHIP 1 1/2W +-1%(1206)'                       | 'CHIPR1206'    | ''          | ''            | '20170725'
 '10K'        | '5%'      | '1W'     | '2512LF'  | 'CHIP'   | 'CS31008JR00'(!)        = ''              | ''                 | 'CS31008JR00'           | 'R2512XP'           | '(SMR2512AW)'                  | '10K'     | '5%'    | '1W'     | 'DISCRETE' | 'RES CHIP 10K 1W +-5%(2512)'                       | 'CHIPR2512'    | ''          | ''            | '20170804'
 '10K'        | '5%'      | '1W'     | '2512LF'  | 'EMPTY'  | 'CS31008JR00'(!)        = ''              | ''                 | 'CS31008JR00'           | 'R2512XP'           | '(SMR2512AW)'                  | '10K'     | '5%'    | '1W'     | 'IO'       | 'RES CHIP 10K 1W +-5%(2512)'                       | 'CHIPR2512'    | ''          | ''            | '20170804'
 '2.2K'       | '5%'      | '1/8W'   | '0805LF'  | 'CHIP'   | 'CS22204JA38'(!)        = ''              | ''                 | 'CS22204JA38'           | 'R0805'             | '(SMR0805AW)'                  | '2.2K'    | '5%'    | '1/8W'   | 'DISCRETE' | 'RES CHIP 2.2K 1/8W +-5%(0805)'                    | 'CHIPR0805'    | ''          | ''            | '20170809'
 '2.2K'       | '5%'      | '1/8W'   | '0805LF'  | 'EMPTY'  | 'CS22204JA38'(!)        = ''              | ''                 | 'CS22204JA38'           | 'R0805'             | '(SMR0805AW)'                  | '2.2K'    | '5%'    | '1/8W'   | 'IO'       | 'RES CHIP 2.2K 1/8W +-5%(0805)'                    | 'CHIPR0805'    | ''          | ''            | '20170809'
 '13.3K'      | '1%'      | '1/10W'  | '0603LF'  | 'CHIP'   | 'CS31333F919'(!)        = ''              | ''                 | 'CS31333F919'           | 'R0603'             | '(SMR0603AW)'                  | '13.3K'   | '1%'    | '1/10W'  | 'DISCRETE' | 'RES CHIP 13.3K 1/10W +-1%(0603)'                  | 'CHIPR0603'    | ''          | ''            | '20170809'
 '13.3K'      | '1%'      | '1/10W'  | '0603LF'  | 'EMPTY'  | 'CS31333F919'(!)        = ''              | ''                 | 'CS31333F919'           | 'R0603'             | '(SMR0603AW)'                  | '13.3K'   | '1%'    | '1/10W'  | 'IO'       | 'RES CHIP 13.3K 1/10W +-1%(0603)'                  | 'CHIPR0603'    | ''          | ''            | '20170809'
 '0.47'       | '1%'      | '1/8W'   | '0603LF ' | 'CHIP'   | 'CS+4704F901'(!)        = ''              | ''                 | 'CS+4704F901'           | 'R0603'             | '(SMR0603AW)'                  | '0.47'    | '1%'    | '1/8W'   | 'DISCRETE' | 'RESISTOR CHIP 0.47 1/8W+-1%(0603) EP'             | 'CHIPR0603'    | ''          | ''            | '20170811'
 '0.47'       | '1%'      | '1/8W'   | '0603LF ' | 'EMPTY'  | 'CS+4704F901'(!)        = ''              | ''                 | 'CS+4704F901'           | 'R0603'             | '(SMR0603AW)'                  | '0.47'    | '1%'    | '1/8W'   | 'IO'       | 'RESISTOR CHIP 0.47 1/8W+-1%(0603) EP'             | 'CHIPR0603'    | ''          | ''            | '20170811'
 '127K'       | '1%'      | '1/10W'  | '0603LF ' | 'CHIP'   | 'CS41273F915'(!)        = ''              | ''                 | 'CS41273F915'           | 'R0603'             | '(SMR0603AW)'                  | '127K'    | '1%'    | '1/10W'  | 'DISCRETE' | 'RES CHIP 127K 1/10W +-1%(0603)'                   | 'CHIPR0603'    | ''          | ''            | '20170817'
 '127K'       | '1%'      | '1/10W'  | '0603LF ' | 'EMPTY'  | 'CS41273F915'(!)        = ''              | ''                 | 'CS41273F915'           | 'R0603'             | '(SMR0603AW)'                  | '127K'    | '1%'    | '1/10W'  | 'IO'       | 'RES CHIP 127K 1/10W +-1%(0603)'                   | 'CHIPR0603'    | ''          | ''            | '20170817'
 '0.5'        | '1%'      | '1/2W'   | '1206LF'  | 'CHIP'   | 'CS+5007F200'(!)        = 'End of Design' | 'Comp-Approve'     | 'CS+5007F200'           | 'R1206XI'           | '(SMRR1206AW)'                 | '0.5'     | '1%'    | '1/2W'   | 'DISCRETE' | 'RES CHIP 0.5 1/2W +-1%(1206)'                     | 'CHIPR1206'    | ''          | ''            | '20170818'
 '0.5'        | '1%'      | '1/2W'   | '1206LF'  | 'EMPTY'  | 'CS+5007F200'(!)        = 'End of Design' | 'Comp-Approve'     | 'CS+5007F200'           | 'R1206XI'           | '(SMRR1206AW)'                 | '0.5'     | '1%'    | '1/2W'   | 'IO'       | 'RES CHIP 0.5 1/2W +-1%(1206)'                     | 'CHIPR1206'    | ''          | ''            | '20170818'
 '52.3K'      | '1%'      | '1/8W'   | '0805LF'  | 'CHIP'   | 'CS35234FA00'(!)        = ''              | ''                 | 'CS35234FA00'           | 'R0805'             | '(SMR0805AW)'                  | '52.3K'   | '1%'    | '1/8W'   | 'DISCRETE' | 'RES CHIP 52.3K 1/8W +-1%(0805)'                   | 'CHIPR0805'    | ''          | ''            | '20170821'
 '52.3K'      | '1%'      | '1/8W'   | '0805LF'  | 'EMPTY'  | 'CS35234FA00'(!)        = ''              | ''                 | 'CS35234FA00'           | 'R0805'             | '(SMR0805AW)'                  | '52.3K'   | '1%'    | '1/8W'   | 'IO'       | 'RES CHIP 52.3K 1/8W +-1%(0805)'                   | 'CHIPR0805'    | ''          | ''            | '20170821'
 '0.003'      | '1%'      | '2W'     | '2512LF'  | 'CHIP'   | 'CS+003AFR00'(!)        = ''              | ''                 | 'CS+003AFR00'           | 'R2512XM'           | '(SMR2512AW)'                  | '0.003'   | '1%'    | '2W'     | 'DISCRETE' | 'RES CHIP 0.003 2W +-1%(2512)'                     | 'CHIPR2512'    | ''          | ''            | '20170822'
 '0.003'      | '1%'      | '2W'     | '2512LF'  | 'EMPTY'  | 'CS+003AFR00'(!)        = ''              | ''                 | 'CS+003AFR00'           | 'R2512XM'           | '(SMR2512AW)'                  | '0.003'   | '1%'    | '2W'     | 'IO'       | 'RES CHIP 0.003 2W +-1%(2512)'                     | 'CHIPR2512'    | ''          | ''            | '20170822'
 '0.004'      | '1%'      | '2W'     | '2512LF'  | 'CHIP'   | 'CS+004AFR00'(!)        = ''              | ''                 | 'CS+004AFR00'           | 'R2512XM'           | '(SMR2512AW)'                  | '0.004'   | '1%'    | '2W'     | 'DISCRETE' | 'RES CHIP 0.004 2W +-1%(2512)'                     | 'CHIPR2512'    | ''          | ''            | '20170823'
 '0.004'      | '1%'      | '2W'     | '2512LF'  | 'EMPTY'  | 'CS+004AFR00'(!)        = ''              | ''                 | 'CS+004AFR00'           | 'R2512XM'           | '(SMR2512AW)'                  | '0.004'   | '1%'    | '2W'     | 'IO'       | 'RES CHIP 0.004 2W +-1%(2512)'                     | 'CHIPR2512'    | ''          | ''            | '20170823'
 '178K'       | '1%'      | '1/16W'  | '0402LF'  | 'CHIP'   | 'CS41782FB11'(!)        = 'End of Design' | 'Comp-Approve'     | 'CS41782FB11'           | 'R0402'             | '(R0402-0201)'                 | '178K'    | '1%'    | '1/16W'  | 'DISCRETE' | 'RES CHIP 178K 1/16W +-1%(0402)'                   | 'CHIP0402'     | ''          | ''            | '20170824'
 '178K'       | '1%'      | '1/16W'  | '0402LF'  | 'EMPTY'  | 'CS41782FB11'(!)        = 'End of Design' | 'Comp-Approve'     | 'CS41782FB11'           | 'R0402'             | '(R0402-0201)'                 | '178K'    | '1%'    | '1/16W'  | 'IO'       | 'RES CHIP 178K 1/16W +-1%(0402)'                   | 'CHIP0402'     | ''          | ''            | '20170824'
 '4.99'       | '0.1%'    | '2W'     | '2512LF'  | 'CHIP'   | 'CS-499ABR00'(!)        = 'Non-Preferred' | 'End of Life'      | 'CS-499ABR00'           | 'R2512XQ_EOL'       | '(SMR2512AW)'                  | '4.99'    | '0.1%'  | '2W'     | 'DISCRETE' | 'RES CHIP 4.99 2W  +-0.1%(2512)'                   | 'CHIPR2512'    | ''          | ''            | '20170830'
 '4.99'       | '0.1%'    | '2W'     | '2512LF'  | 'EMPTY'  | 'CS-499ABR00'(!)        = 'Non-Preferred' | 'End of Life'      | 'CS-499ABR00'           | 'R2512XQ_EOL'       | '(SMR2512AW)'                  | '4.99'    | '0.1%'  | '2W'     | 'IO'       | 'RES CHIP 4.99 2W  +-0.1%(2512)'                   | 'CHIPR2512'    | ''          | ''            | '20170830'
 '1'          | '1%'      | '2W'     | '2512LF'  | 'CHIP'   | 'CS-100AFR00'(!)        = ''              | ''                 | 'CS-100AFR00'           | 'R2512XQ'           | '(SMR2512AW)'                  | '1'       | '1%'    | '2W'     | 'DISCRETE' | 'RES CHIP 1  2W +-1%(2512)'                        | 'CHIPR2512'    | ''          | ''            | '20170830'
 '1'          | '1%'      | '2W'     | '2512LF'  | 'EMPTY'  | 'CS-100AFR00'(!)        = ''              | ''                 | 'CS-100AFR00'           | 'R2512XQ'           | '(SMR2512AW)'                  | '1'       | '1%'    | '2W'     | 'IO'       | 'RES CHIP 1  2W +-1%(2512)'                        | 'CHIPR2512'    | ''          | ''            | '20170830'
 '2.2'        | '5%'      | '2W'     | '2512LF'  | 'CHIP'   | 'CS-220AJR00'(!)        = ''              | ''                 | 'CS-220AJR00'           | 'R2512XQ'           | '(SMR2512AW)'                  | '2.2'     | '5%'    | '2W'     | 'DISCRETE' | 'RES CHIP 2.2 2W  +-5%(2512)'                      | 'CHIPR2512'    | ''          | ''            | '20170830'
 '2.2'        | '5%'      | '2W'     | '2512LF'  | 'EMPTY'  | 'CS-220AJR00'(!)        = ''              | ''                 | 'CS-220AJR00'           | 'R2512XQ'           | '(SMR2512AW)'                  | '2.2'     | '5%'    | '2W'     | 'IO'       | 'RES CHIP 2.2 2W  +-5%(2512)'                      | 'CHIPR2512'    | ''          | ''            | '20170830'
 '750K'       | '1%'      | '1/16W'  | '0402LF'  | 'CHIP'   | 'CS47502FB06'(!)        = ''              | ''                 | 'CS47502FB06'           | 'R0402'             | '(R0402-0201)'                 | '750K'    | '1%'    | '1/16W'  | 'DISCRETE' | 'RES CHIP 750K 1/16W +-1%(0402)'                   | 'CHIPR0402'    | ''          | ''            | '20170904'
 '750K'       | '1%'      | '1/16W'  | '0402LF'  | 'EMPTY'  | 'CS47502FB06'(!)        = ''              | ''                 | 'CS47502FB06'           | 'R0402'             | '(R0402-0201)'                 | '750K'    | '1%'    | '1/16W'  | 'IO'       | 'RES CHIP 750K 1/16W +-1%(0402)'                   | 'CHIPR0402'    | ''          | ''            | '20170904'
 '523K'       | '1%'      | '1/16W'  | '0402LF'  | 'CHIP'   | 'CS45232FB00'(!)        = 'End of Design' | 'Comp-Approve'     | 'CS45232FB00'           | 'R0402'             | '(R0402-0201)'                 | '523K'    | '1%'    | '1/16W'  | 'DISCRETE' | 'RES CHIP 523K 1/16W +-1%(0402)'                   | 'CHIPR0402'    | ''          | ''            | '20170907'
 '523K'       | '1%'      | '1/16W'  | '0402LF'  | 'EMPTY'  | 'CS45232FB00'(!)        = 'End of Design' | 'Comp-Approve'     | 'CS45232FB00'           | 'R0402'             | '(R0402-0201)'                 | '523K'    | '1%'    | '1/16W'  | 'IO'       | 'RES CHIP 523K 1/16W +-1%(0402)'                   | 'CHIPR0402'    | ''          | ''            | '20170907'
 '887K'       | '1%'      | '1/16W'  | '0402LF'  | 'CHIP'   | 'CS48872FB10'(!)        = 'End of Design' | 'Comp-Approve'     | 'CS48872FB10'           | 'R0402'             | '(R0402-0201)'                 | '887K'    | '1%'    | '1/16W'  | 'DISCRETE' | 'RES CHIP 887K 1/16W +-1%(0402)'                   | 'CHIPR0402'    | ''          | ''            | '20170907'
 '887K'       | '1%'      | '1/16W'  | '0402LF'  | 'EMPTY'  | 'CS48872FB10'(!)        = 'End of Design' | 'Comp-Approve'     | 'CS48872FB10'           | 'R0402'             | '(R0402-0201)'                 | '887K'    | '1%'    | '1/16W'  | 'IO'       | 'RES CHIP 887K 1/16W +-1%(0402)'                   | 'CHIPR0402'    | ''          | ''            | '20170907'
 '280'        | '1%'      | '1/16W'  | '0402LF'  | 'CHIP'   | 'CS12802FB00'(!)        = 'End of Design' | 'Comp-Approve'     | 'CS12802FB00'           | 'R0402'             | '(R0402-0201)'                 | '280'     | '1%'    | '1/16W'  | 'DISCRETE' | 'RES CHIP 280 1/16W +-1%(0402)'                    | 'CHIPR0402'    | ''          | ''            | '20170922'
 '280'        | '1%'      | '1/16W'  | '0402LF'  | 'EMPTY'  | 'CS12802FB00'(!)        = 'End of Design' | 'Comp-Approve'     | 'CS12802FB00'           | 'R0402'             | '(R0402-0201)'                 | '280'     | '1%'    | '1/16W'  | 'IO'       | 'RES CHIP 280 1/16W +-1%(0402)'                    | 'CHIPR0402'    | ''          | ''            | '20170922'
 '280'        | '1%'      | '1/16W'  | '0402LF'  | 'CHIP'   | 'CS12802FB08'(!)        = ''              | ''                 | 'CS12802FB08'           | 'R0402'             | '(R0402-0201)'                 | '280'     | '1%'    | '1/16W'  | 'DISCRETE' | 'RES CHIP 280 1/16W +-1% (0402)'                   | 'CHIPR0402'    | ''          | ''            | '20170922'
 '280'        | '1%'      | '1/16W'  | '0402LF'  | 'EMPTY'  | 'CS12802FB08'(!)        = ''              | ''                 | 'CS12802FB08'           | 'R0402'             | '(R0402-0201)'                 | '280'     | '1%'    | '1/16W'  | 'IO'       | 'RES CHIP 280 1/16W +-1% (0402)'                   | 'CHIPR0402'    | ''          | ''            | '20170922'
 '464'        | '1%'      | '1/16W'  | '0402LF'  | 'CHIP'   | 'CS14642FB04'(!)        = ''              | ''                 | 'CS14642FB04'           | 'R0402'             | '(R0402-0201)'                 | '464'     | '1%'    | '1/16W'  | 'DISCRETE' | 'RES CHIP 464 1/16W +-1%(0402)'                    | 'CHIPR0402'    | ''          | ''            | '20170922'
 '464'        | '1%'      | '1/16W'  | '0402LF'  | 'EMPTY'  | 'CS14642FB04'(!)        = ''              | ''                 | 'CS14642FB04'           | 'R0402'             | '(R0402-0201)'                 | '464'     | '1%'    | '1/16W'  | 'IO'       | 'RES CHIP 464 1/16W +-1%(0402)'                    | 'CHIPR0402'    | ''          | ''            | '20170922'
 '464'        | '1%'      | '1/16W'  | '0402LF'  | 'CHIP'   | 'CS14642FB12'(!)        = 'End of Design' | 'Comp-Approve'     | 'CS14642FB12'           | 'R0402'             | '(R0402-0201)'                 | '464'     | '1%'    | '1/16W'  | 'DISCRETE' | 'RES CHIP 464 1/16W +-1%(0402)'                    | 'CHIPR0402'    | ''          | ''            | '20170922'
 '464'        | '1%'      | '1/16W'  | '0402LF'  | 'EMPTY'  | 'CS14642FB12'(!)        = 'End of Design' | 'Comp-Approve'     | 'CS14642FB12'           | 'R0402'             | '(R0402-0201)'                 | '464'     | '1%'    | '1/16W'  | 'IO'       | 'RES CHIP 464 1/16W +-1%(0402)'                    | 'CHIPR0402'    | ''          | ''            | '20170922'
 '2.05K'      | '1%'      | '1/16W'  | '0402LF'  | 'CHIP'   | 'CS22052FB03'(!)        = ''              | ''                 | 'CS22052FB03'           | 'R0402'             | '(R0402-0201)'                 | '2.05K'   | '1%'    | '1/16W'  | 'DISCRETE' | 'RES CHIP 2.05K 1/16W +-1%(0402)'                  | 'CHIPR0402'    | ''          | ''            | '20170922'
 '2.05K'      | '1%'      | '1/16W'  | '0402LF'  | 'EMPTY'  | 'CS22052FB03'(!)        = ''              | ''                 | 'CS22052FB03'           | 'R0402'             | '(R0402-0201)'                 | '2.05K'   | '1%'    | '1/16W'  | 'IO'       | 'RES CHIP 2.05K 1/16W +-1%(0402)'                  | 'CHIPR0402'    | ''          | ''            | '20170922'
 '2.05K'      | '1%'      | '1/16W'  | '0402LF'  | 'CHIP'   | 'CS22052FB11'(!)        = 'End of Design' | 'Comp-Approve'     | 'CS22052FB11'           | 'R0402'             | '(R0402-0201)'                 | '2.05K'   | '1%'    | '1/16W'  | 'DISCRETE' | 'RES CHIP 2.05K 1/16W +-1%(0402)'                  | 'CHIPR0402'    | ''          | ''            | '20170922'
 '2.05K'      | '1%'      | '1/16W'  | '0402LF'  | 'EMPTY'  | 'CS22052FB11'(!)        = 'End of Design' | 'Comp-Approve'     | 'CS22052FB11'           | 'R0402'             | '(R0402-0201)'                 | '2.05K'   | '1%'    | '1/16W'  | 'IO'       | 'RES CHIP 2.05K 1/16W +-1%(0402)'                  | 'CHIPR0402'    | ''          | ''            | '20170922'
 '750K'       | '1%'      | '1/16W'  | '0402LF'  | 'CHIP'   | 'CS47502FB14'(!)        = 'End of Design' | 'Comp-Approve'     | 'CS47502FB14'           | 'R0402'             | '(R0402-0201)'                 | '750K'    | '1%'    | '1/16W'  | 'DISCRETE' | 'RES CHIP 750K 1/16W +-1%(0402)'                   | 'CHIPR0402'    | ''          | ''            | '20170925'
 '750K'       | '1%'      | '1/16W'  | '0402LF'  | 'EMPTY'  | 'CS47502FB14'(!)        = 'End of Design' | 'Comp-Approve'     | 'CS47502FB14'           | 'R0402'             | '(R0402-0201)'                 | '750K'    | '1%'    | '1/16W'  | 'IO'       | 'RES CHIP 750K 1/16W +-1%(0402)'                   | 'CHIPR0402'    | ''          | ''            | '20170925'
 '0.51'       | '1%'      | '1/3W'   | '0805LF'  | 'CHIP'   | 'CS+510CFA00'(!)        = ''              | ''                 | 'CS+510CFA00'           | 'R0805'             | '(SMR0805AW)'                  | '0.51'    | '1%'    | '1/3W'   | 'DISCRETE' | 'RES CHIP 0.51 1/3W +-1%(0805) YGO_AEC'            | 'CHIPR0805'    | ''          | ''            | '20171006'
 '0.51'       | '1%'      | '1/3W'   | '0805LF'  | 'EMPTY'  | 'CS+510CFA00'(!)        = ''              | ''                 | 'CS+510CFA00'           | 'R0805'             | '(SMR0805AW)'                  | '0.51'    | '1%'    | '1/3W'   | 'IO'       | 'RES CHIP 0.51 1/3W +-1%(0805) YGO_AEC'            | 'CHIPR0805'    | ''          | ''            | '20171006'
 '47.5'       | '1%'      | '1/16W'  | '0402LF'  | 'CHIP'   | 'CS04752FB19'(!)        = 'End of Design' | 'Comp-Approve'     | 'CS04752FB19'           | 'R0402'             | '(R0402-0201)'                 | '47.5'    | '1%'    | '1/16W'  | 'DISCRETE' | 'RES CHIP 47.5 1/16W +-1%(0402)'                   | 'CHIPR0402'    | ''          | ''            | '20171018'
 '47.5'       | '1%'      | '1/16W'  | '0402LF'  | 'EMPTY'  | 'CS04752FB19'(!)        = 'End of Design' | 'Comp-Approve'     | 'CS04752FB19'           | 'R0402'             | '(R0402-0201)'                 | '47.5'    | '1%'    | '1/16W'  | 'IO'       | 'RES CHIP 47.5 1/16W +-1%(0402)'                   | 'CHIPR0402'    | ''          | ''            | '20171018'
 '162'        | '1%'      | '1/20W'  | '0201LF'  | 'CHIP'   | 'CS11621FE00'(!)        = ''              | ''                 | 'CS11621FE00'           | 'R0201'             | '(SMR0201AW)'                  | '162'     | '1%'    | '1/20W'  | 'DISCRETE' | 'RES CHIP 162 1/20W +-1%(0201)'                    | 'CHIPR0201'    | ''          | ''            | '20171024'
 '162'        | '1%'      | '1/20W'  | '0201LF'  | 'EMPTY'  | 'CS11621FE00'(!)        = ''              | ''                 | 'CS11621FE00'           | 'R0201'             | '(SMR0201AW)'                  | '162'     | '1%'    | '1/20W'  | 'IO'       | 'RES CHIP 162 1/20W +-1%(0201)'                    | 'CHIPR0201'    | ''          | ''            | '20171024'
 '80.6'       | '1%'      | '1/20W'  | '0201LF'  | 'CHIP'   | 'CS08061FE00'(!)        = ''              | ''                 | 'CS08061FE00'           | 'R0201'             | '(SMR0201AW)'                  | '80.6'    | '1%'    | '1/20W'  | 'DISCRETE' | 'RES CHIP 80.6  1/20W +-1%(0201)'                  | 'CHIPR0201'    | ''          | ''            | '20171025'
 '80.6'       | '1%'      | '1/20W'  | '0201LF'  | 'EMPTY'  | 'CS08061FE00'(!)        = ''              | ''                 | 'CS08061FE00'           | 'R0201'             | '(SMR0201AW)'                  | '80.6'    | '1%'    | '1/20W'  | 'IO'       | 'RES CHIP 80.6  1/20W +-1%(0201)'                  | 'CHIPR0201'    | ''          | ''            | '20171025'
 '845K'       | '1%'      | '1/8W'   | '0805LF'  | 'CHIP'   | 'CS48454FA00'(!)        = ''              | ''                 | 'CS48454FA00'           | 'R0805'             | '(SMR0805AW)'                  | '845K'    | '1%'    | '1/8W'   | 'DISCRETE' | 'RES CHIP 845K 1/8W +-1%(0805)'                    | 'CHIPR0805'    | ''          | ''            | '20171026'
 '845K'       | '1%'      | '1/8W'   | '0805LF'  | 'EMPTY'  | 'CS48454FA00'(!)        = ''              | ''                 | 'CS48454FA00'           | 'R0805'             | '(SMR0805AW)'                  | '845K'    | '1%'    | '1/8W'   | 'IO'       | 'RES CHIP 845K 1/8W +-1%(0805)'                    | 'CHIPR0805'    | ''          | ''            | '20171026'
 '10'         | '1%'      | '2W'     | '2512LF'  | 'CHIP'   | 'CS0100AFR00'(!)        = ''              | ''                 | 'CS0100AFR00'           | 'R2512XR'           | '(SMR2512AW)'                  | '10'      | '1%'    | '2W'     | 'DISCRETE' | 'RES CHIP 10 2W +-1%(2512)'                        | 'CHIP2512'     | ''          | ''            | '20171030'
 '10'         | '1%'      | '2W'     | '2512LF'  | 'EMPTY'  | 'CS0100AFR00'(!)        = ''              | ''                 | 'CS0100AFR00'           | 'R2512XR'           | '(SMR2512AW)'                  | '10'      | '1%'    | '2W'     | 'IO'       | 'RES CHIP 10 2W +-1%(2512)'                        | 'CHIP2512'     | ''          | ''            | '20171030'
 '73.2'       | '1%'      | '1/2W'   | '1210LF'  | 'CHIP'   | 'CS07327F305'(!)        = ''              | ''                 | 'CS07327F305'           | 'R1210XA'           | '(SMR1210AW)'                  | '73.2'    | '1%'    | '1/2W'   | 'DISCRETE' | 'RES CHIP 73.2 1/2W +-1%(1210)'                    | 'CHIPR1210'    | ''          | ''            | '20171113'
 '73.2'       | '1%'      | '1/2W'   | '1210LF'  | 'EMPTY'  | 'CS07327F305'(!)        = ''              | ''                 | 'CS07327F305'           | 'R1210XA'           | '(SMR1210AW)'                  | '73.2'    | '1%'    | '1/2W'   | 'IO'       | 'RES CHIP 73.2 1/2W +-1%(1210)'                    | 'CHIPR1210'    | ''          | ''            | '20171113'
 '3.9'        | '1%'      | '1/16W'  | '0402LF'  | 'CHIP'   | 'CS-3902FB05'(!)        = ''              | ''                 | 'CS-3902FB05'           | 'R0402'             | '(R0402-0201)'                 | '3.9'     | '1%'    | '1/16W'  | 'DISCRETE' | 'RES CHIP 3.9 1/16W +-1% (0402)'                   | 'CHIPR0402'    | ''          | ''            | '20171127'
 '3.9'        | '1%'      | '1/16W'  | '0402LF'  | 'EMPTY'  | 'CS-3902FB05'(!)        = ''              | ''                 | 'CS-3902FB05'           | 'R0402'             | '(R0402-0201)'                 | '3.9'     | '1%'    | '1/16W'  | 'IO'       | 'RES CHIP 3.9 1/16W +-1% (0402)'                   | 'CHIPR0402'    | ''          | ''            | '20171127'
 '6.49K'      | '1%'      | '1/10W'  | '0603LF'  | 'CHIP'   | 'CS26493F911'(!)        = ''              | ''                 | 'CS26493F911'           | 'R0603'             | '(SMR0603AW)'                  | '6.49K'   | '1%'    | '1/10W'  | 'DISCRETE' | 'RES CHIP 6.49K 1/10W +-1%(0603)'                  | 'CHIPR0603'    | ''          | ''            | '20171130'
 '6.49K'      | '1%'      | '1/10W'  | '0603LF'  | 'EMPTY'  | 'CS26493F911'(!)        = ''              | ''                 | 'CS26493F911'           | 'R0603'             | '(SMR0603AW)'                  | '6.49K'   | '1%'    | '1/10W'  | 'IO'       | 'RES CHIP 6.49K 1/10W +-1%(0603)'                  | 'CHIPR0603'    | ''          | ''            | '20171130'
 '200'        | '1%'      | '1/20W'  | '0201LF'  | 'CHIP'   | 'CS12001FE01'(!)        = ''              | ''                 | 'CS12001FE01'           | 'R0201'             | '(SMR0201AW)'                  | '200'     | '1%'    | '1/20W'  | 'DISCRETE' | 'RES CHIP 200 1/20W +-1%(0201)'                    | 'CHIP0201'     | ''          | ''            | '20171130'
 '200'        | '1%'      | '1/20W'  | '0201LF'  | 'EMPTY'  | 'CS12001FE01'(!)        = ''              | ''                 | 'CS12001FE01'           | 'R0201'             | '(SMR0201AW)'                  | '200'     | '1%'    | '1/20W'  | 'IO'       | 'RES CHIP 200 1/20W +-1%(0201)'                    | 'CHIP0201'     | ''          | ''            | '20171130'
 '0.0002'     | '1%'      | '4W'     | '2725LF'  | 'CHIP'   | 'CS0000FFT06'(!)        = 'End of Design' | 'Comp-Approve'     | 'CS0000FFT06'           | 'R2725'             | '(SMR2725AW)'                  | '0.0002'  | '1%'    | '4W'     | 'DISCRETE' | 'RES CHIP 0.0002 4W +-1%(2725)1.1'                 | 'CHIP2725'     | ''          | ''            | '20171215'
 '0.0002'     | '1%'      | '4W'     | '2725LF'  | 'EMPTY'  | 'CS0000FFT06'(!)        = 'End of Design' | 'Comp-Approve'     | 'CS0000FFT06'           | 'R2725'             | '(SMR2725AW)'                  | '0.0002'  | '1%'    | '4W'     | 'IO'       | 'RES CHIP 0.0002 4W +-1%(2725)1.1'                 | 'CHIP2725'     | ''          | ''            | '20171215'
 '5.62K'      | '0.1%'    | '1/16W'  | '0402LF'  | 'CHIP'   | 'CS25622BB00'(!)        = ''              | ''                 | 'CS25622BB00'           | 'R0402'             | '(R0402-0201)'                 | '5.62K'   | '0.1%'  | '1/16W'  | 'DISCRETE' | 'RES CHIP 5.62K 1/16W +-0.1%(0402)'                | 'CHIPR0402'    | ''          | ''            | '20180103'
 '5.62K'      | '0.1%'    | '1/16W'  | '0402LF'  | 'EMPTY'  | 'CS25622BB00'(!)        = ''              | ''                 | 'CS25622BB00'           | 'R0402'             | '(R0402-0201)'                 | '5.62K'   | '0.1%'  | '1/16W'  | 'IO'       | 'RES CHIP 5.62K 1/16W +-0.1%(0402)'                | 'CHIPR0402'    | ''          | ''            | '20180103'
 '143'        | '1%'      | '1/16W'  | '0402LF'  | 'CHIP'   | 'CS11432FB00'(!)        = 'End of Design' | 'Comp-Approve'     | 'CS11432FB00'           | 'R0402'             | '(R0402-0201)'                 | '143'     | '1%'    | '1/16W'  | 'DISCRETE' | 'RES CHIP 143 1/16W +-1%(0402)'                    | 'CHIPR0402'    | ''          | ''            | '20100429'
 '143'        | '1%'      | '1/16W'  | '0402LF'  | 'EMPTY'  | 'CS11432FB00'(!)        = 'End of Design' | 'Comp-Approve'     | 'CS11432FB00'           | 'R0402'             | '(R0402-0201)'                 | '143'     | '1%'    | '1/16W'  | 'IO'       | 'RES CHIP 143 1/16W +-1%(0402)'                    | 'CHIPR0402'    | ''          | ''            | '20100429'
 '86.6'       | '1%'      | '1/16W'  | '0402LF'  | 'CHIP'   | 'CS08662FB00'(!)        = 'End of Design' | 'Comp-Approve'     | 'CS08662FB00'           | 'R0402'             | '(R0402-0201)'                 | '86.6'    | '1%'    | '1/16W'  | 'DISCRETE' | 'RES CHIP 86.6 1/16W +-1%(0402)'                   | 'CHIP0402'     | ''          | ''            | '20180109'
 '86.6'       | '1%'      | '1/16W'  | '0402LF'  | 'EMPTY'  | 'CS08662FB00'(!)        = 'End of Design' | 'Comp-Approve'     | 'CS08662FB00'           | 'R0402'             | '(R0402-0201)'                 | '86.6'    | '1%'    | '1/16W'  | 'IO'       | 'RES CHIP 86.6 1/16W +-1%(0402)'                   | 'CHIP0402'     | ''          | ''            | '20180109'
 '120'        | '1%'      | '1/16W'  | '0402LF'  | 'CHIP'   | 'CS11202FB02'(!)        = 'End of Design' | 'Comp-Approve'     | 'CS11202FB02'           | 'R0402'             | '(R0402-0201)'                 | '120'     | '1%'    | '1/16W'  | 'DISCRETE' | 'RES CHIP 120 1/16W +-1%(0402)EF'                  | 'CHIPR0402'    | ''          | ''            | '20180116'
 '120'        | '1%'      | '1/16W'  | '0402LF'  | 'EMPTY'  | 'CS11202FB02'(!)        = 'End of Design' | 'Comp-Approve'     | 'CS11202FB02'           | 'R0402'             | '(R0402-0201)'                 | '120'     | '1%'    | '1/16W'  | 'IO'       | 'RES CHIP 120 1/16W +-1%(0402)EF'                  | 'CHIPR0402'    | ''          | ''            | '20180116'
 '57.6K'      | '0.1%'    | '1/16W'  | '0402LF'  | 'CHIP'   | 'CS35762BB00'(!)        = ''              | ''                 | 'CS35762BB00'           | 'R0402'             | '(R0402-0201)'                 | '57.6K'   | '0.1%'  | '1/16W'  | 'DISCRETE' | 'RES CHIP 57.6K 1/16W +-0.1% (0402)'               | 'CHIPR0402'    | ''          | ''            | '20150414'
 '57.6K'      | '0.1%'    | '1/16W'  | '0402LF'  | 'EMPTY'  | 'CS35762BB00'(!)        = ''              | ''                 | 'CS35762BB00'           | 'R0402'             | '(R0402-0201)'                 | '57.6K'   | '0.1%'  | '1/16W'  | 'IO'       | 'RES CHIP 57.6K 1/16W +-0.1% (0402)'               | 'CHIPR0402'    | ''          | ''            | '20150414'
 '10.2K'      | '1%'      | '1/16W'  | '0402LF'  | 'CHIP'   | 'CS31022FB04'(!)        = 'End of Design' | 'Comp-Approve'     | 'CS31022FB04'           | 'R0402'             | '(R0402-0201)'                 | '10.2K'   | '1%'    | '1/16W'  | 'DISCRETE' | 'RES CHIP 10.2K 1/16W +-1%(0402)EF'                | 'CHIPR0402'    | ''          | ''            | '20180116'
 '10.2K'      | '1%'      | '1/16W'  | '0402LF'  | 'EMPTY'  | 'CS31022FB04'(!)        = 'End of Design' | 'Comp-Approve'     | 'CS31022FB04'           | 'R0402'             | '(R0402-0201)'                 | '10.2K'   | '1%'    | '1/16W'  | 'IO'       | 'RES CHIP 10.2K 1/16W +-1%(0402)EF'                | 'CHIPR0402'    | ''          | ''            | '20180116'
 '4.02K'      | '0.1%'    | '1/16W'  | '0402LF'  | 'CHIP'   | 'CS24022BB00'(!)        = ''              | ''                 | 'CS24022BB00'           | 'R0402'             | '(R0402-0201)'                 | '4.02K'   | '0.1%'  | '1/16W'  | 'DISCRETE' | 'RES CHIP 4.02K 1/16W  +-0.1%(0402)'               | 'CHIPR0402'    | ''          | ''            | '20170829'
 '4.02K'      | '0.1%'    | '1/16W'  | '0402LF'  | 'EMPTY'  | 'CS24022BB00'(!)        = ''              | ''                 | 'CS24022BB00'           | 'R0402'             | '(R0402-0201)'                 | '4.02K'   | '0.1%'  | '1/16W'  | 'IO'       | 'RES CHIP 4.02K 1/16W  +-0.1%(0402)'               | 'CHIPR0402'    | ''          | ''            | '20170829'
 '375'        | '1%'      | '1/10W'  | '0603LF'  | 'CHIP'   | 'CS13753F906'(!)        = 'End of Design' | 'Comp-Approve'     | 'CS13753F906'           | 'R0603'             | '(SMR0603AW)'                  | '375'     | '1%'    | '1/10W'  | 'DISCRETE' | 'RES CHIP 375 1/10W+-1%(0603)'                     | 'CHIP0603'     | ''          | ''            | '20180131'
 '375'        | '1%'      | '1/10W'  | '0603LF'  | 'EMPTY'  | 'CS13753F906'(!)        = 'End of Design' | 'Comp-Approve'     | 'CS13753F906'           | 'R0603'             | '(SMR0603AW)'                  | '375'     | '1%'    | '1/10W'  | 'IO'       | 'RES CHIP 375 1/10W+-1%(0603)'                     | 'CHIP0603'     | ''          | ''            | '20180131'
 '576K'       | '1%'      | '1/16W'  | '0402LF'  | 'CHIP'   | 'CS45762FB13'(!)        = 'End of Design' | 'Comp-Approve'     | 'CS45762FB13'           | 'R0402'             | '(R0402-0201)'                 | '576K'    | '1%'    | '1/16W'  | 'DISCRETE' | 'RES CHIP 576K 1/16W +-1%(0402)'                   | 'CHIPR0402'    | ''          | ''            | '20180206'
 '576K'       | '1%'      | '1/16W'  | '0402LF'  | 'EMPTY'  | 'CS45762FB13'(!)        = 'End of Design' | 'Comp-Approve'     | 'CS45762FB13'           | 'R0402'             | '(R0402-0201)'                 | '576K'    | '1%'    | '1/16W'  | 'IO'       | 'RES CHIP 576K 1/16W +-1%(0402)'                   | 'CHIPR0402'    | ''          | ''            | '20180206'
 '1.1M'       | '1%'      | '1/16W'  | '0402LF'  | 'CHIP'   | 'CS51102FB00'(!)        = ''              | ''                 | 'CS51102FB00'           | 'R0402'             | '(R0402-0201)'                 | '1.1M'    | '1%'    | '1/16W'  | 'DISCRETE' | 'RES CHIP 1.1M 1/16W +-1%(0402)'                   | 'CHIPR0402'    | ''          | ''            | '20180206'
 '1.1M'       | '1%'      | '1/16W'  | '0402LF'  | 'EMPTY'  | 'CS51102FB00'(!)        = ''              | ''                 | 'CS51102FB00'           | 'R0402'             | '(R0402-0201)'                 | '1.1M'    | '1%'    | '1/16W'  | 'IO'       | 'RES CHIP 1.1M 1/16W +-1%(0402)'                   | 'CHIPR0402'    | ''          | ''            | '20180206'
 '1.18M'      | '1%'      | '1/16W'  | '0402LF'  | 'CHIP'   | 'CS51182FB01'(!)        = ''              | ''                 | 'CS51182FB01'           | 'R0402'             | '(R0402-0201)'                 | '1.18M'   | '1%'    | '1/16W'  | 'DISCRETE' | 'RES CHIP 1.18M 1/16W +-1%(0402)'                  | 'CHIPR0402'    | ''          | ''            | '20180207'
 '1.18M'      | '1%'      | '1/16W'  | '0402LF'  | 'EMPTY'  | 'CS51182FB01'(!)        = ''              | ''                 | 'CS51182FB01'           | 'R0402'             | '(R0402-0201)'                 | '1.18M'   | '1%'    | '1/16W'  | 'IO'       | 'RES CHIP 1.18M 1/16W +-1%(0402)'                  | 'CHIPR0402'    | ''          | ''            | '20180207'
 '1.13M'      | '1%'      | '1/16W'  | '0402LF'  | 'CHIP'   | 'CS51132FB00'(!)        = ''              | ''                 | 'CS51132FB00'           | 'R0402'             | '(R0402-0201)'                 | '1.13M'   | '1%'    | '1/16W'  | 'DISCRETE' | 'RES CHIP 1.13M 1/16W +-1%(0402)'                  | 'CHIPR0402'    | ''          | ''            | '20180207'
 '1.13M'      | '1%'      | '1/16W'  | '0402LF'  | 'EMPTY'  | 'CS51132FB00'(!)        = ''              | ''                 | 'CS51132FB00'           | 'R0402'             | '(R0402-0201)'                 | '1.13M'   | '1%'    | '1/16W'  | 'IO'       | 'RES CHIP 1.13M 1/16W +-1%(0402)'                  | 'CHIPR0402'    | ''          | ''            | '20180207'
 '0.51'       | '1%'      | '1/16W'  | '0402LF'  | 'CHIP'   | 'CS+5102FB01'(!)        = ''              | ''                 | 'CS+5102FB01'           | 'R0402'             | '(R0402-0201)'                 | '0.51'    | '1%'    | '1/16W'  | 'DISCRETE' | 'RES CHIP 0.51 1/16W +-1%(0402)EF'                 | 'CHIP0402'     | ''          | ''            | '20180212'
 '0.51'       | '1%'      | '1/16W'  | '0402LF'  | 'EMPTY'  | 'CS+5102FB01'(!)        = ''              | ''                 | 'CS+5102FB01'           | 'R0402'             | '(R0402-0201)'                 | '0.51'    | '1%'    | '1/16W'  | 'IO'       | 'RES CHIP 0.51 1/16W +-1%(0402)EF'                 | 'CHIP0402'     | ''          | ''            | '20180212'
 '143'        | '1%'      | '1/16W'  | '0402LF'  | 'CHIP'   | 'CS11432FB02'(!)        = ''              | ''                 | 'CS11432FB02'           | 'R0402'             | '(R0402-0201)'                 | '143'     | '1%'    | '1/16W'  | 'DISCRETE' | 'RES CHIP 143 1/16W +-1%(0402)EF'                  | 'CHIP0402'     | ''          | ''            | '20180212'
 '143'        | '1%'      | '1/16W'  | '0402LF'  | 'EMPTY'  | 'CS11432FB02'(!)        = ''              | ''                 | 'CS11432FB02'           | 'R0402'             | '(R0402-0201)'                 | '143'     | '1%'    | '1/16W'  | 'IO'       | 'RES CHIP 143 1/16W +-1%(0402)EF'                  | 'CHIP0402'     | ''          | ''            | '20180212'
 '220'        | '1%'      | '1/16W'  | '0402LF'  | 'CHIP'   | 'CS12202FB04'(!)        = ''              | ''                 | 'CS12202FB04'           | 'R0402'             | '(R0402-0201)'                 | '220'     | '1%'    | '1/16W'  | 'DISCRETE' | 'RES CHIP 220 1/16W +-1%(0402)EF'                  | 'CHIP0402'     | ''          | ''            | '20180212'
 '220'        | '1%'      | '1/16W'  | '0402LF'  | 'EMPTY'  | 'CS12202FB04'(!)        = ''              | ''                 | 'CS12202FB04'           | 'R0402'             | '(R0402-0201)'                 | '220'     | '1%'    | '1/16W'  | 'IO'       | 'RES CHIP 220 1/16W +-1%(0402)EF'                  | 'CHIP0402'     | ''          | ''            | '20180212'
 '1K'         | '1%'      | '1/20W'  | '0201LF'  | 'CHIP'   | 'CS21001FE07'(!)        = ''              | ''                 | 'CS21001FE07'           | 'R0201'             | '(SMR0201AW)'                  | '1K'      | '1%'    | '1/20W'  | 'DISCRETE' | 'RES CHIP 1K 1/20W +-1%(0201)EF'                   | 'CHIP0201'     | ''          | ''            | '20180212'
 '1K'         | '1%'      | '1/20W'  | '0201LF'  | 'EMPTY'  | 'CS21001FE07'(!)        = ''              | ''                 | 'CS21001FE07'           | 'R0201'             | '(SMR0201AW)'                  | '1K'      | '1%'    | '1/20W'  | 'IO'       | 'RES CHIP 1K 1/20W +-1%(0201)EF'                   | 'CHIP0201'     | ''          | ''            | '20180212'
 '5.62K'      | '0.1%'    | '1/16W'  | '0402LF'  | 'CHIP'   | 'CS25622BB01'(!)        = ''              | ''                 | 'CS25622BB01'           | 'R0402'             | '(R0402-0201)'                 | '5.62K'   | '0.1%'  | '1/16W'  | 'DISCRETE' | 'RES CHIP 5.62K 1/16W +-0.1%(0402)EF'              | 'CHIP0402'     | ''          | ''            | '20180212'
 '5.62K'      | '0.1%'    | '1/16W'  | '0402LF'  | 'EMPTY'  | 'CS25622BB01'(!)        = ''              | ''                 | 'CS25622BB01'           | 'R0402'             | '(R0402-0201)'                 | '5.62K'   | '0.1%'  | '1/16W'  | 'IO'       | 'RES CHIP 5.62K 1/16W +-0.1%(0402)EF'              | 'CHIP0402'     | ''          | ''            | '20180212'
 '6.2K'       | '1%'      | '1/16W'  | '0402LF'  | 'CHIP'   | 'CS26202FB02'(!)        = ''              | ''                 | 'CS26202FB02'           | 'R0402'             | '(R0402-0201)'                 | '6.2K'    | '1%'    | '1/16W'  | 'DISCRETE' | 'RES CHIP 6.2K 1/16W +-1%(0402)EF'                 | 'CHIP0402'     | ''          | ''            | '20180212'
 '6.2K'       | '1%'      | '1/16W'  | '0402LF'  | 'EMPTY'  | 'CS26202FB02'(!)        = ''              | ''                 | 'CS26202FB02'           | 'R0402'             | '(R0402-0201)'                 | '6.2K'    | '1%'    | '1/16W'  | 'IO'       | 'RES CHIP 6.2K 1/16W +-1%(0402)EF'                 | 'CHIP0402'     | ''          | ''            | '20180212'
 '6.8K'       | '1%'      | '1/16W'  | '0402LF'  | 'CHIP'   | 'CS26802FB02'(!)        = ''              | ''                 | 'CS26802FB02'           | 'R0402'             | '(R0402-0201)'                 | '6.8K'    | '1%'    | '1/16W'  | 'DISCRETE' | 'RES CHIP 6.8K 1/16W +-1%(0402)EF'                 | 'CHIP0402'     | ''          | ''            | '20180212'
 '6.8K'       | '1%'      | '1/16W'  | '0402LF'  | 'EMPTY'  | 'CS26802FB02'(!)        = ''              | ''                 | 'CS26802FB02'           | 'R0402'             | '(R0402-0201)'                 | '6.8K'    | '1%'    | '1/16W'  | 'IO'       | 'RES CHIP 6.8K 1/16W +-1%(0402)EF'                 | 'CHIP0402'     | ''          | ''            | '20180212'
 '7.5K'       | '0.1%'    | '1/16W'  | '0402LF'  | 'CHIP'   | 'CS27502BB01'(!)        = ''              | ''                 | 'CS27502BB01'           | 'R0402'             | '(R0402-0201)'                 | '7.5K'    | '0.1%'  | '1/16W'  | 'DISCRETE' | 'RES CHIP 7.5K 1/16W +-0.1%(0402)EF'               | 'CHIP0402'     | ''          | ''            | '20180212'
 '7.5K'       | '0.1%'    | '1/16W'  | '0402LF'  | 'EMPTY'  | 'CS27502BB01'(!)        = ''              | ''                 | 'CS27502BB01'           | 'R0402'             | '(R0402-0201)'                 | '7.5K'    | '0.1%'  | '1/16W'  | 'IO'       | 'RES CHIP 7.5K 1/16W +-0.1%(0402)EF'               | 'CHIP0402'     | ''          | ''            | '20180212'
 '8.45K'      | '1%'      | '1/16W'  | '0402LF'  | 'CHIP'   | 'CS28452FB06'(!)        = ''              | ''                 | 'CS28452FB06'           | 'R0402'             | '(R0402-0201)'                 | '8.45K'   | '1%'    | '1/16W'  | 'DISCRETE' | 'RES CHIP 8.45K 1/16W +-1%( 0402)EF'               | 'CHIP0402'     | ''          | ''            | '20180212'
 '8.45K'      | '1%'      | '1/16W'  | '0402LF'  | 'EMPTY'  | 'CS28452FB06'(!)        = ''              | ''                 | 'CS28452FB06'           | 'R0402'             | '(R0402-0201)'                 | '8.45K'   | '1%'    | '1/16W'  | 'IO'       | 'RES CHIP 8.45K 1/16W +-1%( 0402)EF'               | 'CHIP0402'     | ''          | ''            | '20180212'
 '12K'        | '0.1%'    | '1/16W'  | '0402LF'  | 'CHIP'   | 'CS31202BB01'(!)        = ''              | ''                 | 'CS31202BB01'           | 'R0402'             | '(R0402-0201)'                 | '12K'     | '0.1%'  | '1/16W'  | 'DISCRETE' | 'RES CHIP 12K 1/16W +-0.1%(0402)EF'                | 'CHIP0402'     | ''          | ''            | '20180212'
 '12K'        | '0.1%'    | '1/16W'  | '0402LF'  | 'EMPTY'  | 'CS31202BB01'(!)        = ''              | ''                 | 'CS31202BB01'           | 'R0402'             | '(R0402-0201)'                 | '12K'     | '0.1%'  | '1/16W'  | 'IO'       | 'RES CHIP 12K 1/16W +-0.1%(0402)EF'                | 'CHIP0402'     | ''          | ''            | '20180212'
 '20K'        | '5%'      | '1/16W'  | '0402LF'  | 'CHIP'   | 'CS32002JB06'(!)        = ''              | ''                 | 'CS32002JB06'           | 'R0402'             | '(R0402-0201)'                 | '20K'     | '5%'    | '1/16W'  | 'DISCRETE' | 'RES CHIP 20K 1/16W +-5%(0402)EF'                  | 'CHIP0402'     | ''          | ''            | '20180212'
 '20K'        | '5%'      | '1/16W'  | '0402LF'  | 'EMPTY'  | 'CS32002JB06'(!)        = ''              | ''                 | 'CS32002JB06'           | 'R0402'             | '(R0402-0201)'                 | '20K'     | '5%'    | '1/16W'  | 'IO'       | 'RES CHIP 20K 1/16W +-5%(0402)EF'                  | 'CHIP0402'     | ''          | ''            | '20180212'
 '34K'        | '1%'      | '1/16W'  | '0402LF'  | 'CHIP'   | 'CS33402FB06'(!)        = ''              | ''                 | 'CS33402FB06'           | 'R0402'             | '(R0402-0201)'                 | '34K'     | '1%'    | '1/16W'  | 'DISCRETE' | 'RES CHIP 34K 1/16W +-1%(0402)EF'                  | 'CHIP0402'     | ''          | ''            | '20180212'
 '34K'        | '1%'      | '1/16W'  | '0402LF'  | 'EMPTY'  | 'CS33402FB06'(!)        = ''              | ''                 | 'CS33402FB06'           | 'R0402'             | '(R0402-0201)'                 | '34K'     | '1%'    | '1/16W'  | 'IO'       | 'RES CHIP 34K 1/16W +-1%(0402)EF'                  | 'CHIP0402'     | ''          | ''            | '20180212'
 '1.87K'      | '0.1%'    | '1/16W'  | '0402LF'  | 'CHIP'   | 'CS21872BB00'(!)        = ''              | ''                 | 'CS21872BB00'           | 'R0402'             | '(R0402-0201)'                 | '1.87K'   | '0.1%'  | '1/16W'  | 'DISCRETE' | 'RES CHIP 1.87K 1/16W +-0.1%(0402)EF'              | 'CHIP0402'     | ''          | ''            | '20180212'
 '1.87K'      | '0.1%'    | '1/16W'  | '0402LF'  | 'EMPTY'  | 'CS21872BB00'(!)        = ''              | ''                 | 'CS21872BB00'           | 'R0402'             | '(R0402-0201)'                 | '1.87K'   | '0.1%'  | '1/16W'  | 'IO'       | 'RES CHIP 1.87K 1/16W +-0.1%(0402)EF'              | 'CHIP0402'     | ''          | ''            | '20180212'
 '2.37K'      | '0.1%'    | '1/16W'  | '0402LF'  | 'CHIP'   | 'CS22372BB02'(!)        = ''              | ''                 | 'CS22372BB02'           | 'R0402'             | '(R0402-0201)'                 | '2.37K'   | '0.1%'  | '1/16W'  | 'DISCRETE' | 'RES CHIP 2.37K 1/16W +-0.1%(0402)EF'              | 'CHIP0402'     | ''          | ''            | '20180212'
 '2.37K'      | '0.1%'    | '1/16W'  | '0402LF'  | 'EMPTY'  | 'CS22372BB02'(!)        = ''              | ''                 | 'CS22372BB02'           | 'R0402'             | '(R0402-0201)'                 | '2.37K'   | '0.1%'  | '1/16W'  | 'IO'       | 'RES CHIP 2.37K 1/16W +-0.1%(0402)EF'              | 'CHIP0402'     | ''          | ''            | '20180212'
 '4.02K'      | '0.1%'    | '1/16W'  | '0402LF'  | 'CHIP'   | 'CS24022BB01'(!)        = ''              | ''                 | 'CS24022BB01'           | 'R0402'             | '(R0402-0201)'                 | '4.02K'   | '0.1%'  | '1/16W'  | 'DISCRETE' | 'RES CHIP 4.02K 1/16W +-0.1%(0402)EF'              | 'CHIP0402'     | ''          | ''            | '20180212'
 '4.02K'      | '0.1%'    | '1/16W'  | '0402LF'  | 'EMPTY'  | 'CS24022BB01'(!)        = ''              | ''                 | 'CS24022BB01'           | 'R0402'             | '(R0402-0201)'                 | '4.02K'   | '0.1%'  | '1/16W'  | 'IO'       | 'RES CHIP 4.02K 1/16W +-0.1%(0402)EF'              | 'CHIP0402'     | ''          | ''            | '20180212'
 '57.6K'      | '0.1%'    | '1/16W'  | '0402LF'  | 'CHIP'   | 'CS35762BB01'(!)        = ''              | ''                 | 'CS35762BB01'           | 'R0402'             | '(R0402-0201)'                 | '57.6K'   | '0.1%'  | '1/16W'  | 'DISCRETE' | 'RES CHIP 57.6K 1/16W +-0.1%(0402)EF'              | 'CHIP0402'     | ''          | ''            | '20180212'
 '57.6K'      | '0.1%'    | '1/16W'  | '0402LF'  | 'EMPTY'  | 'CS35762BB01'(!)        = ''              | ''                 | 'CS35762BB01'           | 'R0402'             | '(R0402-0201)'                 | '57.6K'   | '0.1%'  | '1/16W'  | 'IO'       | 'RES CHIP 57.6K 1/16W +-0.1%(0402)EF'              | 'CHIP0402'     | ''          | ''            | '20180212'
 '100K'       | '0.1%'    | '1/16W'  | '0402LF'  | 'CHIP'   | 'CS41002BB08'(!)        = ''              | ''                 | 'CS41002BB08'           | 'R0402'             | '(R0402-0201)'                 | '100K'    | '0.1%'  | '1/16W'  | 'DISCRETE' | 'RES CHIP 100K 1/16W +-0.1%(0402)EF'               | 'CHIP0402'     | ''          | ''            | '20180212'
 '100K'       | '0.1%'    | '1/16W'  | '0402LF'  | 'EMPTY'  | 'CS41002BB08'(!)        = ''              | ''                 | 'CS41002BB08'           | 'R0402'             | '(R0402-0201)'                 | '100K'    | '0.1%'  | '1/16W'  | 'IO'       | 'RES CHIP 100K 1/16W +-0.1%(0402)EF'               | 'CHIP0402'     | ''          | ''            | '20180212'
 '2.2'        | '1%'      | '1/16W'  | '0402LF'  | 'CHIP'   | 'CS-2202FB01'(!)        = 'End of Design' | 'Comp-Approve'     | 'CS-2202FB01'           | 'R0402'             | '(R0402-0201)'                 | '2.2'     | '1%'    | '1/16W'  | 'DISCRETE' | 'RES CHIP 2.2 1/16W +-1%(0402)EF'                  | 'CHIP0402'     | ''          | ''            | '20180212'
 '2.2'        | '1%'      | '1/16W'  | '0402LF'  | 'EMPTY'  | 'CS-2202FB01'(!)        = 'End of Design' | 'Comp-Approve'     | 'CS-2202FB01'           | 'R0402'             | '(R0402-0201)'                 | '2.2'     | '1%'    | '1/16W'  | 'IO'       | 'RES CHIP 2.2 1/16W +-1%(0402)EF'                  | 'CHIP0402'     | ''          | ''            | '20180212'
 '0'          | '5%'      | '1/20W'  | '0201LF'  | 'CHIP'   | 'CS00001JE10'(!)        = 'End of Design' | 'Comp-Approve'     | 'CS00001JE10'           | 'R0201'             | '(SMR0201AW)'                  | '0'       | '5%'    | '1/20W'  | 'DISCRETE' | 'RES CHIP 0 1/20W +-5% (0201)EF'                   | 'CHIP0201'     | ''          | ''            | '20180212'
 '0'          | '5%'      | '1/20W'  | '0201LF'  | 'EMPTY'  | 'CS00001JE10'(!)        = 'End of Design' | 'Comp-Approve'     | 'CS00001JE10'           | 'R0201'             | '(SMR0201AW)'                  | '0'       | '5%'    | '1/20W'  | 'IO'       | 'RES CHIP 0 1/20W +-5% (0201)EF'                   | 'CHIP0201'     | ''          | ''            | '20180212'
 '22'         | '5%'      | '1/16W'  | '0402LF'  | 'CHIP'   | 'CS02202JB09'(!)        = 'End of Design' | 'Comp-Approve'     | 'CS02202JB09'           | 'R0402'             | '(R0402-0201)'                 | '22'      | '5%'    | '1/16W'  | 'DISCRETE' | 'RES CHIP 22 1/16W +-5%(0402)EF'                   | 'CHIP0402'     | ''          | ''            | '20180212'
 '22'         | '5%'      | '1/16W'  | '0402LF'  | 'EMPTY'  | 'CS02202JB09'(!)        = 'End of Design' | 'Comp-Approve'     | 'CS02202JB09'           | 'R0402'             | '(R0402-0201)'                 | '22'      | '5%'    | '1/16W'  | 'IO'       | 'RES CHIP 22 1/16W +-5%(0402)EF'                   | 'CHIP0402'     | ''          | ''            | '20180212'
 '51'         | '5%'      | '1/16W'  | '0402LF'  | 'CHIP'   | 'CS05102JB04'(!)        = 'End of Design' | 'Comp-Approve'     | 'CS05102JB04'           | 'R0402'             | '(R0402-0201)'                 | '51'      | '5%'    | '1/16W'  | 'DISCRETE' | 'RES CHIP 51 1/16W +-5%(0402)EF'                   | 'CHIP0402'     | ''          | ''            | '20180212'
 '51'         | '5%'      | '1/16W'  | '0402LF'  | 'EMPTY'  | 'CS05102JB04'(!)        = 'End of Design' | 'Comp-Approve'     | 'CS05102JB04'           | 'R0402'             | '(R0402-0201)'                 | '51'      | '5%'    | '1/16W'  | 'IO'       | 'RES CHIP 51 1/16W +-5%(0402)EF'                   | 'CHIP0402'     | ''          | ''            | '20180212'
 '82.5'       | '1%'      | '1/16W'  | '0402LF'  | 'CHIP'   | 'CS08252FB02'(!)        = 'End of Design' | 'Comp-Approve'     | 'CS08252FB02'           | 'R0402'             | '(R0402-0201)'                 | '82.5'    | '1%'    | '1/16W'  | 'DISCRETE' | 'RES CHIP 82.5 1/16W +-1%(0402)EF'                 | 'CHIP0402'     | ''          | ''            | '20180212'
 '82.5'       | '1%'      | '1/16W'  | '0402LF'  | 'EMPTY'  | 'CS08252FB02'(!)        = 'End of Design' | 'Comp-Approve'     | 'CS08252FB02'           | 'R0402'             | '(R0402-0201)'                 | '82.5'    | '1%'    | '1/16W'  | 'IO'       | 'RES CHIP 82.5 1/16W +-1%(0402)EF'                 | 'CHIP0402'     | ''          | ''            | '20180212'
 '330'        | '1%'      | '1/16W'  | '0402LF'  | 'CHIP'   | 'CS13302FB00'(!)        = 'End of Design' | 'Comp-Approve'     | 'CS13302FB00'           | 'R0402'             | '(R0402-0201)'                 | '330'     | '1%'    | '1/16W'  | 'DISCRETE' | 'RES CHIP 330 1/16W +-1%(0402)EF'                  | 'CHIP0402'     | ''          | ''            | '20180212'
 '330'        | '1%'      | '1/16W'  | '0402LF'  | 'EMPTY'  | 'CS13302FB00'(!)        = 'End of Design' | 'Comp-Approve'     | 'CS13302FB00'           | 'R0402'             | '(R0402-0201)'                 | '330'     | '1%'    | '1/16W'  | 'IO'       | 'RES CHIP 330 1/16W +-1%(0402)EF'                  | 'CHIP0402'     | ''          | ''            | '20180212'
 '2.2K'       | '5%'      | '1/16W'  | '0402LF'  | 'CHIP'   | 'CS22202JB07'(!)        = 'End of Design' | 'Comp-Approve'     | 'CS22202JB07'           | 'R0402'             | '(R0402-0201)'                 | '2.2K'    | '5%'    | '1/16W'  | 'DISCRETE' | 'RES CHIP 2.2K 1/16W +-5%(0402)EF'                 | 'CHIP0402'     | ''          | ''            | '20180212'
 '2.2K'       | '5%'      | '1/16W'  | '0402LF'  | 'EMPTY'  | 'CS22202JB07'(!)        = 'End of Design' | 'Comp-Approve'     | 'CS22202JB07'           | 'R0402'             | '(R0402-0201)'                 | '2.2K'    | '5%'    | '1/16W'  | 'IO'       | 'RES CHIP 2.2K 1/16W +-5%(0402)EF'                 | 'CHIP0402'     | ''          | ''            | '20180212'
 '2.7K'       | '5%'      | '1/16W'  | '0402LF'  | 'CHIP'   | 'CS22702JB04'(!)        = 'End of Design' | 'Comp-Approve'     | 'CS22702JB04'           | 'R0402'             | '(R0402-0201)'                 | '2.7K'    | '5%'    | '1/16W'  | 'DISCRETE' | 'RES CHIP 2.7K 1/16W +-5%(0402)EF'                 | 'CHIP0402'     | ''          | ''            | '20180212'
 '2.7K'       | '5%'      | '1/16W'  | '0402LF'  | 'EMPTY'  | 'CS22702JB04'(!)        = 'End of Design' | 'Comp-Approve'     | 'CS22702JB04'           | 'R0402'             | '(R0402-0201)'                 | '2.7K'    | '5%'    | '1/16W'  | 'IO'       | 'RES CHIP 2.7K 1/16W +-5%(0402)EF'                 | 'CHIP0402'     | ''          | ''            | '20180212'
 '4.53K'      | '1%'      | '1/16W'  | '0402LF'  | 'CHIP'   | 'CS24532FB03'(!)        = 'End of Design' | 'Comp-Approve'     | 'CS24532FB03'           | 'R0402'             | '(R0402-0201)'                 | '4.53K'   | '1%'    | '1/16W'  | 'DISCRETE' | 'RES CHIP 4.53K 1/16W +-1%(0402)EF'                | 'CHIP0402'     | ''          | ''            | '20180212'
 '4.53K'      | '1%'      | '1/16W'  | '0402LF'  | 'EMPTY'  | 'CS24532FB03'(!)        = 'End of Design' | 'Comp-Approve'     | 'CS24532FB03'           | 'R0402'             | '(R0402-0201)'                 | '4.53K'   | '1%'    | '1/16W'  | 'IO'       | 'RES CHIP 4.53K 1/16W +-1%(0402)EF'                | 'CHIP0402'     | ''          | ''            | '20180212'
 '8.2K'       | '5%'      | '1/16W'  | '0402LF'  | 'CHIP'   | 'CS28202JB05'(!)        = 'End of Design' | 'Comp-Approve'     | 'CS28202JB05'           | 'R0402'             | '(R0402-0201)'                 | '8.2K'    | '5%'    | '1/16W'  | 'DISCRETE' | 'RES CHIP 8.2K 1/16W +-5% (0402) EF'               | 'CHIP0402'     | ''          | ''            | '20180212'
 '8.2K'       | '5%'      | '1/16W'  | '0402LF'  | 'EMPTY'  | 'CS28202JB05'(!)        = 'End of Design' | 'Comp-Approve'     | 'CS28202JB05'           | 'R0402'             | '(R0402-0201)'                 | '8.2K'    | '5%'    | '1/16W'  | 'IO'       | 'RES CHIP 8.2K 1/16W +-5% (0402) EF'               | 'CHIP0402'     | ''          | ''            | '20180212'
 '9.76K'      | '1%'      | '1/16W'  | '0402LF'  | 'CHIP'   | 'CS29762FB05'(!)        = 'End of Design' | 'Comp-Approve'     | 'CS29762FB05'           | 'R0402'             | '(R0402-0201)'                 | '9.76K'   | '1%'    | '1/16W'  | 'DISCRETE' | 'RES CHIP 9.76K 1/16W +-1%(0402)EF'                | 'CHIP0402'     | ''          | ''            | '20180212'
 '9.76K'      | '1%'      | '1/16W'  | '0402LF'  | 'EMPTY'  | 'CS29762FB05'(!)        = 'End of Design' | 'Comp-Approve'     | 'CS29762FB05'           | 'R0402'             | '(R0402-0201)'                 | '9.76K'   | '1%'    | '1/16W'  | 'IO'       | 'RES CHIP 9.76K 1/16W +-1%(0402)EF'                | 'CHIP0402'     | ''          | ''            | '20180212'
 '11.3K'      | '1%'      | '1/16W'  | '0402LF'  | 'CHIP'   | 'CS31132FB01'(!)        = 'End of Design' | 'Comp-Approve'     | 'CS31132FB01'           | 'R0402'             | '(R0402-0201)'                 | '11.3K'   | '1%'    | '1/16W'  | 'DISCRETE' | 'RES CHIP 11.3K 1/16W +-1%(0402)EF'                | 'CHIP0402'     | ''          | ''            | '20180212'
 '11.3K'      | '1%'      | '1/16W'  | '0402LF'  | 'EMPTY'  | 'CS31132FB01'(!)        = 'End of Design' | 'Comp-Approve'     | 'CS31132FB01'           | 'R0402'             | '(R0402-0201)'                 | '11.3K'   | '1%'    | '1/16W'  | 'IO'       | 'RES CHIP 11.3K 1/16W +-1%(0402)EF'                | 'CHIP0402'     | ''          | ''            | '20180212'
 '28K'        | '1%'      | '1/16W'  | '0402LF'  | 'CHIP'   | 'CS32802FB05'(!)        = 'End of Design' | 'Comp-Approve'     | 'CS32802FB05'           | 'R0402'             | '(R0402-0201)'                 | '28K'     | '1%'    | '1/16W'  | 'DISCRETE' | 'RES CHIP 28K 1/16W +-1%(0402)EF'                  | 'CHIP0402'     | ''          | ''            | '20180212'
 '28K'        | '1%'      | '1/16W'  | '0402LF'  | 'EMPTY'  | 'CS32802FB05'(!)        = 'End of Design' | 'Comp-Approve'     | 'CS32802FB05'           | 'R0402'             | '(R0402-0201)'                 | '28K'     | '1%'    | '1/16W'  | 'IO'       | 'RES CHIP 28K 1/16W +-1%(0402)EF'                  | 'CHIP0402'     | ''          | ''            | '20180212'
 '49.9K'      | '1%'      | '1/16W'  | '0402LF'  | 'CHIP'   | 'CS34992FB05'(!)        = 'End of Design' | 'Comp-Approve'     | 'CS34992FB05'           | 'R0402'             | '(R0402-0201)'                 | '49.9K'   | '1%'    | '1/16W'  | 'DISCRETE' | 'RES CHIP 49.9K 1/16W +-1%(0402)EF'                | 'CHIP0402'     | ''          | ''            | '20180212'
 '49.9K'      | '1%'      | '1/16W'  | '0402LF'  | 'EMPTY'  | 'CS34992FB05'(!)        = 'End of Design' | 'Comp-Approve'     | 'CS34992FB05'           | 'R0402'             | '(R0402-0201)'                 | '49.9K'   | '1%'    | '1/16W'  | 'IO'       | 'RES CHIP 49.9K 1/16W +-1%(0402)EF'                | 'CHIP0402'     | ''          | ''            | '20180212'
 '51K'        | '1%'      | '1/16W'  | '0402LF'  | 'CHIP'   | 'CS35102FB00'(!)        = 'End of Design' | 'Comp-Approve'     | 'CS35102FB00'           | 'R0402'             | '(R0402-0201)'                 | '51K'     | '1%'    | '1/16W'  | 'DISCRETE' | 'RES CHIP 51K 1/16W +-1%(0402)EF'                  | 'CHIP0402'     | ''          | ''            | '20180212'
 '51K'        | '1%'      | '1/16W'  | '0402LF'  | 'EMPTY'  | 'CS35102FB00'(!)        = 'End of Design' | 'Comp-Approve'     | 'CS35102FB00'           | 'R0402'             | '(R0402-0201)'                 | '51K'     | '1%'    | '1/16W'  | 'IO'       | 'RES CHIP 51K 1/16W +-1%(0402)EF'                  | 'CHIP0402'     | ''          | ''            | '20180212'
 '60.4K'      | '1%'      | '1/16W'  | '0402LF'  | 'CHIP'   | 'CS36042FB04'(!)        = 'End of Design' | 'Comp-Approve'     | 'CS36042FB04'           | 'R0402'             | '(R0402-0201)'                 | '60.4K'   | '1%'    | '1/16W'  | 'DISCRETE' | 'RES CHIP 60.4K 1/16W +-1%(0402)EF'                | 'CHIP0402'     | ''          | ''            | '20180212'
 '60.4K'      | '1%'      | '1/16W'  | '0402LF'  | 'EMPTY'  | 'CS36042FB04'(!)        = 'End of Design' | 'Comp-Approve'     | 'CS36042FB04'           | 'R0402'             | '(R0402-0201)'                 | '60.4K'   | '1%'    | '1/16W'  | 'IO'       | 'RES CHIP 60.4K 1/16W +-1%(0402)EF'                | 'CHIP0402'     | ''          | ''            | '20180212'
 '63.4K'      | '1%'      | '1/16W'  | '0402LF'  | 'CHIP'   | 'CS36342FB04'(!)        = 'End of Design' | 'Comp-Approve'     | 'CS36342FB04'           | 'R0402'             | '(R0402-0201)'                 | '63.4K'   | '1%'    | '1/16W'  | 'DISCRETE' | 'RES CHIP 63.4K 1/16W +-1%(0402)EF'                | 'CHIP0402'     | ''          | ''            | '20180212'
 '63.4K'      | '1%'      | '1/16W'  | '0402LF'  | 'EMPTY'  | 'CS36342FB04'(!)        = 'End of Design' | 'Comp-Approve'     | 'CS36342FB04'           | 'R0402'             | '(R0402-0201)'                 | '63.4K'   | '1%'    | '1/16W'  | 'IO'       | 'RES CHIP 63.4K 1/16W +-1%(0402)EF'                | 'CHIP0402'     | ''          | ''            | '20180212'
 '80.6K'      | '1%'      | '1/16W'  | '0402LF'  | 'CHIP'   | 'CS38062FB04'(!)        = 'End of Design' | 'Comp-Approve'     | 'CS38062FB04'           | 'R0402'             | '(R0402-0201)'                 | '80.6K'   | '1%'    | '1/16W'  | 'DISCRETE' | 'RES CHIP 80.6K 1/16W +-1%(0402)EF'                | 'CHIP0402'     | ''          | ''            | '20180212'
 '80.6K'      | '1%'      | '1/16W'  | '0402LF'  | 'EMPTY'  | 'CS38062FB04'(!)        = 'End of Design' | 'Comp-Approve'     | 'CS38062FB04'           | 'R0402'             | '(R0402-0201)'                 | '80.6K'   | '1%'    | '1/16W'  | 'IO'       | 'RES CHIP 80.6K 1/16W +-1%(0402)EF'                | 'CHIP0402'     | ''          | ''            | '20180212'
 '100K'       | '5%'      | '1/20W'  | '0201LF'  | 'CHIP'   | 'CS41001JE05'(!)        = 'End of Design' | 'Comp-Approve'     | 'CS41001JE05'           | 'R0201'             | '(SMR0201AW)'                  | '100K'    | '5%'    | '1/20W'  | 'DISCRETE' | 'RES CHIP 100K 1/20W +-5%(0201)EF'                 | 'CHIP0201'     | ''          | ''            | '20180212'
 '100K'       | '5%'      | '1/20W'  | '0201LF'  | 'EMPTY'  | 'CS41001JE05'(!)        = 'End of Design' | 'Comp-Approve'     | 'CS41001JE05'           | 'R0201'             | '(SMR0201AW)'                  | '100K'    | '5%'    | '1/20W'  | 'IO'       | 'RES CHIP 100K 1/20W +-5%(0201)EF'                 | 'CHIP0201'     | ''          | ''            | '20180212'
 '100K'       | '5%'      | '1/16W'  | '0402LF'  | 'CHIP'   | 'CS41002JB06'(!)        = 'End of Design' | 'Comp-Approve'     | 'CS41002JB06'           | 'R0402'             | '(R0402-0201)'                 | '100K'    | '5%'    | '1/16W'  | 'DISCRETE' | 'RES CHIP 100K 1/16W +-5%(0402)EF'                 | 'CHIP0402'     | ''          | ''            | '20180212'
 '100K'       | '5%'      | '1/16W'  | '0402LF'  | 'EMPTY'  | 'CS41002JB06'(!)        = 'End of Design' | 'Comp-Approve'     | 'CS41002JB06'           | 'R0402'             | '(R0402-0201)'                 | '100K'    | '5%'    | '1/16W'  | 'IO'       | 'RES CHIP 100K 1/16W +-5%(0402)EF'                 | 'CHIP0402'     | ''          | ''            | '20180212'
 '180K'       | '1%'      | '1/16W'  | '0402LF'  | 'CHIP'   | 'CS41802FB03'(!)        = 'End of Design' | 'Comp-Approve'     | 'CS41802FB03'           | 'R0402'             | '(R0402-0201)'                 | '180K'    | '1%'    | '1/16W'  | 'DISCRETE' | 'RES CHIP 180K 1/16W +-1%(0402)EF'                 | 'CHIP0402'     | ''          | ''            | '20180212'
 '180K'       | '1%'      | '1/16W'  | '0402LF'  | 'EMPTY'  | 'CS41802FB03'(!)        = 'End of Design' | 'Comp-Approve'     | 'CS41802FB03'           | 'R0402'             | '(R0402-0201)'                 | '180K'    | '1%'    | '1/16W'  | 'IO'       | 'RES CHIP 180K 1/16W +-1%(0402)EF'                 | 'CHIP0402'     | ''          | ''            | '20180212'
 '22'         | '1%'      | '1/16W'  | '0402LF'  | 'CHIP'   | 'CS02202FB02'(!)        = 'End of Design' | 'Comp-Approve'     | 'CS02202FB02'           | 'R0402'             | '(R0402-0201)'                 | '22'      | '1%'    | '1/16W'  | 'DISCRETE' | 'RES CHIP 22 1/16W +-1%(0402)EF'                   | 'CHIP0402'     | ''          | ''            | '20180212'
 '22'         | '1%'      | '1/16W'  | '0402LF'  | 'EMPTY'  | 'CS02202FB02'(!)        = 'End of Design' | 'Comp-Approve'     | 'CS02202FB02'           | 'R0402'             | '(R0402-0201)'                 | '22'      | '1%'    | '1/16W'  | 'IO'       | 'RES CHIP 22 1/16W +-1%(0402)EF'                   | 'CHIP0402'     | ''          | ''            | '20180212'
 '42.2'       | '1%'      | '1/16W'  | '0402LF'  | 'CHIP'   | 'CS04222FB05'(!)        = 'End of Design' | 'Comp-Approve'     | 'CS04222FB05'           | 'R0402'             | '(R0402-0201)'                 | '42.2'    | '1%'    | '1/16W'  | 'DISCRETE' | 'RES CHIP 42.2 1/16W +-1%(0402)EF'                 | 'CHIP0402'     | ''          | ''            | '20180212'
 '42.2'       | '1%'      | '1/16W'  | '0402LF'  | 'EMPTY'  | 'CS04222FB05'(!)        = 'End of Design' | 'Comp-Approve'     | 'CS04222FB05'           | 'R0402'             | '(R0402-0201)'                 | '42.2'    | '1%'    | '1/16W'  | 'IO'       | 'RES CHIP 42.2 1/16W +-1%(0402)EF'                 | 'CHIP0402'     | ''          | ''            | '20180212'
 '10K'        | '0.1%'    | '1/16W'  | '0402LF'  | 'CHIP'   | 'CS31002BB06'(!)        = 'End of Design' | 'Comp-Approve'     | 'CS31002BB06'           | 'R0402'             | '(R0402-0201)'                 | '10K'     | '0.1%'  | '1/16W'  | 'DISCRETE' | 'RES CHIP 10K 1/16W +-0.1%(0402)EF'                | 'CHIP0402'     | ''          | ''            | '20180212'
 '10K'        | '0.1%'    | '1/16W'  | '0402LF'  | 'EMPTY'  | 'CS31002BB06'(!)        = 'End of Design' | 'Comp-Approve'     | 'CS31002BB06'           | 'R0402'             | '(R0402-0201)'                 | '10K'     | '0.1%'  | '1/16W'  | 'IO'       | 'RES CHIP 10K 1/16W +-0.1%(0402)EF'                | 'CHIP0402'     | ''          | ''            | '20180212'
 '75K'        | '1%'      | '1/16W'  | '0402LF'  | 'CHIP'   | 'CS37502FB05'(!)        = 'End of Design' | 'Comp-Approve'     | 'CS37502FB05'           | 'R0402'             | '(R0402-0201)'                 | '75K'     | '1%'    | '1/16W'  | 'DISCRETE' | 'RES CHIP 75K 1/16W +-1%(0402)EF'                  | 'CHIP0402'     | ''          | ''            | '20180212'
 '75K'        | '1%'      | '1/16W'  | '0402LF'  | 'EMPTY'  | 'CS37502FB05'(!)        = 'End of Design' | 'Comp-Approve'     | 'CS37502FB05'           | 'R0402'             | '(R0402-0201)'                 | '75K'     | '1%'    | '1/16W'  | 'IO'       | 'RES CHIP 75K 1/16W +-1%(0402)EF'                  | 'CHIP0402'     | ''          | ''            | '20180212'
 '390K'       | '5%'      | '1/16W'  | '0402LF'  | 'CHIP'   | 'CS43902JB04'(!)        = 'End of Design' | 'Comp-Approve'     | 'CS43902JB04'           | 'R0402'             | '(R0402-0201)'                 | '390K'    | '5%'    | '1/16W'  | 'DISCRETE' | 'RES CHIP 390K 1/16W +-5%(0402)EF'                 | 'CHIP0402'     | ''          | ''            | '20180212'
 '390K'       | '5%'      | '1/16W'  | '0402LF'  | 'EMPTY'  | 'CS43902JB04'(!)        = 'End of Design' | 'Comp-Approve'     | 'CS43902JB04'           | 'R0402'             | '(R0402-0201)'                 | '390K'    | '5%'    | '1/16W'  | 'IO'       | 'RES CHIP 390K 1/16W +-5%(0402)EF'                 | 'CHIP0402'     | ''          | ''            | '20180212'
 '1M'         | '1%'      | '1/10W'  | '0603LF'  | 'CHIP'   | 'CS51003F903'(!)        = 'End of Design' | 'Comp-Approve'     | 'CS51003F903'           | 'R0603'             | '(SMR0603AW)'                  | '1M'      | '1%'    | '1/10W'  | 'DISCRETE' | 'RES CHIP 1M 1/10W +-1%(0603)EF'                   | 'CHIP0603'     | ''          | ''            | '20180212'
 '1M'         | '1%'      | '1/10W'  | '0603LF'  | 'EMPTY'  | 'CS51003F903'(!)        = 'End of Design' | 'Comp-Approve'     | 'CS51003F903'           | 'R0603'             | '(SMR0603AW)'                  | '1M'      | '1%'    | '1/10W'  | 'IO'       | 'RES CHIP 1M 1/10W +-1%(0603)EF'                   | 'CHIP0603'     | ''          | ''            | '20180212'
 '0'          | '5%'      | '1/16W'  | '0402LF'  | 'CHIP'   | 'CS00002JB13'(!)        = 'End of Design' | 'Comp-Approve'     | 'CS00002JB13'           | 'R0402'             | '(R0402-0201)'                 | '0'       | '5%'    | '1/16W'  | 'DISCRETE' | 'RES CHIP 0 1/16W +-5%(0402)EF'                    | 'CHIPR0402'    | ''          | ''            | '20180208'
 '0'          | '5%'      | '1/16W'  | '0402LF'  | 'EMPTY'  | 'CS00002JB13'(!)        = 'End of Design' | 'Comp-Approve'     | 'CS00002JB13'           | 'R0402'             | '(R0402-0201)'                 | '0'       | '5%'    | '1/16W'  | 'IO'       | 'RES CHIP 0 1/16W +-5%(0402)EF'                    | 'CHIPR0402'    | ''          | ''            | '20180208'
 '10'         | '1%'      | '1/16W'  | '0402LF'  | 'CHIP'   | 'CS01002FB07'(!)        = 'End of Design' | 'Comp-Approve'     | 'CS01002FB07'           | 'R0402'             | '(R0402-0201)'                 | '10'      | '1%'    | '1/16W'  | 'DISCRETE' | 'RES CHIP 10 1/16W +-1%(0402)EF'                   | 'CHIPR0402'    | ''          | ''            | '20180208'
 '10'         | '1%'      | '1/16W'  | '0402LF'  | 'EMPTY'  | 'CS01002FB07'(!)        = 'End of Design' | 'Comp-Approve'     | 'CS01002FB07'           | 'R0402'             | '(R0402-0201)'                 | '10'      | '1%'    | '1/16W'  | 'IO'       | 'RES CHIP 10 1/16W +-1%(0402)EF'                   | 'CHIPR0402'    | ''          | ''            | '20180208'
 '33.2'       | '1%'      | '1/16W'  | '0402LF'  | 'CHIP'   | 'CS03322FB03'(!)        = 'End of Design' | 'Comp-Approve'     | 'CS03322FB03'           | 'R0402'             | '(R0402-0201)'                 | '33.2'    | '1%'    | '1/16W'  | 'DISCRETE' | 'RES CHIP 33.2 1/16W +-1%(0402)EF'                 | 'CHIPR0402'    | ''          | ''            | '20180208'
 '33.2'       | '1%'      | '1/16W'  | '0402LF'  | 'EMPTY'  | 'CS03322FB03'(!)        = 'End of Design' | 'Comp-Approve'     | 'CS03322FB03'           | 'R0402'             | '(R0402-0201)'                 | '33.2'    | '1%'    | '1/16W'  | 'IO'       | 'RES CHIP 33.2 1/16W +-1%(0402)EF'                 | 'CHIPR0402'    | ''          | ''            | '20180208'
 '49.9'       | '1%'      | '1/16W'  | '0402LF'  | 'CHIP'   | 'CS04992FB07'(!)        = 'End of Design' | 'Comp-Approve'     | 'CS04992FB07'           | 'R0402'             | '(R0402-0201)'                 | '49.9'    | '1%'    | '1/16W'  | 'DISCRETE' | 'RES CHIP 49.9 1/16W +-1%(0402)EF'                 | 'CHIPR0402'    | ''          | ''            | '20180208'
 '49.9'       | '1%'      | '1/16W'  | '0402LF'  | 'EMPTY'  | 'CS04992FB07'(!)        = 'End of Design' | 'Comp-Approve'     | 'CS04992FB07'           | 'R0402'             | '(R0402-0201)'                 | '49.9'    | '1%'    | '1/16W'  | 'IO'       | 'RES CHIP 49.9 1/16W +-1%(0402)EF'                 | 'CHIPR0402'    | ''          | ''            | '20180208'
 '100'        | '1%'      | '1/16W'  | '0402LF'  | 'CHIP'   | 'CS11002FB07'(!)        = 'End of Design' | 'Comp-Approve'     | 'CS11002FB07'           | 'R0402'             | '(R0402-0201)'                 | '100'     | '1%'    | '1/16W'  | 'DISCRETE' | 'RES CHIP 100 1/16W +-1%(0402)EF'                  | 'CHIPR0402'    | ''          | ''            | '20180208'
 '100'        | '1%'      | '1/16W'  | '0402LF'  | 'EMPTY'  | 'CS11002FB07'(!)        = 'End of Design' | 'Comp-Approve'     | 'CS11002FB07'           | 'R0402'             | '(R0402-0201)'                 | '100'     | '1%'    | '1/16W'  | 'IO'       | 'RES CHIP 100 1/16W +-1%(0402)EF'                  | 'CHIPR0402'    | ''          | ''            | '20180208'
 '150'        | '1%'      | '1/16W'  | '0402LF'  | 'CHIP'   | 'CS11502FB07'(!)        = 'End of Design' | 'Comp-Approve'     | 'CS11502FB07'           | 'R0402'             | '(R0402-0201)'                 | '150'     | '1%'    | '1/16W'  | 'DISCRETE' | 'RES CHIP 150 1/16W +-1%(0402)EF'                  | 'CHIPR0402'    | ''          | ''            | '20180208'
 '150'        | '1%'      | '1/16W'  | '0402LF'  | 'EMPTY'  | 'CS11502FB07'(!)        = 'End of Design' | 'Comp-Approve'     | 'CS11502FB07'           | 'R0402'             | '(R0402-0201)'                 | '150'     | '1%'    | '1/16W'  | 'IO'       | 'RES CHIP 150 1/16W +-1%(0402)EF'                  | 'CHIPR0402'    | ''          | ''            | '20180208'
 '200'        | '1%'      | '1/16W'  | '0402LF'  | 'CHIP'   | 'CS12002FB06'(!)        = 'End of Design' | 'Comp-Approve'     | 'CS12002FB06'           | 'R0402'             | '(R0402-0201)'                 | '200'     | '1%'    | '1/16W'  | 'DISCRETE' | 'RES CHIP 200 1/16W +-1%(0402)EF'                  | 'CHIPR0402'    | ''          | ''            | '20180208'
 '200'        | '1%'      | '1/16W'  | '0402LF'  | 'EMPTY'  | 'CS12002FB06'(!)        = 'End of Design' | 'Comp-Approve'     | 'CS12002FB06'           | 'R0402'             | '(R0402-0201)'                 | '200'     | '1%'    | '1/16W'  | 'IO'       | 'RES CHIP 200 1/16W +-1%(0402)EF'                  | 'CHIPR0402'    | ''          | ''            | '20180208'
 '412'        | '1%'      | '1/16W'  | '0402LF'  | 'CHIP'   | 'CS14122FB04'(!)        = 'End of Design' | 'Comp-Approve'     | 'CS14122FB04'           | 'R0402'             | '(R0402-0201)'                 | '412'     | '1%'    | '1/16W'  | 'DISCRETE' | 'RES CHIP 412 1/16W +-1%(0402)EF'                  | 'CHIPR0402'    | ''          | ''            | '20180208'
 '412'        | '1%'      | '1/16W'  | '0402LF'  | 'EMPTY'  | 'CS14122FB04'(!)        = 'End of Design' | 'Comp-Approve'     | 'CS14122FB04'           | 'R0402'             | '(R0402-0201)'                 | '412'     | '1%'    | '1/16W'  | 'IO'       | 'RES CHIP 412 1/16W +-1%(0402)EF'                  | 'CHIPR0402'    | ''          | ''            | '20180208'
 '1K'         | '1%'      | '1/16W'  | '0402LF'  | 'CHIP'   | 'CS21002FB06'(!)        = 'End of Design' | 'Comp-Approve'     | 'CS21002FB06'           | 'R0402'             | '(R0402-0201)'                 | '1K'      | '1%'    | '1/16W'  | 'DISCRETE' | 'RES CHIP 1K 1/16W +-1%(0402)EF'                   | 'CHIPR0402'    | ''          | ''            | '20180208'
 '1K'         | '1%'      | '1/16W'  | '0402LF'  | 'EMPTY'  | 'CS21002FB06'(!)        = 'End of Design' | 'Comp-Approve'     | 'CS21002FB06'           | 'R0402'             | '(R0402-0201)'                 | '1K'      | '1%'    | '1/16W'  | 'IO'       | 'RES CHIP 1K 1/16W +-1%(0402)EF'                   | 'CHIPR0402'    | ''          | ''            | '20180208'
 '1.02K'      | '1%'      | '1/16W'  | '0402LF'  | 'CHIP'   | 'CS21022FB03'(!)        = 'End of Design' | 'Comp-Approve'     | 'CS21022FB03'           | 'R0402'             | '(R0402-0201)'                 | '1.02K'   | '1%'    | '1/16W'  | 'DISCRETE' | 'RES CHIP 1.02K 1/16W +-1%(0402)EF'                | 'CHIPR0402'    | ''          | ''            | '20180208'
 '1.02K'      | '1%'      | '1/16W'  | '0402LF'  | 'EMPTY'  | 'CS21022FB03'(!)        = 'End of Design' | 'Comp-Approve'     | 'CS21022FB03'           | 'R0402'             | '(R0402-0201)'                 | '1.02K'   | '1%'    | '1/16W'  | 'IO'       | 'RES CHIP 1.02K 1/16W +-1%(0402)EF'                | 'CHIPR0402'    | ''          | ''            | '20180208'
 '1.5K'       | '1%'      | '1/16W'  | '0402LF'  | 'CHIP'   | 'CS21502FB07'(!)        = 'End of Design' | 'Comp-Approve'     | 'CS21502FB07'           | 'R0402'             | '(R0402-0201)'                 | '1.5K'    | '1%'    | '1/16W'  | 'DISCRETE' | 'RES CHIP 1.5K 1/16W +-1%(0402)EF'                 | 'CHIPR0402'    | ''          | ''            | '20180208'
 '1.5K'       | '1%'      | '1/16W'  | '0402LF'  | 'EMPTY'  | 'CS21502FB07'(!)        = 'End of Design' | 'Comp-Approve'     | 'CS21502FB07'           | 'R0402'             | '(R0402-0201)'                 | '1.5K'    | '1%'    | '1/16W'  | 'IO'       | 'RES CHIP 1.5K 1/16W +-1%(0402)EF'                 | 'CHIPR0402'    | ''          | ''            | '20180208'
 '4.7K'       | '1%'      | '1/16W'  | '0402LF'  | 'CHIP'   | 'CS24702FB06'(!)        = 'End of Design' | 'Comp-Approve'     | 'CS24702FB06'           | 'R0402'             | '(R0402-0201)'                 | '4.7K'    | '1%'    | '1/16W'  | 'DISCRETE' | 'RES CHIP 4.7K 1/16W +-1%(0402)EF'                 | 'CHIPR0402'    | ''          | ''            | '20180208'
 '4.7K'       | '1%'      | '1/16W'  | '0402LF'  | 'EMPTY'  | 'CS24702FB06'(!)        = 'End of Design' | 'Comp-Approve'     | 'CS24702FB06'           | 'R0402'             | '(R0402-0201)'                 | '4.7K'    | '1%'    | '1/16W'  | 'IO'       | 'RES CHIP 4.7K 1/16W +-1%(0402)EF'                 | 'CHIPR0402'    | ''          | ''            | '20180208'
 '5.9K'       | '1%'      | '1/16W'  | '0402LF'  | 'CHIP'   | 'CS25902FB04'(!)        = 'End of Design' | 'Comp-Approve'     | 'CS25902FB04'           | 'R0402'             | '(R0402-0201)'                 | '5.9K'    | '1%'    | '1/16W'  | 'DISCRETE' | 'RES CHIP 5.9K 1/16W +-1%(0402)EF'                 | 'CHIPR0402'    | ''          | ''            | '20180208'
 '5.9K'       | '1%'      | '1/16W'  | '0402LF'  | 'EMPTY'  | 'CS25902FB04'(!)        = 'End of Design' | 'Comp-Approve'     | 'CS25902FB04'           | 'R0402'             | '(R0402-0201)'                 | '5.9K'    | '1%'    | '1/16W'  | 'IO'       | 'RES CHIP 5.9K 1/16W +-1%(0402)EF'                 | 'CHIPR0402'    | ''          | ''            | '20180208'
 '7.5K'       | '1%'      | '1/16W'  | '0402LF'  | 'CHIP'   | 'CS27502FB04'(!)        = 'End of Design' | 'Comp-Approve'     | 'CS27502FB04'           | 'R0402'             | '(R0402-0201)'                 | '7.5K'    | '1%'    | '1/16W'  | 'DISCRETE' | 'RES CHIP 7.5K 1/16W +-1%(0402)EF'                 | 'CHIPR0402'    | ''          | ''            | '20180208'
 '7.5K'       | '1%'      | '1/16W'  | '0402LF'  | 'EMPTY'  | 'CS27502FB04'(!)        = 'End of Design' | 'Comp-Approve'     | 'CS27502FB04'           | 'R0402'             | '(R0402-0201)'                 | '7.5K'    | '1%'    | '1/16W'  | 'IO'       | 'RES CHIP 7.5K 1/16W +-1%(0402)EF'                 | 'CHIPR0402'    | ''          | ''            | '20180208'
 '10K'        | '1%'      | '1/16W'  | '0402LF'  | 'CHIP'   | 'CS31002FB08'(!)        = 'End of Design' | 'Comp-Approve'     | 'CS31002FB08'           | 'R0402'             | '(R0402-0201)'                 | '10K'     | '1%'    | '1/16W'  | 'DISCRETE' | 'RES CHIP 10K 1/16W +-1%(0402)EF'                  | 'CHIPR0402'    | ''          | ''            | '20180208'
 '10K'        | '1%'      | '1/16W'  | '0402LF'  | 'EMPTY'  | 'CS31002FB08'(!)        = 'End of Design' | 'Comp-Approve'     | 'CS31002FB08'           | 'R0402'             | '(R0402-0201)'                 | '10K'     | '1%'    | '1/16W'  | 'IO'       | 'RES CHIP 10K 1/16W +-1%(0402)EF'                  | 'CHIPR0402'    | ''          | ''            | '20180208'
 '10K'        | '5%'      | '1/16W'  | '0402LF'  | 'CHIP'   | 'CS31002JB08'(!)        = 'End of Design' | 'Comp-Approve'     | 'CS31002JB08'           | 'R0402'             | '(R0402-0201)'                 | '10K'     | '5%'    | '1/16W'  | 'DISCRETE' | 'RES CHIP 10K 1/16W +-5%(0402)EF'                  | 'CHIPR0402'    | ''          | ''            | '20180208'
 '10K'        | '5%'      | '1/16W'  | '0402LF'  | 'EMPTY'  | 'CS31002JB08'(!)        = 'End of Design' | 'Comp-Approve'     | 'CS31002JB08'           | 'R0402'             | '(R0402-0201)'                 | '10K'     | '5%'    | '1/16W'  | 'IO'       | 'RES CHIP 10K 1/16W +-5%(0402)EF'                  | 'CHIPR0402'    | ''          | ''            | '20180208'
 '20K'        | '1%'      | '1/16W'  | '0402LF'  | 'CHIP'   | 'CS32002FB06'(!)        = 'End of Design' | 'Comp-Approve'     | 'CS32002FB06'           | 'R0402'             | '(R0402-0201)'                 | '20K'     | '1%'    | '1/16W'  | 'DISCRETE' | 'RES CHIP 20K 1/16W +-1%(0402)EF'                  | 'CHIPR0402'    | ''          | ''            | '20180208'
 '20K'        | '1%'      | '1/16W'  | '0402LF'  | 'EMPTY'  | 'CS32002FB06'(!)        = 'End of Design' | 'Comp-Approve'     | 'CS32002FB06'           | 'R0402'             | '(R0402-0201)'                 | '20K'     | '1%'    | '1/16W'  | 'IO'       | 'RES CHIP 20K 1/16W +-1%(0402)EF'                  | 'CHIPR0402'    | ''          | ''            | '20180208'
 '22.1K'      | '1%'      | '1/16W'  | '0402LF'  | 'CHIP'   | 'CS32212FB02'(!)        = 'End of Design' | 'Comp-Approve'     | 'CS32212FB02'           | 'R0402'             | '(R0402-0201)'                 | '22.1K'   | '1%'    | '1/16W'  | 'DISCRETE' | 'RES CHIP 22.1K 1/16W +-1%(0402)EF'                | 'CHIPR0402'    | ''          | ''            | '20180208'
 '22.1K'      | '1%'      | '1/16W'  | '0402LF'  | 'EMPTY'  | 'CS32212FB02'(!)        = 'End of Design' | 'Comp-Approve'     | 'CS32212FB02'           | 'R0402'             | '(R0402-0201)'                 | '22.1K'   | '1%'    | '1/16W'  | 'IO'       | 'RES CHIP 22.1K 1/16W +-1%(0402)EF'                | 'CHIPR0402'    | ''          | ''            | '20180208'
 '47K'        | '1%'      | '1/16W'  | '0402LF'  | 'CHIP'   | 'CS34702FB01'(!)        = 'End of Design' | 'Comp-Approve'     | 'CS34702FB01'           | 'R0402'             | '(R0402-0201)'                 | '47K'     | '1%'    | '1/16W'  | 'DISCRETE' | 'RES CHIP 47K 1/16W +-1%(0402)EF'                  | 'CHIPR0402'    | ''          | ''            | '20180208'
 '47K'        | '1%'      | '1/16W'  | '0402LF'  | 'EMPTY'  | 'CS34702FB01'(!)        = 'End of Design' | 'Comp-Approve'     | 'CS34702FB01'           | 'R0402'             | '(R0402-0201)'                 | '47K'     | '1%'    | '1/16W'  | 'IO'       | 'RES CHIP 47K 1/16W +-1%(0402)EF'                  | 'CHIPR0402'    | ''          | ''            | '20180208'
 '52.3K'      | '1%'      | '1/16W'  | '0402LF'  | 'CHIP'   | 'CS35232FB02'(!)        = 'End of Design' | 'Comp-Approve'     | 'CS35232FB02'           | 'R0402'             | '(R0402-0201)'                 | '52.3K'   | '1%'    | '1/16W'  | 'DISCRETE' | 'RES CHIP 52.3K 1/16W +-1%(0402)EF'                | 'CHIPR0402'    | ''          | ''            | '20180208'
 '52.3K'      | '1%'      | '1/16W'  | '0402LF'  | 'EMPTY'  | 'CS35232FB02'(!)        = 'End of Design' | 'Comp-Approve'     | 'CS35232FB02'           | 'R0402'             | '(R0402-0201)'                 | '52.3K'   | '1%'    | '1/16W'  | 'IO'       | 'RES CHIP 52.3K 1/16W +-1%(0402)EF'                | 'CHIPR0402'    | ''          | ''            | '20180208'
 '97.6K'      | '1%'      | '1/16W'  | '0402LF'  | 'CHIP'   | 'CS39762FB02'(!)        = 'End of Design' | 'Comp-Approve'     | 'CS39762FB02'           | 'R0402'             | '(R0402-0201)'                 | '97.6K'   | '1%'    | '1/16W'  | 'DISCRETE' | 'RES CHIP 97.6K 1/16W +-1%(0402)EF'                | 'CHIPR0402'    | ''          | ''            | '20180208'
 '97.6K'      | '1%'      | '1/16W'  | '0402LF'  | 'EMPTY'  | 'CS39762FB02'(!)        = 'End of Design' | 'Comp-Approve'     | 'CS39762FB02'           | 'R0402'             | '(R0402-0201)'                 | '97.6K'   | '1%'    | '1/16W'  | 'IO'       | 'RES CHIP 97.6K 1/16W +-1%(0402)EF'                | 'CHIPR0402'    | ''          | ''            | '20180208'
 '100K'       | '1%'      | '1/16W'  | '0402LF'  | 'CHIP'   | 'CS41002FB09'(!)        = 'End of Design' | 'Comp-Approve'     | 'CS41002FB09'           | 'R0402'             | '(R0402-0201)'                 | '100K'    | '1%'    | '1/16W'  | 'DISCRETE' | 'RES CHIP 100K 1/16W +-1%(0402)EF'                 | 'CHIPR0402'    | ''          | ''            | '20180208'
 '100K'       | '1%'      | '1/16W'  | '0402LF'  | 'EMPTY'  | 'CS41002FB09'(!)        = 'End of Design' | 'Comp-Approve'     | 'CS41002FB09'           | 'R0402'             | '(R0402-0201)'                 | '100K'    | '1%'    | '1/16W'  | 'IO'       | 'RES CHIP 100K 1/16W +-1%(0402)EF'                 | 'CHIPR0402'    | ''          | ''            | '20180208'
 '130K'       | '1%'      | '1/16W'  | '0402LF'  | 'CHIP'   | 'CS41302FB05'(!)        = 'End of Design' | 'Comp-Release Qty' | 'CS41302FB05'           | 'R0402'             | '(R0402-0201)'                 | '130K'    | '1%'    | '1/16W'  | 'DISCRETE' | 'RES CHIP 130K 1/16W +-1%(0402)EF'                 | 'CHIPR0402'    | ''          | ''            | '20180208'
 '130K'       | '1%'      | '1/16W'  | '0402LF'  | 'EMPTY'  | 'CS41302FB05'(!)        = 'End of Design' | 'Comp-Release Qty' | 'CS41302FB05'           | 'R0402'             | '(R0402-0201)'                 | '130K'    | '1%'    | '1/16W'  | 'IO'       | 'RES CHIP 130K 1/16W +-1%(0402)EF'                 | 'CHIPR0402'    | ''          | ''            | '20180208'
 '147K'       | '1%'      | '1/16W'  | '0402LF'  | 'CHIP'   | 'CS41472FB03'(!)        = 'End of Design' | 'Comp-Approve'     | 'CS41472FB03'           | 'R0402'             | '(R0402-0201)'                 | '147K'    | '1%'    | '1/16W'  | 'DISCRETE' | 'RES CHIP 147K 1/16W +-1%(0402)EF'                 | 'CHIPR0402'    | ''          | ''            | '20180208'
 '147K'       | '1%'      | '1/16W'  | '0402LF'  | 'EMPTY'  | 'CS41472FB03'(!)        = 'End of Design' | 'Comp-Approve'     | 'CS41472FB03'           | 'R0402'             | '(R0402-0201)'                 | '147K'    | '1%'    | '1/16W'  | 'IO'       | 'RES CHIP 147K 1/16W +-1%(0402)EF'                 | 'CHIPR0402'    | ''          | ''            | '20180208'
 '154K'       | '1%'      | '1/16W'  | '0402LF'  | 'CHIP'   | 'CS41542FB05'(!)        = 'End of Design' | 'Comp-Approve'     | 'CS41542FB05'           | 'R0402'             | '(R0402-0201)'                 | '154K'    | '1%'    | '1/16W'  | 'DISCRETE' | 'RES CHIP 154K 1/16W +-1%(0402)EF'                 | 'CHIPR0402'    | ''          | ''            | '20180208'
 '154K'       | '1%'      | '1/16W'  | '0402LF'  | 'EMPTY'  | 'CS41542FB05'(!)        = 'End of Design' | 'Comp-Approve'     | 'CS41542FB05'           | 'R0402'             | '(R0402-0201)'                 | '154K'    | '1%'    | '1/16W'  | 'IO'       | 'RES CHIP 154K 1/16W +-1%(0402)EF'                 | 'CHIPR0402'    | ''          | ''            | '20180208'
 '200K'       | '1%'      | '1/16W'  | '0402LF'  | 'CHIP'   | 'CS42002FB05'(!)        = 'End of Design' | 'Comp-Approve'     | 'CS42002FB05'           | 'R0402'             | '(R0402-0201)'                 | '200K'    | '1%'    | '1/16W'  | 'DISCRETE' | 'RES CHIP 200K 1/16W +-1%(0402)EF'                 | 'CHIPR0402'    | ''          | ''            | '20180208'
 '200K'       | '1%'      | '1/16W'  | '0402LF'  | 'EMPTY'  | 'CS42002FB05'(!)        = 'End of Design' | 'Comp-Approve'     | 'CS42002FB05'           | 'R0402'             | '(R0402-0201)'                 | '200K'    | '1%'    | '1/16W'  | 'IO'       | 'RES CHIP 200K 1/16W +-1%(0402)EF'                 | 'CHIPR0402'    | ''          | ''            | '20180208'
 '267K'       | '1%'      | '1/16W'  | '0402LF'  | 'CHIP'   | 'CS42672FB03'(!)        = 'End of Design' | 'Comp-Approve'     | 'CS42672FB03'           | 'R0402'             | '(R0402-0201)'                 | '267K'    | '1%'    | '1/16W'  | 'DISCRETE' | 'RES CHIP 267K 1/16W +-1%(0402)EF'                 | 'CHIPR0402'    | ''          | ''            | '20180208'
 '267K'       | '1%'      | '1/16W'  | '0402LF'  | 'EMPTY'  | 'CS42672FB03'(!)        = 'End of Design' | 'Comp-Approve'     | 'CS42672FB03'           | 'R0402'             | '(R0402-0201)'                 | '267K'    | '1%'    | '1/16W'  | 'IO'       | 'RES CHIP 267K 1/16W +-1%(0402)EF'                 | 'CHIPR0402'    | ''          | ''            | '20180208'
 '0'          | '5%'      | '1/10W'  | '0603LF'  | 'CHIP'   | 'CS00003J910'(!)        = 'End of Design' | 'Comp-Approve'     | 'CS00003J910'           | 'R0603'             | '(SMR0603AW)'                  | '0'       | '5%'    | '1/16W'  | 'DISCRETE' | 'RES CHIP 0 1/10W +-5% (0603)EF'                   | 'CHIPR0603'    | ''          | ''            | '20180208'
 '0'          | '5%'      | '1/10W'  | '0603LF'  | 'EMPTY'  | 'CS00003J910'(!)        = 'End of Design' | 'Comp-Approve'     | 'CS00003J910'           | 'R0603'             | '(SMR0603AW)'                  | '0'       | '5%'    | '1/16W'  | 'IO'       | 'RES CHIP 0 1/10W +-5% (0603)EF'                   | 'CHIPR0603'    | ''          | ''            | '20180208'
 '200K'       | '0.1%'    | '1/10W'  | '0603LF'  | 'CHIP'   | 'CS42003B902'(!)        = 'End of Design' | 'Comp-Approve'     | 'CS42003B902'           | 'R0603_H24'         | '(SMR0603AW)'                  | '200K'    | '0.1%'  | '1/10W'  | 'DISCRETE' | 'RES CHIP 200K 1/10W +-0.1%(0603)EF'               | 'CHIPR0603'    | ''          | ''            | '20180213'
 '200K'       | '0.1%'    | '1/10W'  | '0603LF'  | 'EMPTY'  | 'CS42003B902'(!)        = 'End of Design' | 'Comp-Approve'     | 'CS42003B902'           | 'R0603_H24'         | '(SMR0603AW)'                  | '200K'    | '0.1%'  | '1/10W'  | 'IO'       | 'RES CHIP 200K 1/10W +-0.1%(0603)EF'               | 'CHIPR0603'    | ''          | ''            | '20180213'
 '1'          | '5'       | '1/8W'   | '0805LF'  | 'CHIP'   | 'CS-1004JA02'(!)        = ''              | ''                 | 'CS-1004JA02'           | 'R0805_H26'         | '(SMR0805AW)'                  | '1'       | '5%'    | '1/8W'   | 'DISCRETE' | 'RES CHIP 1 1/8W +-5%(0805)EF'                     | 'CHIPR0805'    | ''          | ''            | '20180213'
 '1'          | '5'       | '1/8W'   | '0805LF'  | 'EMPTY'  | 'CS-1004JA02'(!)        = ''              | ''                 | 'CS-1004JA02'           | 'R0805_H26'         | '(SMR0805AW)'                  | '1'       | '5%'    | '1/8W'   | 'IO'       | 'RES CHIP 1 1/8W +-5%(0805)EF'                     | 'CHIPR0805'    | ''          | ''            | '20180213'
 '0.002'      | '1%'      | '2W'     | '2512LF'  | 'CHIP'   | 'CS+002AFR06'(!)        = 'End of Design' | 'Comp-Approve'     | 'CS+002AFR06'           | 'R2512XS'           | '(SMR2512AW)'                  | '0.002'   | '1%'    | '2W'     | 'DISCRETE' | 'RES CHIP 0.002 2W +-1%(2512)EF'                   | 'CHIPR2512'    | ''          | ''            | '20180213'
 '0.002'      | '1%'      | '2W'     | '2512LF'  | 'EMPTY'  | 'CS+002AFR06'(!)        = 'End of Design' | 'Comp-Approve'     | 'CS+002AFR06'           | 'R2512XS'           | '(SMR2512AW)'                  | '0.002'   | '1%'    | '2W'     | 'IO'       | 'RES CHIP 0.002 2W +-1%(2512)EF'                   | 'CHIPR2512'    | ''          | ''            | '20180213'
 '20'         | '1%'      | '1/16W'  | '0402LF'  | 'CHIP'   | 'CS02002FB03'(!)        = 'End of Design' | 'Comp-Approve'     | 'CS02002FB03'           | 'R0402'             | '(R0402-0201)'                 | '20'      | '1%'    | '1/16W'  | 'DISCRETE' | 'RES CHIP 20 1/16W +-1%(0402)EF'                   | 'CHIPR0402'    | ''          | ''            | '20180221'
 '20'         | '1%'      | '1/16W'  | '0402LF'  | 'EMPTY'  | 'CS02002FB03'(!)        = 'End of Design' | 'Comp-Approve'     | 'CS02002FB03'           | 'R0402'             | '(R0402-0201)'                 | '20'      | '1%'    | '1/16W'  | 'IO'       | 'RES CHIP 20 1/16W +-1%(0402)EF'                   | 'CHIPR0402'    | ''          | ''            | '20180221'
 '22.1'       | '1%'      | '1/16W'  | '0402LF'  | 'CHIP'   | 'CS02212FB02'(!)        = 'End of Design' | 'Comp-Approve'     | 'CS02212FB02'           | 'R0402'             | '(R0402-0201)'                 | '22.1'    | '1%'    | '1/16W'  | 'DISCRETE' | 'RES CHIP 22.1 1/16W +-1%(0402)EF'                 | 'CHIPR0402'    | ''          | ''            | '20180221'
 '22.1'       | '1%'      | '1/16W'  | '0402LF'  | 'EMPTY'  | 'CS02212FB02'(!)        = 'End of Design' | 'Comp-Approve'     | 'CS02212FB02'           | 'R0402'             | '(R0402-0201)'                 | '22.1'    | '1%'    | '1/16W'  | 'IO'       | 'RES CHIP 22.1 1/16W +-1%(0402)EF'                 | 'CHIPR0402'    | ''          | ''            | '20180221'
 '27.4'       | '1%'      | '1/16W'  | '0402LF'  | 'CHIP'   | 'CS02742FB03'(!)        = 'End of Design' | 'Comp-Release Qty' | 'CS02742FB03'           | 'R0402'             | '(R0402-0201)'                 | '27.4'    | '1%'    | '1/16W'  | 'DISCRETE' | 'RES CHIP 27.4 1/16W +-1%(0402)EF'                 | 'CHIPR0402'    | ''          | ''            | '20180221'
 '27.4'       | '1%'      | '1/16W'  | '0402LF'  | 'EMPTY'  | 'CS02742FB03'(!)        = 'End of Design' | 'Comp-Release Qty' | 'CS02742FB03'           | 'R0402'             | '(R0402-0201)'                 | '27.4'    | '1%'    | '1/16W'  | 'IO'       | 'RES CHIP 27.4 1/16W +-1%(0402)EF'                 | 'CHIPR0402'    | ''          | ''            | '20180221'
 '47'         | '1%'      | '1/16W'  | '0402LF'  | 'CHIP'   | 'CS04702FB03'(!)        = 'End of Design' | 'Comp-Approve'     | 'CS04702FB03'           | 'R0402'             | '(R0402-0201)'                 | '47'      | '1%'    | '1/16W'  | 'DISCRETE' | 'RES CHIP 47 1/16W +-1% (0402)EF'                  | 'CHIPR0402'    | ''          | ''            | '20180221'
 '47'         | '1%'      | '1/16W'  | '0402LF'  | 'EMPTY'  | 'CS04702FB03'(!)        = 'End of Design' | 'Comp-Approve'     | 'CS04702FB03'           | 'R0402'             | '(R0402-0201)'                 | '47'      | '1%'    | '1/16W'  | 'IO'       | 'RES CHIP 47 1/16W +-1% (0402)EF'                  | 'CHIPR0402'    | ''          | ''            | '20180221'
 '60.4'       | '1%'      | '1/16W'  | '0402LF'  | 'CHIP'   | 'CS06042FB03'(!)        = 'End of Design' | 'Comp-Approve'     | 'CS06042FB03'           | 'R0402'             | '(R0402-0201)'                 | '60.4'    | '1%'    | '1/16W'  | 'DISCRETE' | 'RES CHIP 60.4 1/16W +-1%(0402)EF'                 | 'CHIPR0402'    | ''          | ''            | '20180221'
 '60.4'       | '1%'      | '1/16W'  | '0402LF'  | 'EMPTY'  | 'CS06042FB03'(!)        = 'End of Design' | 'Comp-Approve'     | 'CS06042FB03'           | 'R0402'             | '(R0402-0201)'                 | '60.4'    | '1%'    | '1/16W'  | 'IO'       | 'RES CHIP 60.4 1/16W +-1%(0402)EF'                 | 'CHIPR0402'    | ''          | ''            | '20180221'
 '75'         | '1%'      | '1/16W'  | '0402LF'  | 'CHIP'   | 'CS07502FB04'(!)        = 'End of Design' | 'Comp-Approve'     | 'CS07502FB04'           | 'R0402'             | '(R0402-0201)'                 | '75'      | '1%'    | '1/16W'  | 'DISCRETE' | 'RES CHIP 75 1/16W +-1%(0402)EF'                   | 'CHIPR0402'    | ''          | ''            | '20180221'
 '75'         | '1%'      | '1/16W'  | '0402LF'  | 'EMPTY'  | 'CS07502FB04'(!)        = 'End of Design' | 'Comp-Approve'     | 'CS07502FB04'           | 'R0402'             | '(R0402-0201)'                 | '75'      | '1%'    | '1/16W'  | 'IO'       | 'RES CHIP 75 1/16W +-1%(0402)EF'                   | 'CHIPR0402'    | ''          | ''            | '20180221'
 '113'        | '1%'      | '1/16W'  | '0402LF'  | 'CHIP'   | 'CS11132FB02'(!)        = 'End of Design' | 'Comp-Approve'     | 'CS11132FB02'           | 'R0402'             | '(R0402-0201)'                 | '113'     | '1%'    | '1/16W'  | 'DISCRETE' | 'RES CHIP 113 1/16W +-1%(0402)EF'                  | 'CHIPR0402'    | ''          | ''            | '20180221'
 '113'        | '1%'      | '1/16W'  | '0402LF'  | 'EMPTY'  | 'CS11132FB02'(!)        = 'End of Design' | 'Comp-Approve'     | 'CS11132FB02'           | 'R0402'             | '(R0402-0201)'                 | '113'     | '1%'    | '1/16W'  | 'IO'       | 'RES CHIP 113 1/16W +-1%(0402)EF'                  | 'CHIPR0402'    | ''          | ''            | '20180221'
 '130'        | '1%'      | '1/16W'  | '0402LF'  | 'CHIP'   | 'CS11302FB03'(!)        = 'End of Design' | 'Comp-Approve'     | 'CS11302FB03'           | 'R0402'             | '(R0402-0201)'                 | '130'     | '1%'    | '1/16W'  | 'DISCRETE' | 'RES CHIP 130 1/16W +-1%(0402)EF'                  | 'CHIPR0402'    | ''          | ''            | '20180221'
 '130'        | '1%'      | '1/16W'  | '0402LF'  | 'EMPTY'  | 'CS11302FB03'(!)        = 'End of Design' | 'Comp-Approve'     | 'CS11302FB03'           | 'R0402'             | '(R0402-0201)'                 | '130'     | '1%'    | '1/16W'  | 'IO'       | 'RES CHIP 130 1/16W +-1%(0402)EF'                  | 'CHIPR0402'    | ''          | ''            | '20180221'
 '169'        | '1%'      | '1/16W'  | '0402LF'  | 'CHIP'   | 'CS11692FB01'(!)        = 'End of Design' | 'Comp-Approve'     | 'CS11692FB01'           | 'R0402'             | '(R0402-0201)'                 | '169'     | '1%'    | '1/16W'  | 'DISCRETE' | 'RES CHIP 169 1/16W +-1%(0402)EF'                  | 'CHIPR0402'    | ''          | ''            | '20180221'
 '169'        | '1%'      | '1/16W'  | '0402LF'  | 'EMPTY'  | 'CS11692FB01'(!)        = 'End of Design' | 'Comp-Approve'     | 'CS11692FB01'           | 'R0402'             | '(R0402-0201)'                 | '169'     | '1%'    | '1/16W'  | 'IO'       | 'RES CHIP 169 1/16W +-1%(0402)EF'                  | 'CHIPR0402'    | ''          | ''            | '20180221'
 '220'        | '0.1%'    | '1/16W'  | '0402LF'  | 'CHIP'   | 'CS12202BB00'(!)        = 'End of Design' | 'Comp-Approve'     | 'CS12202BB00'           | 'R0402'             | '(R0402-0201)'                 | '220'     | '0.1%'  | '1/16W'  | 'DISCRETE' | 'RES CHIP 220 1/16W +-0.1%(0402)EF'                | 'CHIPR0402'    | ''          | ''            | '20180221'
 '220'        | '0.1%'    | '1/16W'  | '0402LF'  | 'EMPTY'  | 'CS12202BB00'(!)        = 'End of Design' | 'Comp-Approve'     | 'CS12202BB00'           | 'R0402'             | '(R0402-0201)'                 | '220'     | '0.1%'  | '1/16W'  | 'IO'       | 'RES CHIP 220 1/16W +-0.1%(0402)EF'                | 'CHIPR0402'    | ''          | ''            | '20180221'
 '240'        | '1%'      | '1/16W'  | '0402LF'  | 'CHIP'   | 'CS12402FB01'(!)        = 'End of Design' | 'Comp-Approve'     | 'CS12402FB01'           | 'R0402'             | '(R0402-0201)'                 | '240'     | '1%'    | '1/16W'  | 'DISCRETE' | 'RES CHIP 240 1/16W +-1%(0402)EF'                  | 'CHIPR0402'    | ''          | ''            | '20180221'
 '240'        | '1%'      | '1/16W'  | '0402LF'  | 'EMPTY'  | 'CS12402FB01'(!)        = 'End of Design' | 'Comp-Approve'     | 'CS12402FB01'           | 'R0402'             | '(R0402-0201)'                 | '240'     | '1%'    | '1/16W'  | 'IO'       | 'RES CHIP 240 1/16W +-1%(0402)EF'                  | 'CHIPR0402'    | ''          | ''            | '20180221'
 '332'        | '1%'      | '1/16W'  | '0402LF'  | 'CHIP'   | 'CS13322FB05'(!)        = 'End of Design' | 'Comp-Approve'     | 'CS13322FB05'           | 'R0402'             | '(R0402-0201)'                 | '332'     | '1%'    | '1/16W'  | 'DISCRETE' | 'RES CHIP 332 1/16W +-1%(0402)EF'                  | 'CHIPR0402'    | ''          | ''            | '20180221'
 '332'        | '1%'      | '1/16W'  | '0402LF'  | 'EMPTY'  | 'CS13322FB05'(!)        = 'End of Design' | 'Comp-Approve'     | 'CS13322FB05'           | 'R0402'             | '(R0402-0201)'                 | '332'     | '1%'    | '1/16W'  | 'IO'       | 'RES CHIP 332 1/16W +-1%(0402)EF'                  | 'CHIPR0402'    | ''          | ''            | '20180221'
 '348'        | '1%'      | '1/16W'  | '0402LF'  | 'CHIP'   | 'CS13482FB02'(!)        = 'End of Design' | 'Comp-Approve'     | 'CS13482FB02'           | 'R0402'             | '(R0402-0201)'                 | '348'     | '1%'    | '1/16W'  | 'DISCRETE' | 'RES CHIP 348 1/16W +-1%(0402)EF'                  | 'CHIPR0402'    | ''          | ''            | '20180221'
 '348'        | '1%'      | '1/16W'  | '0402LF'  | 'EMPTY'  | 'CS13482FB02'(!)        = 'End of Design' | 'Comp-Approve'     | 'CS13482FB02'           | 'R0402'             | '(R0402-0201)'                 | '348'     | '1%'    | '1/16W'  | 'IO'       | 'RES CHIP 348 1/16W +-1%(0402)EF'                  | 'CHIPR0402'    | ''          | ''            | '20180221'
 '402'        | '1%'      | '1/16W'  | '0402LF'  | 'CHIP'   | 'CS14022FB02'(!)        = 'End of Design' | 'Comp-Approve'     | 'CS14022FB02'           | 'R0402'             | '(R0402-0201)'                 | '402'     | '1%'    | '1/16W'  | 'DISCRETE' | 'RES CHIP 402 1/16W +-1%(0402)EF'                  | 'CHIPR0402'    | ''          | ''            | '20180221'
 '402'        | '1%'      | '1/16W'  | '0402LF'  | 'EMPTY'  | 'CS14022FB02'(!)        = 'End of Design' | 'Comp-Approve'     | 'CS14022FB02'           | 'R0402'             | '(R0402-0201)'                 | '402'     | '1%'    | '1/16W'  | 'IO'       | 'RES CHIP 402 1/16W +-1%(0402)EF'                  | 'CHIPR0402'    | ''          | ''            | '20180221'
 '475'        | '1%'      | '1/16W'  | '0402LF'  | 'CHIP'   | 'CS14752FB04'(!)        = 'End of Design' | 'Comp-Approve'     | 'CS14752FB04'           | 'R0402'             | '(R0402-0201)'                 | '475'     | '1%'    | '1/16W'  | 'DISCRETE' | 'RES CHIP 475 1/16W +-1%(0402)EF'                  | 'CHIPR0402'    | ''          | ''            | '20180221'
 '475'        | '1%'      | '1/16W'  | '0402LF'  | 'EMPTY'  | 'CS14752FB04'(!)        = 'End of Design' | 'Comp-Approve'     | 'CS14752FB04'           | 'R0402'             | '(R0402-0201)'                 | '475'     | '1%'    | '1/16W'  | 'IO'       | 'RES CHIP 475 1/16W +-1%(0402)EF'                  | 'CHIPR0402'    | ''          | ''            | '20180221'
 '499'        | '1%'      | '1/16W'  | '0402LF'  | 'CHIP'   | 'CS14992FB06'(!)        = 'End of Design' | 'Comp-Approve'     | 'CS14992FB06'           | 'R0402'             | '(R0402-0201)'                 | '499'     | '1%'    | '1/16W'  | 'DISCRETE' | 'RES CHIP 499 1/16W +-1%(0402)EF'                  | 'CHIPR0402'    | ''          | ''            | '20180221'
 '499'        | '1%'      | '1/16W'  | '0402LF'  | 'EMPTY'  | 'CS14992FB06'(!)        = 'End of Design' | 'Comp-Approve'     | 'CS14992FB06'           | 'R0402'             | '(R0402-0201)'                 | '499'     | '1%'    | '1/16W'  | 'IO'       | 'RES CHIP 499 1/16W +-1%(0402)EF'                  | 'CHIPR0402'    | ''          | ''            | '20180221'
 '511'        | '1%'      | '1/16W'  | '0402LF'  | 'CHIP'   | 'CS15112FB03'(!)        = 'End of Design' | 'Comp-Approve'     | 'CS15112FB03'           | 'R0402'             | '(R0402-0201)'                 | '511'     | '1%'    | '1/16W'  | 'DISCRETE' | 'RES CHIP 511 1/16W +-1%(0402)EF'                  | 'CHIPR0402'    | ''          | ''            | '20180221'
 '511'        | '1%'      | '1/16W'  | '0402LF'  | 'EMPTY'  | 'CS15112FB03'(!)        = 'End of Design' | 'Comp-Approve'     | 'CS15112FB03'           | 'R0402'             | '(R0402-0201)'                 | '511'     | '1%'    | '1/16W'  | 'IO'       | 'RES CHIP 511 1/16W +-1%(0402)EF'                  | 'CHIPR0402'    | ''          | ''            | '20180221'
 '665'        | '1%'      | '1/16W'  | '0402LF'  | 'CHIP'   | 'CS16652FB00'(!)        = 'End of Design' | 'Comp-Approve'     | 'CS16652FB00'           | 'R0402'             | '(R0402-0201)'                 | '665'     | '1%'    | '1/16W'  | 'DISCRETE' | 'RES CHIP 665 1/16W +-1%(0402)EF'                  | 'CHIPR0402'    | ''          | ''            | '20180221'
 '665'        | '1%'      | '1/16W'  | '0402LF'  | 'EMPTY'  | 'CS16652FB00'(!)        = 'End of Design' | 'Comp-Approve'     | 'CS16652FB00'           | 'R0402'             | '(R0402-0201)'                 | '665'     | '1%'    | '1/16W'  | 'IO'       | 'RES CHIP 665 1/16W +-1%(0402)EF'                  | 'CHIPR0402'    | ''          | ''            | '20180221'
 '845'        | '1%'      | '1/16W'  | '0402LF'  | 'CHIP'   | 'CS18452FB01'(!)        = 'End of Design' | 'Comp-Approve'     | 'CS18452FB01'           | 'R0402'             | '(R0402-0201)'                 | '845'     | '1%'    | '1/16W'  | 'DISCRETE' | 'RES CHIP 845 1/16W +-1%(0402)EF'                  | 'CHIPR0402'    | ''          | ''            | '20180221'
 '845'        | '1%'      | '1/16W'  | '0402LF'  | 'EMPTY'  | 'CS18452FB01'(!)        = 'End of Design' | 'Comp-Approve'     | 'CS18452FB01'           | 'R0402'             | '(R0402-0201)'                 | '845'     | '1%'    | '1/16W'  | 'IO'       | 'RES CHIP 845 1/16W +-1%(0402)EF'                  | 'CHIPR0402'    | ''          | ''            | '20180221'
 '2'          | '1%'      | '1/16W'  | '0402LF'  | 'CHIP'   | 'CS-2002FB02'(!)        = 'End of Design' | 'Comp-Approve'     | 'CS-2002FB02'           | 'R0402'             | '(R0402-0201)'                 | '2'       | '1%'    | '1/16W'  | 'DISCRETE' | 'RES CHIP 2 1/16W +-1%(0402)EF'                    | 'CHIPR0402'    | ''          | ''            | '20180221'
 '2'          | '1%'      | '1/16W'  | '0402LF'  | 'EMPTY'  | 'CS-2002FB02'(!)        = 'End of Design' | 'Comp-Approve'     | 'CS-2002FB02'           | 'R0402'             | '(R0402-0201)'                 | '2'       | '1%'    | '1/16W'  | 'IO'       | 'RES CHIP 2 1/16W +-1%(0402)EF'                    | 'CHIPR0402'    | ''          | ''            | '20180221'
 '1K'         | '0.1%'    | '1/16W'  | '0402LF'  | 'CHIP'   | 'CS21002BB05'(!)        = 'End of Design' | 'Comp-Approve'     | 'CS21002BB05'           | 'R0402'             | '(R0402-0201)'                 | '1K'      | '0.1%'  | '1/16W'  | 'DISCRETE' | 'RES CHIP 1K 1/16W +-0.1%(0402)EF'                 | 'CHIPR0402'    | ''          | ''            | '20180221'
 '1K'         | '0.1%'    | '1/16W'  | '0402LF'  | 'EMPTY'  | 'CS21002BB05'(!)        = 'End of Design' | 'Comp-Approve'     | 'CS21002BB05'           | 'R0402'             | '(R0402-0201)'                 | '1K'      | '0.1%'  | '1/16W'  | 'IO'       | 'RES CHIP 1K 1/16W +-0.1%(0402)EF'                 | 'CHIPR0402'    | ''          | ''            | '20180221'
 '1.21K'      | '1%'      | '1/16W'  | '0402LF'  | 'CHIP'   | 'CS21212FB05'(!)        = 'End of Design' | 'Comp-Approve'     | 'CS21212FB05'           | 'R0402'             | '(R0402-0201)'                 | '1.21K'   | '1%'    | '1/16W'  | 'DISCRETE' | 'RES CHIP 1.21K 1/16W +-1%(0402)EF'                | 'CHIPR0402'    | ''          | ''            | '20180221'
 '1.21K'      | '1%'      | '1/16W'  | '0402LF'  | 'EMPTY'  | 'CS21212FB05'(!)        = 'End of Design' | 'Comp-Approve'     | 'CS21212FB05'           | 'R0402'             | '(R0402-0201)'                 | '1.21K'   | '1%'    | '1/16W'  | 'IO'       | 'RES CHIP 1.21K 1/16W +-1%(0402)EF'                | 'CHIPR0402'    | ''          | ''            | '20180221'
 '1.82K'      | '1%'      | '1/16W'  | '0402LF'  | 'CHIP'   | 'CS21822FB03'(!)        = 'End of Design' | 'Comp-Approve'     | 'CS21822FB03'           | 'R0402'             | '(R0402-0201)'                 | '1.82K'   | '1%'    | '1/16W'  | 'DISCRETE' | 'RES CHIP 1.82K 1/16W +-1%(0402)EF'                | 'CHIPR0402'    | ''          | ''            | '20180221'
 '1.82K'      | '1%'      | '1/16W'  | '0402LF'  | 'EMPTY'  | 'CS21822FB03'(!)        = 'End of Design' | 'Comp-Approve'     | 'CS21822FB03'           | 'R0402'             | '(R0402-0201)'                 | '1.82K'   | '1%'    | '1/16W'  | 'IO'       | 'RES CHIP 1.82K 1/16W +-1%(0402)EF'                | 'CHIPR0402'    | ''          | ''            | '20180221'
 '2K'         | '1%'      | '1/16W'  | '0402LF'  | 'CHIP'   | 'CS22002FB07'(!)        = 'End of Design' | 'Comp-Approve'     | 'CS22002FB07'           | 'R0402'             | '(R0402-0201)'                 | '2K'      | '1%'    | '1/16W'  | 'DISCRETE' | 'RES CHIP 2K 1/16W +-1%(0402)EF'                   | 'CHIPR0402'    | ''          | ''            | '20180221'
 '2K'         | '1%'      | '1/16W'  | '0402LF'  | 'EMPTY'  | 'CS22002FB07'(!)        = 'End of Design' | 'Comp-Approve'     | 'CS22002FB07'           | 'R0402'             | '(R0402-0201)'                 | '2K'      | '1%'    | '1/16W'  | 'IO'       | 'RES CHIP 2K 1/16W +-1%(0402)EF'                   | 'CHIPR0402'    | ''          | ''            | '20180221'
 '2.21K'      | '1%'      | '1/16W'  | '0402LF'  | 'CHIP'   | 'CS22212FB06'(!)        = 'End of Design' | 'Comp-Approve'     | 'CS22212FB06'           | 'R0402'             | '(R0402-0201)'                 | '2.21K'   | '1%'    | '1/16W'  | 'DISCRETE' | 'RES CHIP 2.21K 1/16W +-1%(0402)EF'                | 'CHIPR0402'    | ''          | ''            | '20180221'
 '2.21K'      | '1%'      | '1/16W'  | '0402LF'  | 'EMPTY'  | 'CS22212FB06'(!)        = 'End of Design' | 'Comp-Approve'     | 'CS22212FB06'           | 'R0402'             | '(R0402-0201)'                 | '2.21K'   | '1%'    | '1/16W'  | 'IO'       | 'RES CHIP 2.21K 1/16W +-1%(0402)EF'                | 'CHIPR0402'    | ''          | ''            | '20180221'
 '2.49K'      | '1%'      | '1/16W'  | '0402LF'  | 'CHIP'   | 'CS22492FB05'(!)        = 'End of Design' | 'Comp-Approve'     | 'CS22492FB05'           | 'R0402'             | '(R0402-0201)'                 | '2.49K'   | '1%'    | '1/16W'  | 'DISCRETE' | 'RES CHIP 2.49K 1/16W +-1%(0402)EF'                | 'CHIPR0402'    | ''          | ''            | '20180221'
 '2.49K'      | '1%'      | '1/16W'  | '0402LF'  | 'EMPTY'  | 'CS22492FB05'(!)        = 'End of Design' | 'Comp-Approve'     | 'CS22492FB05'           | 'R0402'             | '(R0402-0201)'                 | '2.49K'   | '1%'    | '1/16W'  | 'IO'       | 'RES CHIP 2.49K 1/16W +-1%(0402)EF'                | 'CHIPR0402'    | ''          | ''            | '20180221'
 '2.87K'      | '1%'      | '1/16W'  | '0402LF'  | 'CHIP'   | 'CS22872FB03'(!)        = 'End of Design' | 'Comp-Approve'     | 'CS22872FB03'           | 'R0402'             | '(R0402-0201)'                 | '2.87K'   | '1%'    | '1/16W'  | 'DISCRETE' | 'RES CHIP 2.87K 1/16W +-1%(0402)EF'                | 'CHIPR0402'    | ''          | ''            | '20180221'
 '2.87K'      | '1%'      | '1/16W'  | '0402LF'  | 'EMPTY'  | 'CS22872FB03'(!)        = 'End of Design' | 'Comp-Approve'     | 'CS22872FB03'           | 'R0402'             | '(R0402-0201)'                 | '2.87K'   | '1%'    | '1/16W'  | 'IO'       | 'RES CHIP 2.87K 1/16W +-1%(0402)EF'                | 'CHIPR0402'    | ''          | ''            | '20180221'
 '3.16K'      | '1%'      | '1/16W'  | '0402LF'  | 'CHIP'   | 'CS23162FB03'(!)        = 'End of Design' | 'Comp-Approve'     | 'CS23162FB03'           | 'R0402'             | '(R0402-0201)'                 | '3.16K'   | '1%'    | '1/16W'  | 'DISCRETE' | 'RES CHIP 3.16K 1/16W +-1%(0402)EF'                | 'CHIPR0402'    | ''          | ''            | '20180221'
 '3.16K'      | '1%'      | '1/16W'  | '0402LF'  | 'EMPTY'  | 'CS23162FB03'(!)        = 'End of Design' | 'Comp-Approve'     | 'CS23162FB03'           | 'R0402'             | '(R0402-0201)'                 | '3.16K'   | '1%'    | '1/16W'  | 'IO'       | 'RES CHIP 3.16K 1/16W +-1%(0402)EF'                | 'CHIPR0402'    | ''          | ''            | '20180221'
 '4.02K'      | '1%'      | '1/16W'  | '0402LF'  | 'CHIP'   | 'CS24022FB04'(!)        = 'End of Design' | 'Comp-Approve'     | 'CS24022FB04'           | 'R0402'             | '(R0402-0201)'                 | '4.02K'   | '1%'    | '1/16W'  | 'DISCRETE' | 'RES CHIP 4.02K 1/16W +-1%(0402)EF'                | 'CHIPR0402'    | ''          | ''            | '20180221'
 '4.02K'      | '1%'      | '1/16W'  | '0402LF'  | 'EMPTY'  | 'CS24022FB04'(!)        = 'End of Design' | 'Comp-Approve'     | 'CS24022FB04'           | 'R0402'             | '(R0402-0201)'                 | '4.02K'   | '1%'    | '1/16W'  | 'IO'       | 'RES CHIP 4.02K 1/16W +-1%(0402)EF'                | 'CHIPR0402'    | ''          | ''            | '20180221'
 '4.75K'      | '0.1%'    | '1/16W'  | '0402LF'  | 'CHIP'   | 'CS24752BB02'(!)        = 'End of Design' | 'Comp-Approve'     | 'CS24752BB02'           | 'R0402'             | '(R0402-0201)'                 | '4.75K'   | '0.1%'  | '1/16W'  | 'DISCRETE' | 'RES CHIP 4.75K 1/16W +-0.1%(0402)EF'              | 'CHIPR0402'    | ''          | ''            | '20180221'
 '4.75K'      | '0.1%'    | '1/16W'  | '0402LF'  | 'EMPTY'  | 'CS24752BB02'(!)        = 'End of Design' | 'Comp-Approve'     | 'CS24752BB02'           | 'R0402'             | '(R0402-0201)'                 | '4.75K'   | '0.1%'  | '1/16W'  | 'IO'       | 'RES CHIP 4.75K 1/16W +-0.1%(0402)EF'              | 'CHIPR0402'    | ''          | ''            | '20180221'
 '4.87K'      | '1%'      | '1/16W'  | '0402LF'  | 'CHIP'   | 'CS24872FB01'(!)        = 'End of Design' | 'Comp-Approve'     | 'CS24872FB01'           | 'R0402'             | '(R0402-0201)'                 | '4.87K'   | '1%'    | '1/16W'  | 'DISCRETE' | 'RES CHIP 4.87K 1/16W +-1%(0402)EF'                | 'CHIPR0402'    | ''          | ''            | '20180221'
 '4.87K'      | '1%'      | '1/16W'  | '0402LF'  | 'EMPTY'  | 'CS24872FB01'(!)        = 'End of Design' | 'Comp-Approve'     | 'CS24872FB01'           | 'R0402'             | '(R0402-0201)'                 | '4.87K'   | '1%'    | '1/16W'  | 'IO'       | 'RES CHIP 4.87K 1/16W +-1%(0402)EF'                | 'CHIPR0402'    | ''          | ''            | '20180221'
 '6.19K'      | '1%'      | '1/16W'  | '0402LF'  | 'CHIP'   | 'CS26192FB03'(!)        = 'End of Design' | 'Comp-Approve'     | 'CS26192FB03'           | 'R0402'             | '(R0402-0201)'                 | '6.19K'   | '1%'    | '1/16W'  | 'DISCRETE' | 'RES CHIP 6.19K 1/16W +-1%(0402)EF'                | 'CHIPR0402'    | ''          | ''            | '20180221'
 '6.19K'      | '1%'      | '1/16W'  | '0402LF'  | 'EMPTY'  | 'CS26192FB03'(!)        = 'End of Design' | 'Comp-Approve'     | 'CS26192FB03'           | 'R0402'             | '(R0402-0201)'                 | '6.19K'   | '1%'    | '1/16W'  | 'IO'       | 'RES CHIP 6.19K 1/16W +-1%(0402)EF'                | 'CHIPR0402'    | ''          | ''            | '20180221'
 '6.65K'      | '1%'      | '1/16W'  | '0402LF'  | 'CHIP'   | 'CS26652FB04'(!)        = 'End of Design' | 'Comp-Approve'     | 'CS26652FB04'           | 'R0402'             | '(R0402-0201)'                 | '6.65K'   | '1%'    | '1/16W'  | 'DISCRETE' | 'RES CHIP 6.65K 1/16W +-1%(0402)EF'                | 'CHIPR0402'    | ''          | ''            | '20180221'
 '6.65K'      | '1%'      | '1/16W'  | '0402LF'  | 'EMPTY'  | 'CS26652FB04'(!)        = 'End of Design' | 'Comp-Approve'     | 'CS26652FB04'           | 'R0402'             | '(R0402-0201)'                 | '6.65K'   | '1%'    | '1/16W'  | 'IO'       | 'RES CHIP 6.65K 1/16W +-1%(0402)EF'                | 'CHIPR0402'    | ''          | ''            | '20180221'
 '6.81K'      | '1%'      | '1/16W'  | '0402LF'  | 'CHIP'   | 'CS26812FB04'(!)        = ''              | ''                 | 'CS26812FB04'           | 'R0402'             | '(R0402-0201)'                 | '6.81K'   | '1%'    | '1/16W'  | 'DISCRETE' | 'RES CHIP 6.81K 1/16W +-1%(0402)EF'                | 'CHIPR0402'    | ''          | ''            | '20180221'
 '6.81K'      | '1%'      | '1/16W'  | '0402LF'  | 'EMPTY'  | 'CS26812FB04'(!)        = ''              | ''                 | 'CS26812FB04'           | 'R0402'             | '(R0402-0201)'                 | '6.81K'   | '1%'    | '1/16W'  | 'IO'       | 'RES CHIP 6.81K 1/16W +-1%(0402)EF'                | 'CHIPR0402'    | ''          | ''            | '20180221'
 '8.25K'      | '1%'      | '1/16W'  | '0402LF'  | 'CHIP'   | 'CS28252FB03'(!)        = 'End of Design' | 'Comp-Approve'     | 'CS28252FB03'           | 'R0402'             | '(R0402-0201)'                 | '8.25K'   | '1%'    | '1/16W'  | 'DISCRETE' | 'RES CHIP 8.25K 1/16W +-1%(0402)EF'                | 'CHIPR0402'    | ''          | ''            | '20180221'
 '8.25K'      | '1%'      | '1/16W'  | '0402LF'  | 'EMPTY'  | 'CS28252FB03'(!)        = 'End of Design' | 'Comp-Approve'     | 'CS28252FB03'           | 'R0402'             | '(R0402-0201)'                 | '8.25K'   | '1%'    | '1/16W'  | 'IO'       | 'RES CHIP 8.25K 1/16W +-1%(0402)EF'                | 'CHIPR0402'    | ''          | ''            | '20180221'
 '9.31K'      | '1%'      | '1/16W'  | '0402LF'  | 'CHIP'   | 'CS29312FB02'(!)        = 'End of Design' | 'Comp-Approve'     | 'CS29312FB02'           | 'R0402'             | '(R0402-0201)'                 | '9.31K'   | '1%'    | '1/16W'  | 'DISCRETE' | 'RES CHIP 9.31K 1/16W +-1%(0402)EF'                | 'CHIPR0402'    | ''          | ''            | '20180221'
 '9.31K'      | '1%'      | '1/16W'  | '0402LF'  | 'EMPTY'  | 'CS29312FB02'(!)        = 'End of Design' | 'Comp-Approve'     | 'CS29312FB02'           | 'R0402'             | '(R0402-0201)'                 | '9.31K'   | '1%'    | '1/16W'  | 'IO'       | 'RES CHIP 9.31K 1/16W +-1%(0402)EF'                | 'CHIPR0402'    | ''          | ''            | '20180221'
 '11K'        | '1%'      | '1/16W'  | '0402LF'  | 'CHIP'   | 'CS31102FB05'(!)        = 'End of Design' | 'Comp-Approve'     | 'CS31102FB05'           | 'R0402'             | '(R0402-0201)'                 | '11K'     | '1%'    | '1/16W'  | 'DISCRETE' | 'RES CHIP 11K 1/16W +-1%(0402)EF'                  | 'CHIPR0402'    | ''          | ''            | '20180221'
 '11K'        | '1%'      | '1/16W'  | '0402LF'  | 'EMPTY'  | 'CS31102FB05'(!)        = 'End of Design' | 'Comp-Approve'     | 'CS31102FB05'           | 'R0402'             | '(R0402-0201)'                 | '11K'     | '1%'    | '1/16W'  | 'IO'       | 'RES CHIP 11K 1/16W +-1%(0402)EF'                  | 'CHIPR0402'    | ''          | ''            | '20180221'
 '11.5K'      | '1%'      | '1/16W'  | '0402LF'  | 'CHIP'   | 'CS31152FB03'(!)        = 'End of Design' | 'Comp-Approve'     | 'CS31152FB03'           | 'R0402'             | '(R0402-0201)'                 | '11.5K'   | '1%'    | '1/16W'  | 'DISCRETE' | 'RES CHIP 11.5K 1/16W +-1%(0402)EF'                | 'CHIPR0402'    | ''          | ''            | '20180221'
 '11.5K'      | '1%'      | '1/16W'  | '0402LF'  | 'EMPTY'  | 'CS31152FB03'(!)        = 'End of Design' | 'Comp-Approve'     | 'CS31152FB03'           | 'R0402'             | '(R0402-0201)'                 | '11.5K'   | '1%'    | '1/16W'  | 'IO'       | 'RES CHIP 11.5K 1/16W +-1%(0402)EF'                | 'CHIPR0402'    | ''          | ''            | '20180221'
 '11.8K'      | '1%'      | '1/16W'  | '0402LF'  | 'CHIP'   | 'CS31182FB03'(!)        = 'End of Design' | 'Comp-Approve'     | 'CS31182FB03'           | 'R0402'             | '(R0402-0201)'                 | '11.8K'   | '1%'    | '1/16W'  | 'DISCRETE' | 'RES CHIP 11.8K 1/16W +-1%(0402)EF'                | 'CHIPR0402'    | ''          | ''            | '20180221'
 '11.8K'      | '1%'      | '1/16W'  | '0402LF'  | 'EMPTY'  | 'CS31182FB03'(!)        = 'End of Design' | 'Comp-Approve'     | 'CS31182FB03'           | 'R0402'             | '(R0402-0201)'                 | '11.8K'   | '1%'    | '1/16W'  | 'IO'       | 'RES CHIP 11.8K 1/16W +-1%(0402)EF'                | 'CHIPR0402'    | ''          | ''            | '20180221'
 '12K'        | '1%'      | '1/16W'  | '0402LF'  | 'CHIP'   | 'CS31202FB04'(!)        = 'End of Design' | 'Comp-Approve'     | 'CS31202FB04'           | 'R0402'             | '(R0402-0201)'                 | '12K'     | '1%'    | '1/16W'  | 'DISCRETE' | 'RES CHIP 12K 1/16W +-1%(0402)EF'                  | 'CHIPR0402'    | ''          | ''            | '20180221'
 '12K'        | '1%'      | '1/16W'  | '0402LF'  | 'EMPTY'  | 'CS31202FB04'(!)        = 'End of Design' | 'Comp-Approve'     | 'CS31202FB04'           | 'R0402'             | '(R0402-0201)'                 | '12K'     | '1%'    | '1/16W'  | 'IO'       | 'RES CHIP 12K 1/16W +-1%(0402)EF'                  | 'CHIPR0402'    | ''          | ''            | '20180221'
 '12.1K'      | '1%'      | '1/16W'  | '0402LF'  | 'CHIP'   | 'CS31212FB05'(!)        = 'End of Design' | 'Comp-Approve'     | 'CS31212FB05'           | 'R0402'             | '(R0402-0201)'                 | '12.1K'   | '1%'    | '1/16W'  | 'DISCRETE' | 'RES CHIP 12.1K 1/16W +-1%(0402)EF'                | 'CHIPR0402'    | ''          | ''            | '20180221'
 '12.1K'      | '1%'      | '1/16W'  | '0402LF'  | 'EMPTY'  | 'CS31212FB05'(!)        = 'End of Design' | 'Comp-Approve'     | 'CS31212FB05'           | 'R0402'             | '(R0402-0201)'                 | '12.1K'   | '1%'    | '1/16W'  | 'IO'       | 'RES CHIP 12.1K 1/16W +-1%(0402)EF'                | 'CHIPR0402'    | ''          | ''            | '20180221'
 '12.4K'      | '1%'      | '1/16W'  | '0402LF'  | 'CHIP'   | 'CS31242FB02'(!)        = 'End of Design' | 'Comp-Approve'     | 'CS31242FB02'           | 'R0402'             | '(R0402-0201)'                 | '12.4K'   | '1%'    | '1/16W'  | 'DISCRETE' | 'RES CHIP 12.4K 1/16W +-1%(0402)EF'                | 'CHIPR0402'    | ''          | ''            | '20180221'
 '12.4K'      | '1%'      | '1/16W'  | '0402LF'  | 'EMPTY'  | 'CS31242FB02'(!)        = 'End of Design' | 'Comp-Approve'     | 'CS31242FB02'           | 'R0402'             | '(R0402-0201)'                 | '12.4K'   | '1%'    | '1/16W'  | 'IO'       | 'RES CHIP 12.4K 1/16W +-1%(0402)EF'                | 'CHIPR0402'    | ''          | ''            | '20180221'
 '13K'        | '1%'      | '1/16W'  | '0402LF'  | 'CHIP'   | 'CS31302FB04'(!)        = 'End of Design' | 'Comp-Approve'     | 'CS31302FB04'           | 'R0402'             | '(R0402-0201)'                 | '13K'     | '1%'    | '1/16W'  | 'DISCRETE' | 'RES CHIP 13K 1/16W +-1%(0402)EF'                  | 'CHIPR0402'    | ''          | ''            | '20180221'
 '13K'        | '1%'      | '1/16W'  | '0402LF'  | 'EMPTY'  | 'CS31302FB04'(!)        = 'End of Design' | 'Comp-Approve'     | 'CS31302FB04'           | 'R0402'             | '(R0402-0201)'                 | '13K'     | '1%'    | '1/16W'  | 'IO'       | 'RES CHIP 13K 1/16W +-1%(0402)EF'                  | 'CHIPR0402'    | ''          | ''            | '20180221'
 '14K'        | '1%'      | '1/16W'  | '0402LF'  | 'CHIP'   | 'CS31402FB03'(!)        = 'End of Design' | 'Comp-Approve'     | 'CS31402FB03'           | 'R0402'             | '(R0402-0201)'                 | '14K'     | '1%'    | '1/16W'  | 'DISCRETE' | 'RES CHIP 14K 1/16W +-1%(0402)EF'                  | 'CHIPR0402'    | ''          | ''            | '20180221'
 '14K'        | '1%'      | '1/16W'  | '0402LF'  | 'EMPTY'  | 'CS31402FB03'(!)        = 'End of Design' | 'Comp-Approve'     | 'CS31402FB03'           | 'R0402'             | '(R0402-0201)'                 | '14K'     | '1%'    | '1/16W'  | 'IO'       | 'RES CHIP 14K 1/16W +-1%(0402)EF'                  | 'CHIPR0402'    | ''          | ''            | '20180221'
 '14.3K'      | '1%'      | '1/16W'  | '0402LF'  | 'CHIP'   | 'CS31432FB02'(!)        = 'End of Design' | 'Comp-Approve'     | 'CS31432FB02'           | 'R0402'             | '(R0402-0201)'                 | '14.3K'   | '1%'    | '1/16W'  | 'DISCRETE' | 'RES CHIP 14.3K 1/16W +-1%(0402)EF'                | 'CHIPR0402'    | ''          | ''            | '20180221'
 '14.3K'      | '1%'      | '1/16W'  | '0402LF'  | 'EMPTY'  | 'CS31432FB02'(!)        = 'End of Design' | 'Comp-Approve'     | 'CS31432FB02'           | 'R0402'             | '(R0402-0201)'                 | '14.3K'   | '1%'    | '1/16W'  | 'IO'       | 'RES CHIP 14.3K 1/16W +-1%(0402)EF'                | 'CHIPR0402'    | ''          | ''            | '20180221'
 '15K'        | '0.1%'    | '1/16W'  | '0402LF'  | 'CHIP'   | 'CS31502BB03'(!)        = 'End of Design' | 'Comp-Approve'     | 'CS31502BB03'           | 'R0402'             | '(R0402-0201)'                 | '15K'     | '0.1%'  | '1/16W'  | 'DISCRETE' | 'RES CHIP 15K  1/16W +-0.1%(0402)EF'               | 'CHIPR0402'    | ''          | ''            | '20180221'
 '15K'        | '0.1%'    | '1/16W'  | '0402LF'  | 'EMPTY'  | 'CS31502BB03'(!)        = 'End of Design' | 'Comp-Approve'     | 'CS31502BB03'           | 'R0402'             | '(R0402-0201)'                 | '15K'     | '0.1%'  | '1/16W'  | 'IO'       | 'RES CHIP 15K  1/16W +-0.1%(0402)EF'               | 'CHIPR0402'    | ''          | ''            | '20180221'
 '15.8K'      | '1%'      | '1/16W'  | '0402LF'  | 'CHIP'   | 'CS31582FB02'(!)        = 'End of Design' | 'Comp-Approve'     | 'CS31582FB02'           | 'R0402'             | '(R0402-0201)'                 | '15.8K'   | '1%'    | '1/16W'  | 'DISCRETE' | 'RES CHIP 15.8K 1/16W +-1% (0402)EF'               | 'CHIPR0402'    | ''          | ''            | '20180221'
 '15.8K'      | '1%'      | '1/16W'  | '0402LF'  | 'EMPTY'  | 'CS31582FB02'(!)        = 'End of Design' | 'Comp-Approve'     | 'CS31582FB02'           | 'R0402'             | '(R0402-0201)'                 | '15.8K'   | '1%'    | '1/16W'  | 'IO'       | 'RES CHIP 15.8K 1/16W +-1% (0402)EF'               | 'CHIPR0402'    | ''          | ''            | '20180221'
 '16.5K'      | '1%'      | '1/16W'  | '0402LF'  | 'CHIP'   | 'CS31652FB05'(!)        = 'End of Design' | 'Comp-Approve'     | 'CS31652FB05'           | 'R0402'             | '(R0402-0201)'                 | '16.5K'   | '1%'    | '1/16W'  | 'DISCRETE' | 'RES CHIP 16.5K 1/16W +-1%(0402)EF'                | 'CHIPR0402'    | ''          | ''            | '20180221'
 '16.5K'      | '1%'      | '1/16W'  | '0402LF'  | 'EMPTY'  | 'CS31652FB05'(!)        = 'End of Design' | 'Comp-Approve'     | 'CS31652FB05'           | 'R0402'             | '(R0402-0201)'                 | '16.5K'   | '1%'    | '1/16W'  | 'IO'       | 'RES CHIP 16.5K 1/16W +-1%(0402)EF'                | 'CHIPR0402'    | ''          | ''            | '20180221'
 '22K'        | '1%'      | '1/16W'  | '0402LF'  | 'CHIP'   | 'CS32202FB02'(!)        = 'End of Design' | 'Comp-Approve'     | 'CS32202FB02'           | 'R0402'             | '(R0402-0201)'                 | '22K'     | '1%'    | '1/16W'  | 'DISCRETE' | 'RES CHIP 22K 1/16W +-1%(0402)EF'                  | 'CHIPR0402'    | ''          | ''            | '20180221'
 '22K'        | '1%'      | '1/16W'  | '0402LF'  | 'EMPTY'  | 'CS32202FB02'(!)        = 'End of Design' | 'Comp-Approve'     | 'CS32202FB02'           | 'R0402'             | '(R0402-0201)'                 | '22K'     | '1%'    | '1/16W'  | 'IO'       | 'RES CHIP 22K 1/16W +-1%(0402)EF'                  | 'CHIPR0402'    | ''          | ''            | '20180221'
 '24.9K'      | '1%'      | '1/16W'  | '0402LF'  | 'CHIP'   | 'CS32492FB04'(!)        = 'End of Design' | 'Comp-Approve'     | 'CS32492FB04'           | 'R0402'             | '(R0402-0201)'                 | '24.9K'   | '1%'    | '1/16W'  | 'DISCRETE' | 'RES CHIP 24.9K 1/16W +-1%(0402)EF'                | 'CHIPR0402'    | ''          | ''            | '20180221'
 '24.9K'      | '1%'      | '1/16W'  | '0402LF'  | 'EMPTY'  | 'CS32492FB04'(!)        = 'End of Design' | 'Comp-Approve'     | 'CS32492FB04'           | 'R0402'             | '(R0402-0201)'                 | '24.9K'   | '1%'    | '1/16W'  | 'IO'       | 'RES CHIP 24.9K 1/16W +-1%(0402)EF'                | 'CHIPR0402'    | ''          | ''            | '20180221'
 '25.5K'      | '1%'      | '1/16W'  | '0402LF'  | 'CHIP'   | 'CS32552FB06'(!)        = 'End of Design' | 'Comp-Approve'     | 'CS32552FB06'           | 'R0402'             | '(R0402-0201)'                 | '25.5K'   | '1%'    | '1/16W'  | 'DISCRETE' | 'RES CHIP 25.5K 1/16W +-1%(0402)EF'                | 'CHIPR0402'    | ''          | ''            | '20180221'
 '25.5K'      | '1%'      | '1/16W'  | '0402LF'  | 'EMPTY'  | 'CS32552FB06'(!)        = 'End of Design' | 'Comp-Approve'     | 'CS32552FB06'           | 'R0402'             | '(R0402-0201)'                 | '25.5K'   | '1%'    | '1/16W'  | 'IO'       | 'RES CHIP 25.5K 1/16W +-1%(0402)EF'                | 'CHIPR0402'    | ''          | ''            | '20180221'
 '26.1K'      | '1%'      | '1/16W'  | '0402LF'  | 'CHIP'   | 'CS32612FB02'(!)        = 'End of Design' | 'Comp-Approve'     | 'CS32612FB02'           | 'R0402'             | '(R0402-0201)'                 | '26.1K'   | '1%'    | '1/16W'  | 'DISCRETE' | 'RES CHIP 26.1K 1/16W +-1%(0402)EF'                | 'CHIPR0402'    | ''          | ''            | '20180221'
 '26.1K'      | '1%'      | '1/16W'  | '0402LF'  | 'EMPTY'  | 'CS32612FB02'(!)        = 'End of Design' | 'Comp-Approve'     | 'CS32612FB02'           | 'R0402'             | '(R0402-0201)'                 | '26.1K'   | '1%'    | '1/16W'  | 'IO'       | 'RES CHIP 26.1K 1/16W +-1%(0402)EF'                | 'CHIPR0402'    | ''          | ''            | '20180221'
 '27.4K'      | '1%'      | '1/16W'  | '0402LF'  | 'CHIP'   | 'CS32742FB04'(!)        = 'End of Design' | 'Comp-Approve'     | 'CS32742FB04'           | 'R0402'             | '(R0402-0201)'                 | '27.4K'   | '1%'    | '1/16W'  | 'DISCRETE' | 'RES CHIP 27.4K 1/16W +-1%(0402)EF'                | 'CHIPR0402'    | ''          | ''            | '20180221'
 '27.4K'      | '1%'      | '1/16W'  | '0402LF'  | 'EMPTY'  | 'CS32742FB04'(!)        = 'End of Design' | 'Comp-Approve'     | 'CS32742FB04'           | 'R0402'             | '(R0402-0201)'                 | '27.4K'   | '1%'    | '1/16W'  | 'IO'       | 'RES CHIP 27.4K 1/16W +-1%(0402)EF'                | 'CHIPR0402'    | ''          | ''            | '20180221'
 '33K'        | '1%'      | '1/16W'  | '0402LF'  | 'CHIP'   | 'CS33302FB00'(!)        = ''              | ''                 | 'CS33302FB00'           | 'R0402'             | '(R0402-0201)'                 | '33K'     | '1%'    | '1/16W'  | 'DISCRETE' | 'RES CHIP 33K 1/16W +-1%(0402)EF'                  | 'CHIPR0402'    | ''          | ''            | '20180221'
 '33K'        | '1%'      | '1/16W'  | '0402LF'  | 'EMPTY'  | 'CS33302FB00'(!)        = ''              | ''                 | 'CS33302FB00'           | 'R0402'             | '(R0402-0201)'                 | '33K'     | '1%'    | '1/16W'  | 'IO'       | 'RES CHIP 33K 1/16W +-1%(0402)EF'                  | 'CHIPR0402'    | ''          | ''            | '20180221'
 '35.7K'      | '1%'      | '1/16W'  | '0402LF'  | 'CHIP'   | 'CS33572FB01'(!)        = 'End of Design' | 'Comp-Approve'     | 'CS33572FB01'           | 'R0402'             | '(R0402-0201)'                 | '35.7K'   | '1%'    | '1/16W'  | 'DISCRETE' | 'RES CHIP 35.7K 1/16W +-1%(0402) EF'               | 'CHIPR0402'    | ''          | ''            | '20180221'
 '35.7K'      | '1%'      | '1/16W'  | '0402LF'  | 'EMPTY'  | 'CS33572FB01'(!)        = 'End of Design' | 'Comp-Approve'     | 'CS33572FB01'           | 'R0402'             | '(R0402-0201)'                 | '35.7K'   | '1%'    | '1/16W'  | 'IO'       | 'RES CHIP 35.7K 1/16W +-1%(0402) EF'               | 'CHIPR0402'    | ''          | ''            | '20180221'
 '39.2K'      | '1%'      | '1/16W'  | '0402LF'  | 'CHIP'   | 'CS33922FB05'(!)        = 'End of Design' | 'Comp-Approve'     | 'CS33922FB05'           | 'R0402'             | '(R0402-0201)'                 | '39.2K'   | '1%'    | '1/16W'  | 'DISCRETE' | 'RES CHIP 39.2K 1/16W +-1%(0402)EF'                | 'CHIPR0402'    | ''          | ''            | '20180221'
 '39.2K'      | '1%'      | '1/16W'  | '0402LF'  | 'EMPTY'  | 'CS33922FB05'(!)        = 'End of Design' | 'Comp-Approve'     | 'CS33922FB05'           | 'R0402'             | '(R0402-0201)'                 | '39.2K'   | '1%'    | '1/16W'  | 'IO'       | 'RES CHIP 39.2K 1/16W +-1%(0402)EF'                | 'CHIPR0402'    | ''          | ''            | '20180221'
 '43.2K'      | '1%'      | '1/16W'  | '0402LF'  | 'CHIP'   | 'CS34322FB03'(!)        = 'End of Design' | 'Comp-Approve'     | 'CS34322FB03'           | 'R0402'             | '(R0402-0201)'                 | '43.2K'   | '1%'    | '1/16W'  | 'DISCRETE' | 'RES CHIP 43.2K 1/16W +-1%(0402)EF'                | 'CHIPR0402'    | ''          | ''            | '20180221'
 '43.2K'      | '1%'      | '1/16W'  | '0402LF'  | 'EMPTY'  | 'CS34322FB03'(!)        = 'End of Design' | 'Comp-Approve'     | 'CS34322FB03'           | 'R0402'             | '(R0402-0201)'                 | '43.2K'   | '1%'    | '1/16W'  | 'IO'       | 'RES CHIP 43.2K 1/16W +-1%(0402)EF'                | 'CHIPR0402'    | ''          | ''            | '20180221'
 '44.2K'      | '1%'      | '1/16W'  | '0402LF'  | 'CHIP'   | 'CS34422FB04'(!)        = 'End of Design' | 'Comp-Approve'     | 'CS34422FB04'           | 'R0402'             | '(R0402-0201)'                 | '44.2K'   | '1%'    | '1/16W'  | 'DISCRETE' | 'RES CHIP 44.2K 1/16W +-1%(0402)EF'                | 'CHIPR0402'    | ''          | ''            | '20180221'
 '44.2K'      | '1%'      | '1/16W'  | '0402LF'  | 'EMPTY'  | 'CS34422FB04'(!)        = 'End of Design' | 'Comp-Approve'     | 'CS34422FB04'           | 'R0402'             | '(R0402-0201)'                 | '44.2K'   | '1%'    | '1/16W'  | 'IO'       | 'RES CHIP 44.2K 1/16W +-1%(0402)EF'                | 'CHIPR0402'    | ''          | ''            | '20180221'
 '47.5K'      | '1%'      | '1/16W'  | '0402LF'  | 'CHIP'   | 'CS34752FB03'(!)        = 'End of Design' | 'Comp-Approve'     | 'CS34752FB03'           | 'R0402'             | '(R0402-0201)'                 | '47.5K'   | '1%'    | '1/16W'  | 'DISCRETE' | 'RES CHIP 47.5K 1/16W +-1%(0402)EF'                | 'CHIPR0402'    | ''          | ''            | '20180221'
 '47.5K'      | '1%'      | '1/16W'  | '0402LF'  | 'EMPTY'  | 'CS34752FB03'(!)        = 'End of Design' | 'Comp-Approve'     | 'CS34752FB03'           | 'R0402'             | '(R0402-0201)'                 | '47.5K'   | '1%'    | '1/16W'  | 'IO'       | 'RES CHIP 47.5K 1/16W +-1%(0402)EF'                | 'CHIPR0402'    | ''          | ''            | '20180221'
 '51.1K'      | '1%'      | '1/16W'  | '0402LF'  | 'CHIP'   | 'CS35112FB03'(!)        = 'End of Design' | 'Comp-Approve'     | 'CS35112FB03'           | 'R0402'             | '(R0402-0201)'                 | '51.1K'   | '1%'    | '1/16W'  | 'DISCRETE' | 'RES CHIP 51.1K 1/16W +-1%(0402)EF'                | 'CHIPR0402'    | ''          | ''            | '20180221'
 '51.1K'      | '1%'      | '1/16W'  | '0402LF'  | 'EMPTY'  | 'CS35112FB03'(!)        = 'End of Design' | 'Comp-Approve'     | 'CS35112FB03'           | 'R0402'             | '(R0402-0201)'                 | '51.1K'   | '1%'    | '1/16W'  | 'IO'       | 'RES CHIP 51.1K 1/16W +-1%(0402)EF'                | 'CHIPR0402'    | ''          | ''            | '20180221'
 '54.9K'      | '1%'      | '1/16W'  | '0402LF'  | 'CHIP'   | 'CS35492FB03'(!)        = 'End of Design' | 'Comp-Approve'     | 'CS35492FB03'           | 'R0402'             | '(R0402-0201)'                 | '54.9K'   | '1%'    | '1/16W'  | 'DISCRETE' | 'RES CHIP 54.9K 1/16W  +-1%(0402)EF'               | 'CHIPR0402'    | ''          | ''            | '20180221'
 '54.9K'      | '1%'      | '1/16W'  | '0402LF'  | 'EMPTY'  | 'CS35492FB03'(!)        = 'End of Design' | 'Comp-Approve'     | 'CS35492FB03'           | 'R0402'             | '(R0402-0201)'                 | '54.9K'   | '1%'    | '1/16W'  | 'IO'       | 'RES CHIP 54.9K 1/16W  +-1%(0402)EF'               | 'CHIPR0402'    | ''          | ''            | '20180221'
 '64.9K'      | '1%'      | '1/16W'  | '0402LF'  | 'CHIP'   | 'CS36492FB02'(!)        = 'End of Design' | 'Comp-Approve'     | 'CS36492FB02'           | 'R0402'             | '(R0402-0201)'                 | '64.9K'   | '1%'    | '1/16W'  | 'DISCRETE' | 'RES CHIP 64.9K 1/16W +-1%(0402)EF'                | 'CHIPR0402'    | ''          | ''            | '20180221'
 '64.9K'      | '1%'      | '1/16W'  | '0402LF'  | 'EMPTY'  | 'CS36492FB02'(!)        = 'End of Design' | 'Comp-Approve'     | 'CS36492FB02'           | 'R0402'             | '(R0402-0201)'                 | '64.9K'   | '1%'    | '1/16W'  | 'IO'       | 'RES CHIP 64.9K 1/16W +-1%(0402)EF'                | 'CHIPR0402'    | ''          | ''            | '20180221'
 '66.5K'      | '1%'      | '1/16W'  | '0402LF'  | 'CHIP'   | 'CS36652FB03'(!)        = 'End of Design' | 'Comp-Approve'     | 'CS36652FB03'           | 'R0402'             | '(R0402-0201)'                 | '66.5K'   | '1%'    | '1/16W'  | 'DISCRETE' | 'RES CHIP 66.5K 1/16W +-1%(0402)EF'                | 'CHIPR0402'    | ''          | ''            | '20180221'
 '66.5K'      | '1%'      | '1/16W'  | '0402LF'  | 'EMPTY'  | 'CS36652FB03'(!)        = 'End of Design' | 'Comp-Approve'     | 'CS36652FB03'           | 'R0402'             | '(R0402-0201)'                 | '66.5K'   | '1%'    | '1/16W'  | 'IO'       | 'RES CHIP 66.5K 1/16W +-1%(0402)EF'                | 'CHIPR0402'    | ''          | ''            | '20180221'
 '86.6K'      | '1%'      | '1/16W'  | '0402LF'  | 'CHIP'   | 'CS38662FB05'(!)        = 'End of Design' | 'Comp-Approve'     | 'CS38662FB05'           | 'R0402'             | '(R0402-0201)'                 | '86.6K'   | '1%'    | '1/16W'  | 'DISCRETE' | 'RES CHIP 86.6K 1/16W +-1%(0402)EF'                | 'CHIPR0402'    | ''          | ''            | '20180221'
 '86.6K'      | '1%'      | '1/16W'  | '0402LF'  | 'EMPTY'  | 'CS38662FB05'(!)        = 'End of Design' | 'Comp-Approve'     | 'CS38662FB05'           | 'R0402'             | '(R0402-0201)'                 | '86.6K'   | '1%'    | '1/16W'  | 'IO'       | 'RES CHIP 86.6K 1/16W +-1%(0402)EF'                | 'CHIPR0402'    | ''          | ''            | '20180221'
 '121K'       | '1%'      | '1/16W'  | '0402LF'  | 'CHIP'   | 'CS41212FB02'(!)        = 'End of Design' | 'Comp-Approve'     | 'CS41212FB02'           | 'R0402'             | '(R0402-0201)'                 | '121K'    | '1%'    | '1/16W'  | 'DISCRETE' | 'RES CHIP 121K 1/16W +-1%(0402)EF'                 | 'CHIPR0402'    | ''          | ''            | '20180221'
 '121K'       | '1%'      | '1/16W'  | '0402LF'  | 'EMPTY'  | 'CS41212FB02'(!)        = 'End of Design' | 'Comp-Approve'     | 'CS41212FB02'           | 'R0402'             | '(R0402-0201)'                 | '121K'    | '1%'    | '1/16W'  | 'IO'       | 'RES CHIP 121K 1/16W +-1%(0402)EF'                 | 'CHIPR0402'    | ''          | ''            | '20180221'
 '137K'       | '1%'      | '1/16W'  | '0402LF'  | 'CHIP'   | 'CS41372FB01'(!)        = 'End of Design' | 'Comp-Approve'     | 'CS41372FB01'           | 'R0402'             | '(R0402-0201)'                 | '137K'    | '1%'    | '1/16W'  | 'DISCRETE' | 'RES CHIP 137K 1/16W +-1%(0402)EF'                 | 'CHIPR0402'    | ''          | ''            | '20180221'
 '137K'       | '1%'      | '1/16W'  | '0402LF'  | 'EMPTY'  | 'CS41372FB01'(!)        = 'End of Design' | 'Comp-Approve'     | 'CS41372FB01'           | 'R0402'             | '(R0402-0201)'                 | '137K'    | '1%'    | '1/16W'  | 'IO'       | 'RES CHIP 137K 1/16W +-1%(0402)EF'                 | 'CHIPR0402'    | ''          | ''            | '20180221'
 '150K'       | '1%'      | '1/16W'  | '0402LF'  | 'CHIP'   | 'CS41502FB04'(!)        = 'End of Design' | 'Comp-Approve'     | 'CS41502FB04'           | 'R0402'             | '(R0402-0201)'                 | '150K'    | '1%'    | '1/16W'  | 'DISCRETE' | 'RES CHIP 150K 1/16W +-1%(0402)EF'                 | 'CHIPR0402'    | ''          | ''            | '20180221'
 '150K'       | '1%'      | '1/16W'  | '0402LF'  | 'EMPTY'  | 'CS41502FB04'(!)        = 'End of Design' | 'Comp-Approve'     | 'CS41502FB04'           | 'R0402'             | '(R0402-0201)'                 | '150K'    | '1%'    | '1/16W'  | 'IO'       | 'RES CHIP 150K 1/16W +-1%(0402)EF'                 | 'CHIPR0402'    | ''          | ''            | '20180221'
 '510K'       | '5%'      | '1/16W'  | '0402LF'  | 'CHIP'   | 'CS45102JB03'(!)        = 'End of Design' | 'Comp-Approve'     | 'CS45102JB03'           | 'R0402'             | '(R0402-0201)'                 | '510K'    | '5%'    | '1/16W'  | 'DISCRETE' | 'RES CHIP 510K 1/16W +-5%(0402)EF'                 | 'CHIPR0402'    | ''          | ''            | '20180221'
 '510K'       | '5%'      | '1/16W'  | '0402LF'  | 'EMPTY'  | 'CS45102JB03'(!)        = 'End of Design' | 'Comp-Approve'     | 'CS45102JB03'           | 'R0402'             | '(R0402-0201)'                 | '510K'    | '5%'    | '1/16W'  | 'IO'       | 'RES CHIP 510K 1/16W +-5%(0402)EF'                 | 'CHIPR0402'    | ''          | ''            | '20180221'
 '1M'         | '1%'      | '1/16W'  | '0402LF'  | 'CHIP'   | 'CS51002FB05'(!)        = 'End of Design' | 'Comp-Approve'     | 'CS51002FB05'           | 'R0402'             | '(R0402-0201)'                 | '1M'      | '1%'    | '1/16W'  | 'DISCRETE' | 'RES CHIP 1M 1/16W +-1%(0402)EF'                   | 'CHIPR0402'    | ''          | ''            | '20180221'
 '1M'         | '1%'      | '1/16W'  | '0402LF'  | 'EMPTY'  | 'CS51002FB05'(!)        = 'End of Design' | 'Comp-Approve'     | 'CS51002FB05'           | 'R0402'             | '(R0402-0201)'                 | '1M'      | '1%'    | '1/16W'  | 'IO'       | 'RES CHIP 1M 1/16W +-1%(0402)EF'                   | 'CHIPR0402'    | ''          | ''            | '20180221'
 '2.2'        | '1%'      | '1/10W'  | '0603LF'  | 'CHIP'   | 'CS-2203F902'(!)        = 'End of Design' | 'Comp-Approve'     | 'CS-2203F902'           | 'R0603'             | '(SMR0603AW)'                  | '2.2'     | '1%'    | '1/10W'  | 'DISCRETE' | 'RES CHIP 2.2 1/10W +-1%(0603)EF'                  | 'CHIPR0603'    | ''          | ''            | '20180221'
 '2.2'        | '1%'      | '1/10W'  | '0603LF'  | 'EMPTY'  | 'CS-2203F902'(!)        = 'End of Design' | 'Comp-Approve'     | 'CS-2203F902'           | 'R0603'             | '(SMR0603AW)'                  | '2.2'     | '1%'    | '1/10W'  | 'IO'       | 'RES CHIP 2.2 1/10W +-1%(0603)EF'                  | 'CHIPR0603'    | ''          | ''            | '20180221'
 '10M'        | '1%'      | '1/10W'  | '0603LF'  | 'CHIP'   | 'CS61003F901'(!)        = 'End of Design' | 'Comp-Approve'     | 'CS61003F901'           | 'R0603'             | '(SMR0603AW)'                  | '10M'     | '1%'    | '1/10W'  | 'DISCRETE' | 'RES CHIP 10M 1/10W +-1%(0603)EF'                  | 'CHIPR0603'    | ''          | ''            | '20180221'
 '10M'        | '1%'      | '1/10W'  | '0603LF'  | 'EMPTY'  | 'CS61003F901'(!)        = 'End of Design' | 'Comp-Approve'     | 'CS61003F901'           | 'R0603'             | '(SMR0603AW)'                  | '10M'     | '1%'    | '1/10W'  | 'IO'       | 'RES CHIP 10M 1/10W +-1%(0603)EF'                  | 'CHIPR0603'    | ''          | ''            | '20180221'
 '0'          | ''        | '1/2W'   | '1206LF'  | 'CHIP'   | 'CS00007T200'(!)        = 'End of Design' | 'Comp-Approve'     | 'CS00007T200'           | 'R1206XI'           | '(SMRR1206AW)'                 | '0'       | ''      | '1/2W'   | 'DISCRETE' | 'RES CHIP 0 1/2W (1206)EF'                         | 'CHIPR1206'    | ''          | ''            | '20180221'
 '0'          | ''        | '1/2W'   | '1206LF'  | 'EMPTY'  | 'CS00007T200'(!)        = 'End of Design' | 'Comp-Approve'     | 'CS00007T200'           | 'R1206XI'           | '(SMRR1206AW)'                 | '0'       | ''      | '1/2W'   | 'IO'       | 'RES CHIP 0 1/2W (1206)EF'                         | 'CHIPR1206'    | ''          | ''            | '20180221'
 '51.1'       | '1%'      | '1/16W'  | '0402LF'  | 'CHIP'   | 'CS05112FB05'(!)        = 'End of Design' | 'Comp-Approve'     | 'CS05112FB05'           | 'R0402'             | '(R0402-0201)'                 | '51.1'    | '1%'    | '1/16W'  | 'DISCRETE' | 'RES CHIP 51.1 1/16W +-1%(0402)EF'                 | 'CHIPR0402'    | ''          | ''            | '20180221'
 '51.1'       | '1%'      | '1/16W'  | '0402LF'  | 'EMPTY'  | 'CS05112FB05'(!)        = 'End of Design' | 'Comp-Approve'     | 'CS05112FB05'           | 'R0402'             | '(R0402-0201)'                 | '51.1'    | '1%'    | '1/16W'  | 'IO'       | 'RES CHIP 51.1 1/16W +-1%(0402)EF'                 | 'CHIPR0402'    | ''          | ''            | '20180221'
 '1'          | '1%'      | '1/16W'  | '0402LF'  | 'CHIP'   | 'CS-1002FB04'(!)        = 'End of Design' | 'Comp-Approve'     | 'CS-1002FB04'           | 'R0402'             | '(R0402-0201)'                 | '1'       | '1%'    | '1/16W'  | 'DISCRETE' | 'RES CHIP 1 1/16W +-1%(0402)EF'                    | 'CHIPR0402'    | ''          | ''            | '20180221'
 '1'          | '1%'      | '1/16W'  | '0402LF'  | 'EMPTY'  | 'CS-1002FB04'(!)        = 'End of Design' | 'Comp-Approve'     | 'CS-1002FB04'           | 'R0402'             | '(R0402-0201)'                 | '1'       | '1%'    | '1/16W'  | 'IO'       | 'RES CHIP 1 1/16W +-1%(0402)EF'                    | 'CHIPR0402'    | ''          | ''            | '20180221'
 '4.7'        | '5%'      | '1/16W'  | '0402LF'  | 'CHIP'   | 'CS-4702JB29'(!)        = 'End of Design' | 'Comp-Approve'     | 'CS-4702JB29'           | 'R0402'             | '(R0402-0201)'                 | '4.7'     | '5%'    | '1/16W'  | 'DISCRETE' | 'RES CHIP 4.7 1/16W +-5% (0402)'                   | 'CHIPR0402'    | ''          | ''            | '20180305'
 '4.7'        | '5%'      | '1/16W'  | '0402LF'  | 'EMPTY'  | 'CS-4702JB29'(!)        = 'End of Design' | 'Comp-Approve'     | 'CS-4702JB29'           | 'R0402'             | '(R0402-0201)'                 | '4.7'     | '5%'    | '1/16W'  | 'IO'       | 'RES CHIP 4.7 1/16W +-5% (0402)'                   | 'CHIPR0402'    | ''          | ''            | '20180305'
 '8.66K'      | '1%'      | '1/10W'  | '0603LF'  | 'CHIP'   | 'CS28663F911'(!)        = ''              | ''                 | 'CS28663F911'           | 'R0603'             | '(SMR0603AW)'                  | '8.66K'   | '1%'    | '1/10W'  | 'DISCRETE' | 'RES CHIP 8.66K 1/10W +-1% (0603)'                 | 'CHIP0603'     | ''          | ''            | '20180313'
 '8.66K'      | '1%'      | '1/10W'  | '0603LF'  | 'EMPTY'  | 'CS28663F911'(!)        = ''              | ''                 | 'CS28663F911'           | 'R0603'             | '(SMR0603AW)'                  | '8.66K'   | '1%'    | '1/10W'  | 'IO'       | 'RES CHIP 8.66K 1/10W +-1% (0603)'                 | 'CHIP0603'     | ''          | ''            | '20180313'
 '11.2K'      | '1%'      | '1/16W'  | '0402LF'  | 'CHIP'   | 'CS31122FB11'(!)        = 'End of Design' | 'Comp-Approve'     | 'CS31122FB11'           | 'R0402'             | '(R0402-0201)'                 | '11.2K'   | '1%'    | '1/16W'  | 'DISCRETE' | 'RES CHIP 11.2K 1/16W +-1% (0402)'                 | 'CHIP0402'     | ''          | ''            | '20180313'
 '11.2K'      | '1%'      | '1/16W'  | '0402LF'  | 'EMPTY'  | 'CS31122FB11'(!)        = 'End of Design' | 'Comp-Approve'     | 'CS31122FB11'           | 'R0402'             | '(R0402-0201)'                 | '11.2K'   | '1%'    | '1/16W'  | 'IO'       | 'RES CHIP 11.2K 1/16W +-1% (0402)'                 | 'CHIP0402'     | ''          | ''            | '20180313'
 '40.2K'      | '1%'      | '1/10W'  | '0603LF ' | 'CHIP'   | 'CS34023F911'(!)        = ''              | ''                 | 'CS34023F911'           | 'R0603'             | '(SMR0603AW)'                  | '40.2K'   | '1%'    | '1/10W'  | 'DISCRETE' | 'RESISTOR CHIP 40.2K 1/10W +-1%(0603)'             | 'CHIPR0603'    | ''          | ''            | '20180319'
 '40.2K'      | '1%'      | '1/10W'  | '0603LF ' | 'EMPTY'  | 'CS34023F911'(!)        = ''              | ''                 | 'CS34023F911'           | 'R0603'             | '(SMR0603AW)'                  | '40.2K'   | '1%'    | '1/10W'  | 'IO'       | 'RESISTOR CHIP 40.2K 1/10W +-1%(0603)'             | 'CHIPR0603'    | ''          | ''            | '20180319'
 '562'        | '1%'      | '1/16W'  | '0402LF'  | 'CHIP'   | 'CS15622FB16'(!)        = 'End of Design' | 'Comp-Approve'     | 'CS15622FB16'           | 'R0402'             | '(R0402-0201)'                 | '562'     | '1%'    | '1/16W'  | 'DISCRETE' | 'RES CHIP 562 1/16W +-1% (0402)'                   | 'CHIPR0402'    | ''          | ''            | '20180328'
 '562'        | '1%'      | '1/16W'  | '0402LF'  | 'EMPTY'  | 'CS15622FB16'(!)        = 'End of Design' | 'Comp-Approve'     | 'CS15622FB16'           | 'R0402'             | '(R0402-0201)'                 | '562'     | '1%'    | '1/16W'  | 'IO'       | 'RES CHIP 562 1/16W +-1% (0402)'                   | 'CHIPR0402'    | ''          | ''            | '20180328'
 '62K'        | '1%'      | '1/16W'  | '0402LF'  | 'CHIP'   | 'CS36202FB19'(!)        = 'End of Design' | 'Comp-Approve'     | 'CS36202FB19'           | 'R0402'             | '(R0402-0201)'                 | '62K'     | '1%'    | '1/16W'  | 'DISCRETE' | 'RES CHIP 62K 1/16W +-1%(0402)'                    | 'CHIPR0402'    | ''          | ''            | '20180316'
 '62K'        | '1%'      | '1/16W'  | '0402LF'  | 'EMPTY'  | 'CS36202FB19'(!)        = 'End of Design' | 'Comp-Approve'     | 'CS36202FB19'           | 'R0402'             | '(R0402-0201)'                 | '62K'     | '1%'    | '1/16W'  | 'IO'       | 'RES CHIP 62K 1/16W +-1%(0402)'                    | 'CHIPR0402'    | ''          | ''            | '20180316'
 '78.7K'      | '1%'      | '1/16W'  | '0402LF'  | 'CHIP'   | 'CS37872FB15'(!)        = 'End of Design' | 'Comp-Approve'     | 'CS37872FB15'           | 'R0402'             | '(R0402-0201)'                 | '78.7K'   | '1%'    | '1/16W'  | 'DISCRETE' | 'RES CHIP 78.7K 1/16W +-1%(0402)'                  | 'CHIPR0402'    | ''          | ''            | '20180402'
 '78.7K'      | '1%'      | '1/16W'  | '0402LF'  | 'EMPTY'  | 'CS37872FB15'(!)        = 'End of Design' | 'Comp-Approve'     | 'CS37872FB15'           | 'R0402'             | '(R0402-0201)'                 | '78.7K'   | '1%'    | '1/16W'  | 'IO'       | 'RES CHIP 78.7K 1/16W +-1%(0402)'                  | 'CHIPR0402'    | ''          | ''            | '20180402'
 '267K'       | '0.1%'    | '1/16W'  | '0402LF'  | 'CHIP'   | 'CS42672BB00'(!)        = ''              | ''                 | 'CS42672BB00'           | 'R0402'             | '(R0402-0201)'                 | '267K'    | '0.1%'  | '1/16W'  | 'DISCRETE' | 'RES CHIP 267K 1/16W +-0.1%(0402)'                 | 'CHIPR0402'    | ''          | ''            | '20180418'
 '267K'       | '0.1%'    | '1/16W'  | '0402LF'  | 'EMPTY'  | 'CS42672BB00'(!)        = ''              | ''                 | 'CS42672BB00'           | 'R0402'             | '(R0402-0201)'                 | '267K'    | '0.1%'  | '1/16W'  | 'IO'       | 'RES CHIP 267K 1/16W +-0.1%(0402)'                 | 'CHIPR0402'    | ''          | ''            | '20180418'
 '549'        | '1%'      | '1/4W'   | '1206LF'  | 'CHIP'   | 'CS15496F200'(!)        = ''              | ''                 | 'CS15496F200'           | 'R1206XF'           | '(SMR1206AW)'                  | '549'     | '1%'    | '1/4W'   | 'DISCRETE' | 'RES CHIP 549 1/4W 1%(1206)'                       | 'CHIPR1206'    | ''          | ''            | '20180418'
 '549'        | '1%'      | '1/4W'   | '1206LF'  | 'EMPTY'  | 'CS15496F200'(!)        = ''              | ''                 | 'CS15496F200'           | 'R1206XF'           | '(SMR1206AW)'                  | '549'     | '1%'    | '1/4W'   | 'IO'       | 'RES CHIP 549 1/4W 1%(1206)'                       | 'CHIPR1206'    | ''          | ''            | '20180418'
 '243K'       | '1%'      | '1/16W'  | '0402LF'  | 'CHIP'   | 'CS42432FB02'(!)        = 'End of Design' | 'Comp-Approve'     | 'CS42432FB02'           | 'R0402'             | '(R0402-0201)'                 | '243K'    | '1%'    | '1/16W'  | 'DISCRETE' | 'RES CHIP 243K 1/16W +-1%(0402)'                   | 'CHIPR0402'    | ''          | ''            | '20180420'
 '243K'       | '1%'      | '1/16W'  | '0402LF'  | 'EMPTY'  | 'CS42432FB02'(!)        = 'End of Design' | 'Comp-Approve'     | 'CS42432FB02'           | 'R0402'             | '(R0402-0201)'                 | '243K'    | '1%'    | '1/16W'  | 'IO'       | 'RES CHIP 243K 1/16W +-1%(0402)'                   | 'CHIPR0402'    | ''          | ''            | '20180420'
 '147K'       | '1%'      | '1/8W'   | '0805LF'  | 'CHIP'   | 'CS41474FA00'(!)        = ''              | ''                 | 'CS41474FA00'           | 'R0805'             | '(SMR0805AW)'                  | '147K'    | '1%'    | '1/8W'   | 'DISCRETE' | 'RES CHIP 147K 1/8W +-1%(0805)'                    | 'CHIPR0805'    | ''          | ''            | '20180424'
 '147K'       | '1%'      | '1/8W'   | '0805LF'  | 'EMPTY'  | 'CS41474FA00'(!)        = ''              | ''                 | 'CS41474FA00'           | 'R0805'             | '(SMR0805AW)'                  | '147K'    | '1%'    | '1/8W'   | 'IO'       | 'RES CHIP 147K 1/8W +-1%(0805)'                    | 'CHIPR0805'    | ''          | ''            | '20180424'
 '1.54K'      | '1%'      | '1/16W'  | '0402LF'  | 'CHIP'   | 'TMP_QCS21542FB00'(!)   = 'End of Design' | 'Comp-Approve'     | 'CS21542FB00'           | 'R0402'             | '(R0402-0201)'                 | '1.54K'   | '1%'    | '1/16W'  | 'DISCRETE' | 'RES CHIP 1.54K 1/16W +-1%(0402)'                  | 'CHIP0402'     | ''          | ''            | ''        
 '1.54K'      | '1%'      | '1/16W'  | '0402LF'  | 'EMPTY'  | 'TMP_QCS21542FB00'(!)   = 'End of Design' | 'Comp-Approve'     | 'CS21542FB00'           | 'R0402'             | '(R0402-0201)'                 | '1.54K'   | '1%'    | '1/16W'  | 'IO'       | 'RES CHIP 1.54K 1/16W +-1%(0402)'                  | 'CHIP0402'     | ''          | ''            | ''        
 '6.19K'      | '1%'      | '1/16W'  | '0402LF'  | 'CHIP'   | 'TMP_QCS26192FB14'(!)   = 'End of Design' | 'Comp-Approve'     | 'CS26192FB14'           | 'R0402'             | '(R0402-0201)'                 | '6.19K'   | '1%'    | '1/16W'  | 'DISCRETE' | 'RES CHIP 6.19K 1/16W +-1%  (0402)'                | 'CHIP0402'     | ''          | ''            | ''        
 '6.19K'      | '1%'      | '1/16W'  | '0402LF'  | 'EMPTY'  | 'TMP_QCS26192FB14'(!)   = 'End of Design' | 'Comp-Approve'     | 'CS26192FB14'           | 'R0402'             | '(R0402-0201)'                 | '6.19K'   | '1%'    | '1/16W'  | 'IO'       | 'RES CHIP 6.19K 1/16W +-1%  (0402)'                | 'CHIP0402'     | ''          | ''            | ''        
 '47K'        | '1%'      | '1/16W'  | '0402LF'  | 'CHIP'   | 'TMP_QCS34702FB11'(!)   = 'End of Design' | 'Comp-Release Qty' | 'CS34702FB11'           | 'R0402'             | '(R0402-0201)'                 | '47K'     | '1%'    | '1/16W'  | 'DISCRETE' | 'RES CHIP 47K 1/16W +-1% (0402)'                   | 'CHIP0402'     | ''          | ''            | ''        
 '47K'        | '1%'      | '1/16W'  | '0402LF'  | 'EMPTY'  | 'TMP_QCS34702FB11'(!)   = 'End of Design' | 'Comp-Release Qty' | 'CS34702FB11'           | 'R0402'             | '(R0402-0201)'                 | '47K'     | '1%'    | '1/16W'  | 'IO'       | 'RES CHIP 47K 1/16W +-1% (0402)'                   | 'CHIP0402'     | ''          | ''            | ''        
 '10K'        | '5%'      | '1/16W'  | '0402LF'  | 'CHIP'   | 'TMP_QCS31002JB28'(!)   = 'End of Design' | 'Comp-Approve'     | 'CS31002JB28'           | 'R0402'             | '(R0402-0201)'                 | '10K'     | '5%'    | '1/16W'  | 'DISCRETE' | 'RES CHIP 10K 1/16W 5%(0402)'                      | 'CHIP0402'     | ''          | ''            | ''        
 '10K'        | '5%'      | '1/16W'  | '0402LF'  | 'EMPTY'  | 'TMP_QCS31002JB28'(!)   = 'End of Design' | 'Comp-Approve'     | 'CS31002JB28'           | 'R0402'             | '(R0402-0201)'                 | '10K'     | '5%'    | '1/16W'  | 'IO'       | 'RES CHIP 10K 1/16W 5%(0402)'                      | 'CHIP0402'     | ''          | ''            | ''        
 '1K'         | '1%'      | '1/16W'  | '0402LF'  | 'CHIP'   | 'TMP_QCS21002FB24'(!)   = 'End of Design' | 'Comp-Approve'     | 'CS21002FB24'           | 'R0402'             | '(R0402-0201)'                 | '1K'      | '1%'    | '1/16W'  | 'DISCRETE' | 'RES CHIP 1K 1/16W +-1% (0402)'                    | 'CHIP0402'     | ''          | ''            | ''        
 '1K'         | '1%'      | '1/16W'  | '0402LF'  | 'EMPTY'  | 'TMP_QCS21002FB24'(!)   = 'End of Design' | 'Comp-Approve'     | 'CS21002FB24'           | 'R0402'             | '(R0402-0201)'                 | '1K'      | '1%'    | '1/16W'  | 'IO'       | 'RES CHIP 1K 1/16W +-1% (0402)'                    | 'CHIP0402'     | ''          | ''            | ''        
 '0'          | '5%'      | '1/10W'  | '0603'    | 'CHIP'   | 'TMP_QCS00003J951'(!)   = ''              | ''                 | 'CS00003J951'           | 'R0603'             | '(SMR0603AW)'                  | '0'       | '5%'    | '1/10W'  | 'DISCRETE' | 'RESISTOR CHIP 0 1/10W+-5%(0603)'                  | 'CHIP0603'     | ''          | ''            | ''        
 '0'          | '5%'      | '1/10W'  | '0603'    | 'EMPTY'  | 'TMP_QCS00003J951'(!)   = ''              | ''                 | 'CS00003J951'           | 'R0603'             | '(SMR0603AW)'                  | '0'       | '5%'    | '1/10W'  | 'IO'       | 'RESISTOR CHIP 0 1/10W+-5%(0603)'                  | 'CHIP0603'     | ''          | ''            | ''        
 '3.4M'       | '1%'      | '1/8W'   | '0805LF'  | 'CHIP'   | 'CS53404FA00'(!)        = ''              | ''                 | 'CS53404FA00'           | 'R0805'             | '(SMR0805AW)'                  | '3.4M'    | '1%'    | '1/8W'   | 'DISCRETE' | 'RES CHIP 3.4M 1/8W +-1%(0805)'                    | 'CHIPR0805'    | ''          | ''            | '20180502'
 '3.4M'       | '1%'      | '1/8W'   | '0805LF'  | 'EMPTY'  | 'CS53404FA00'(!)        = ''              | ''                 | 'CS53404FA00'           | 'R0805'             | '(SMR0805AW)'                  | '3.4M'    | '1%'    | '1/8W'   | 'IO'       | 'RES CHIP 3.4M 1/8W +-1%(0805)'                    | 'CHIPR0805'    | ''          | ''            | '20180502'
 '0.006'      | '1%'      | '1W'     | '1206LF'  | 'CHIP'   | 'CS+0068F200'(!)        = ''              | ''                 | 'CS+0068F200'           | 'R1206XI_H18'       | '(SMR1206AW)'                  | '0.006'   | '1%'    | '1W'     | 'DISCRETE' | 'RES CHIP 0.006 1W +-1%(1206)EF'                   | 'CHIPR1206'    | ''          | ''            | '20180514'
 '0.006'      | '1%'      | '1W'     | '1206LF'  | 'EMPTY'  | 'CS+0068F200'(!)        = ''              | ''                 | 'CS+0068F200'           | 'R1206XI_H18'       | '(SMR1206AW)'                  | '0.006'   | '1%'    | '1W'     | 'IO'       | 'RES CHIP 0.006 1W +-1%(1206)EF'                   | 'CHIPR1206'    | ''          | ''            | '20180514'
 '1.47M'      | '1%'      | '1/8W'   | '0805LF'  | 'CHIP'   | 'CS51474FA00'(!)        = ''              | ''                 | 'CS51474FA00'           | 'R0805'             | '(SMR0805AW)'                  | '1.47M'   | '1%'    | '1/8W'   | 'DISCRETE' | 'RES CHIP 1.47M 1/8W +-1%(0805)'                   | 'CHIPR0805'    | ''          | ''            | '20180514'
 '1.47M'      | '1%'      | '1/8W'   | '0805LF'  | 'EMPTY'  | 'CS51474FA00'(!)        = ''              | ''                 | 'CS51474FA00'           | 'R0805'             | '(SMR0805AW)'                  | '1.47M'   | '1%'    | '1/8W'   | 'IO'       | 'RES CHIP 1.47M 1/8W +-1%(0805)'                   | 'CHIPR0805'    | ''          | ''            | '20180514'
 '2.05M'      | '1%'      | '1/8W'   | '0805LF'  | 'CHIP'   | 'CS52054FA00'(!)        = ''              | ''                 | 'CS52054FA00'           | 'R0805'             | '(SMR0805AW)'                  | '2.05M'   | '1%'    | '1/8W'   | 'DISCRETE' | 'RES CHIP 2.05M 1/8W +-1%(0805)'                   | 'CHIPR0805'    | ''          | ''            | '20180515'
 '2.05M'      | '1%'      | '1/8W'   | '0805LF'  | 'EMPTY'  | 'CS52054FA00'(!)        = ''              | ''                 | 'CS52054FA00'           | 'R0805'             | '(SMR0805AW)'                  | '2.05M'   | '1%'    | '1/8W'   | 'IO'       | 'RES CHIP 2.05M 1/8W +-1%(0805)'                   | 'CHIPR0805'    | ''          | ''            | '20180515'
 '30.9K'      | '1%'      | '1/16W'  | '0402LF'  | 'CHIP'   | 'CS33092FB06'(!)        = 'End of Design' | 'Comp-Approve'     | 'CS33092FB06'           | 'R0402'             | '(R0402-0201)'                 | '30.9K'   | '1%'    | '1/16W'  | 'DISCRETE' | 'RES CHIP 30.9K 1/16W +-1%(0402)'                  | 'CHIPR0402'    | ''          | ''            | '20130510'
 '30.9K'      | '1%'      | '1/16W'  | '0402LF'  | 'EMPTY'  | 'CS33092FB06'(!)        = 'End of Design' | 'Comp-Approve'     | 'CS33092FB06'           | 'R0402'             | '(R0402-0201)'                 | '30.9K'   | '1%'    | '1/16W'  | 'IO'       | 'RES CHIP 30.9K 1/16W +-1%(0402)'                  | 'CHIPR0402'    | ''          | ''            | '20130510'
 '66.5K'      | '1%'      | '1/16W'  | '0402LF'  | 'CHIP'   | 'TMP_QCS36652FB16'(!)   = 'End of Design' | 'Comp-Approve'     | 'CS36652FB16'           | 'R0402'             | '(R0402-0201)'                 | '66.5K'   | '1%'    | '1/16W'  | 'DISCRETE' | 'RES CHIP 66.5K 1/16W +-1%(0402)'                  | 'CHIP0402'     | ''          | ''            | ''        
 '66.5K'      | '1%'      | '1/16W'  | '0402LF'  | 'EMPTY'  | 'TMP_QCS36652FB16'(!)   = 'End of Design' | 'Comp-Approve'     | 'CS36652FB16'           | 'R0402'             | '(R0402-0201)'                 | '66.5K'   | '1%'    | '1/16W'  | 'IO'       | 'RES CHIP 66.5K 1/16W +-1%(0402)'                  | 'CHIP0402'     | ''          | ''            | ''        
 '7.87'       | '1%'      | '1/16W'  | '0402LF'  | 'CHIP'   | 'CS-7872FB00'(!)        = ''              | ''                 | 'CS-7872FB00'           | 'R0402'             | '(R0402-0201)'                 | '7.87'    | '1%'    | '1/16W'  | 'DISCRETE' | 'RES CHIP 7.87 1/16W +-1%(0402)'                   | 'CHIPR0402'    | ''          | ''            | '20180522'
 '7.87'       | '1%'      | '1/16W'  | '0402LF'  | 'EMPTY'  | 'CS-7872FB00'(!)        = ''              | ''                 | 'CS-7872FB00'           | 'R0402'             | '(R0402-0201)'                 | '7.87'    | '1%'    | '1/16W'  | 'IO'       | 'RES CHIP 7.87 1/16W +-1%(0402)'                   | 'CHIPR0402'    | ''          | ''            | '20180522'
 '0.5'        | '1%'      | '2W'     | '2512LF'  | 'CHIP'   | 'CS+500AFR00'(!)        = ''              | ''                 | 'CS+500AFR00'           | 'R2512XA'           | '(SMR2512AW)'                  | '0.5'     | '1%'    | '2W'     | 'DISCRETE' | 'RES CHIP 0.5 2W +-1%(2512)'                       | 'CHIPR2512'    | ''          | ''            | '20180523'
 '0.5'        | '1%'      | '2W'     | '2512LF'  | 'EMPTY'  | 'CS+500AFR00'(!)        = ''              | ''                 | 'CS+500AFR00'           | 'R2512XA'           | '(SMR2512AW)'                  | '0.5'     | '1%'    | '2W'     | 'IO'       | 'RES CHIP 0.5 2W +-1%(2512)'                       | 'CHIPR2512'    | ''          | ''            | '20180523'
 '1.5'        | '1%'      | '1/8W'   | '0402LF'  | 'CHIP'   | 'CS-1504FB00'(!)        = ''              | ''                 | 'CS-1504FB00'           | 'R0402'             | '(R0402-0201)'                 | '1.5'     | '1%'    | '1/8W'   | 'DISCRETE' | 'RES CHIP 1.5 1/8W +-1%(0402)'                     | 'CHIPR0402'    | ''          | ''            | '20180523'
 '1.5'        | '1%'      | '1/8W'   | '0402LF'  | 'EMPTY'  | 'CS-1504FB00'(!)        = ''              | ''                 | 'CS-1504FB00'           | 'R0402'             | '(R0402-0201)'                 | '1.5'     | '1%'    | '1/8W'   | 'IO'       | 'RES CHIP 1.5 1/8W +-1%(0402)'                     | 'CHIPR0402'    | ''          | ''            | '20180523'
 '1'          | '1%'      | '1/8W'   | '0402LF'  | 'CHIP'   | 'CS-1004FB00'(!)        = ''              | ''                 | 'CS-1004FB00'           | 'R0402'             | '(R0402-0201)'                 | '1'       | '1%'    | '1/8W'   | 'DISCRETE' | 'RES CHIP 1 1/8W +-1%(0402)'                       | 'CHIPR0402'    | ''          | ''            | '20180523'
 '1'          | '1%'      | '1/8W'   | '0402LF'  | 'EMPTY'  | 'CS-1004FB00'(!)        = ''              | ''                 | 'CS-1004FB00'           | 'R0402'             | '(R0402-0201)'                 | '1'       | '1%'    | '1/8W'   | 'IO'       | 'RES CHIP 1 1/8W +-1%(0402)'                       | 'CHIPR0402'    | ''          | ''            | '20180523'
 '365K'       | '1%'      | '1/16W'  | '0402LF'  | 'CHIP'   | 'CS43652FB10'(!)        = 'End of Design' | 'Comp-Approve'     | 'CS43652FB10'           | 'R0402'             | '(R0402-0201)'                 | '365K'    | '1%'    | '1/16W'  | 'DISCRETE' | 'RES CHIP 365K 1/16W +-1%(0402)'                   | 'CHIPR0402'    | ''          | ''            | '20180704'
 '365K'       | '1%'      | '1/16W'  | '0402LF'  | 'EMPTY'  | 'CS43652FB10'(!)        = 'End of Design' | 'Comp-Approve'     | 'CS43652FB10'           | 'R0402'             | '(R0402-0201)'                 | '365K'    | '1%'    | '1/16W'  | 'IO'       | 'RES CHIP 365K 1/16W +-1%(0402)'                   | 'CHIPR0402'    | ''          | ''            | '20180704'
 '100K'       | '0.1%'    | '1/8W'   | '0805LF'  | 'CHIP'   | 'CS41004BA01'(!)        = ''              | ''                 | 'CS41004BA01'           | 'R0805'             | '(SMR0805AW)'                  | '100K'    | '0.1%'  | '1/8W'   | 'DISCRETE' | 'RES CHIP 100K 1/8W +-0.1%(0805)'                  | 'CHIPR0805'    | ''          | ''            | '20180704'
 '100K'       | '0.1%'    | '1/8W'   | '0805LF'  | 'EMPTY'  | 'CS41004BA01'(!)        = ''              | ''                 | 'CS41004BA01'           | 'R0805'             | '(SMR0805AW)'                  | '100K'    | '0.1%'  | '1/8W'   | 'IO'       | 'RES CHIP 100K 1/8W +-0.1%(0805)'                  | 'CHIPR0805'    | ''          | ''            | '20180704'
 '100K'       | '1%'      | '1/8W'   | '0805LF'  | 'CHIP'   | 'CS41004FA00'(!)        = 'End of Design' | 'Comp-Approve'     | 'CS41004FA00'           | 'R0805'             | '(SMR0805AW)'                  | '100K'    | '1%'    | '1/8W'   | 'DISCRETE' | 'RESISTOR CHIP 100K 1/8W+-1%(0805)'                | 'CHIPR0805'    | ''          | ''            | '20170927'
 '100K'       | '1%'      | '1/8W'   | '0805LF'  | 'EMPTY'  | 'CS41004FA00'(!)        = 'End of Design' | 'Comp-Approve'     | 'CS41004FA00'           | 'R0805'             | '(SMR0805AW)'                  | '100K'    | '1%'    | '1/8W'   | 'IO'       | 'RESISTOR CHIP 100K 1/8W+-1%(0805)'                | 'CHIPR0805'    | ''          | ''            | '20170927'
 '0'          | '1%'      | '1/16W'  | '0402LF'  | 'CHIP'   | 'TMP_QCS00002FB00'(!)   = 'End of Design' | 'Comp-Approve'     | 'CS00002FB00'           | 'R0402'             | '(R0402-0201)'                 | '0'       | '1%'    | '1/16W'  | 'DISCRETE' | 'RES CHIP 0 1/16W +-1%(0402)'                      | 'CHIP0402'     | ''          | ''            | ''        
 '0'          | '1%'      | '1/16W'  | '0402LF'  | 'EMPTY'  | 'TMP_QCS00002FB00'(!)   = 'End of Design' | 'Comp-Approve'     | 'CS00002FB00'           | 'R0402'             | '(R0402-0201)'                 | '0'       | '1%'    | '1/16W'  | 'IO'       | 'RES CHIP 0 1/16W +-1%(0402)'                      | 'CHIP0402'     | ''          | ''            | ''        
 '549K'       | '1%'      | '1/16W'  | '0402LF'  | 'CHIP'   | 'CS45492FB08'(!)        = ''              | ''                 | 'CS45492FB08'           | 'R0402'             | '(R0402-0201)'                 | '549K'    | '1%'    | '1/16W'  | 'DISCRETE' | 'RES CHIP 549K 1/16W +-1%(0402)'                   | 'CHIPR0402'    | ''          | ''            | '20180709'
 '549K'       | '1%'      | '1/16W'  | '0402LF'  | 'EMPTY'  | 'CS45492FB08'(!)        = ''              | ''                 | 'CS45492FB08'           | 'R0402'             | '(R0402-0201)'                 | '549K'    | '1%'    | '1/16W'  | 'IO'       | 'RES CHIP 549K 1/16W +-1%(0402)'                   | 'CHIPR0402'    | ''          | ''            | '20180709'
 '1.5K'       | '5%'      | '1/8W'   | '0805LF'  | 'CHIP'   | 'CS21504JA02'(!)        = ''              | ''                 | 'CS21504JA02'           | 'R0805_H26'         | '(SMR0805AW)'                  | '1.5K'    | '5%'    | '1/8W'   | 'DISCRETE' | 'RES CHIP 1.5K 1/8W +-5%(0805)'                    | 'CHIPR0805'    | ''          | ''            | '20180720'
 '1.5K'       | '5%'      | '1/8W'   | '0805LF'  | 'EMPTY'  | 'CS21504JA02'(!)        = ''              | ''                 | 'CS21504JA02'           | 'R0805_H26'         | '(SMR0805AW)'                  | '1.5K'    | '5%'    | '1/8W'   | 'IO'       | 'RES CHIP 1.5K 1/8W +-5%(0805)'                    | 'CHIPR0805'    | ''          | ''            | '20180720'
 '15'         | '5%'      | '1/16W'  | '0402LF'  | 'CHIP'   | 'CS01502JB12'(!)        = 'End of Design' | 'Comp-Approve'     | 'CS01502JB12'           | 'R0402'             | '(R0402-0201)'                 | '15'      | '5%'    | '1/16W'  | 'DISCRETE' | 'RES CHIP 15 1/16W +-5%(0402)L-F'                  | 'CHIPR0402'    | ''          | ''            | '20180720'
 '15'         | '5%'      | '1/16W'  | '0402LF'  | 'EMPTY'  | 'CS01502JB12'(!)        = 'End of Design' | 'Comp-Approve'     | 'CS01502JB12'           | 'R0402'             | '(R0402-0201)'                 | '15'      | '5%'    | '1/16W'  | 'IO'       | 'RES CHIP 15 1/16W +-5%(0402)L-F'                  | 'CHIPR0402'    | ''          | ''            | '20180720'
 '95.3K'      | '1%'      | '1/4W'   | '1206LF'  | 'CHIP'   | 'CS39536F200'(!)        = ''              | ''                 | 'CS39536F200'           | 'R1206XJ'           | '(SMR1206AW)'                  | '95.3K'   | '1%'    | '1/4W'   | 'DISCRETE' | 'RES CHIP 95.3K 1/4W +-1%(1206)'                   | 'CHIPR1206'    | ''          | ''            | '20180725'
 '95.3K'      | '1%'      | '1/4W'   | '1206LF'  | 'EMPTY'  | 'CS39536F200'(!)        = ''              | ''                 | 'CS39536F200'           | 'R1206XJ'           | '(SMR1206AW)'                  | '95.3K'   | '1%'    | '1/4W'   | 'IO'       | 'RES CHIP 95.3K 1/4W +-1%(1206)'                   | 'CHIPR1206'    | ''          | ''            | '20180725'
 '100'        | '1%'      | '1/8W'   | '0805LF'  | 'CHIP'   | 'CS11004FA34'(!)        = ''              | ''                 | 'CS11004FA34'           | 'R0805_H26'         | '(SMR0805AW)'                  | '100'     | '1%'    | '1/8W'   | 'DISCRETE' | 'RES CHIP 100 1/8W +-1%(0805)'                     | 'CHIPR0805'    | ''          | ''            | '20180802'
 '100'        | '1%'      | '1/8W'   | '0805LF'  | 'EMPTY'  | 'CS11004FA34'(!)        = ''              | ''                 | 'CS11004FA34'           | 'R0805_H26'         | '(SMR0805AW)'                  | '100'     | '1%'    | '1/8W'   | 'IO'       | 'RES CHIP 100 1/8W +-1%(0805)'                     | 'CHIPR0805'    | ''          | ''            | '20180802'
 '10'         | '5%'      | '1/20W'  | '0201LF'  | 'CHIP'   | 'CS01001JE11'(!)        = ''              | ''                 | 'CS01001JE11'           | 'R0201'             | '(SMR0201AW)'                  | '10'      | '5%'    | '1/20W'  | 'DISCRETE' | 'RES CHIP 10(1/20W,+-5%,0201)'                     | 'CHIPR0201'    | ''          | ''            | '20180802'
 '10'         | '5%'      | '1/20W'  | '0201LF'  | 'EMPTY'  | 'CS01001JE11'(!)        = ''              | ''                 | 'CS01001JE11'           | 'R0201'             | '(SMR0201AW)'                  | '10'      | '5%'    | '1/20W'  | 'IO'       | 'RES CHIP 10(1/20W,+-5%,0201)'                     | 'CHIPR0201'    | ''          | ''            | '20180802'
 '22.0'       | '1%'      | '1/20W'  | '0201LF'  | 'CHIP'   | 'CS02201FE00'(!)        = ''              | ''                 | 'CS02201FE00'           | 'R0201'             | '(SMR0201AW)'                  | '22.0'    | '1%'    | '1/20W'  | 'DISCRETE' | 'RES CHIP 22.0 1/20W +-1%(0201)'                   | 'CHIPR0201'    | ''          | ''            | '20150324'
 '22.0'       | '1%'      | '1/20W'  | '0201LF'  | 'EMPTY'  | 'CS02201FE00'(!)        = ''              | ''                 | 'CS02201FE00'           | 'R0201'             | '(SMR0201AW)'                  | '22.0'    | '1%'    | '1/20W'  | 'IO'       | 'RES CHIP 22.0 1/20W +-1%(0201)'                   | 'CHIPR0201'    | ''          | ''            | '20150324'
 '60.4'       | '1%'      | '1/20W'  | '0201LF'  | 'CHIP'   | 'CS06041FE00'(!)        = ''              | ''                 | 'CS06041FE00'           | 'R0201'             | '(SMR0201AW)'                  | '60.4'    | '1%'    | '1/20W'  | 'DISCRETE' | 'RES CHIP 60.4 1/20W,+-1%(0201)'                   | 'CHIPR0201'    | ''          | ''            | '20120209'
 '60.4'       | '1%'      | '1/20W'  | '0201LF'  | 'EMPTY'  | 'CS06041FE00'(!)        = ''              | ''                 | 'CS06041FE00'           | 'R0201'             | '(SMR0201AW)'                  | '60.4'    | '1%'    | '1/20W'  | 'IO'       | 'RES CHIP 60.4 1/20W,+-1%(0201)'                   | 'CHIPR0201'    | ''          | ''            | '20120209'
 '150'        | '1%'      | '1/20W'  | '0201LF'  | 'CHIP'   | 'CS11501FE01'(!)        = ''              | ''                 | 'CS11501FE01'           | 'R0201'             | '(SMR0201AW)'                  | '150'     | '1%'    | '1/20W'  | 'DISCRETE' | 'RES CHIP 150 1/20W +-1%(0201)'                    | 'CHIPR0201'    | ''          | ''            | '20170825'
 '150'        | '1%'      | '1/20W'  | '0201LF'  | 'EMPTY'  | 'CS11501FE01'(!)        = ''              | ''                 | 'CS11501FE01'           | 'R0201'             | '(SMR0201AW)'                  | '150'     | '1%'    | '1/20W'  | 'IO'       | 'RES CHIP 150 1/20W +-1%(0201)'                    | 'CHIPR0201'    | ''          | ''            | '20170825'
 '22.1'       | '1%'      | '1/20W'  | '0201LF'  | 'CHIP'   | 'CS02211FE01'(!)        = ''              | ''                 | 'CS02211FE01'           | 'R0201'             | '(SMR0201AW)'                  | '22.1'    | '1%'    | '1/20W'  | 'DISCRETE' | 'RES CHIP 22.1 1/20W(+-1%,0201)'                   | 'CHIPR0201'    | ''          | ''            | '20180803'
 '22.1'       | '1%'      | '1/20W'  | '0201LF'  | 'EMPTY'  | 'CS02211FE01'(!)        = ''              | ''                 | 'CS02211FE01'           | 'R0201'             | '(SMR0201AW)'                  | '22.1'    | '1%'    | '1/20W'  | 'IO'       | 'RES CHIP 22.1 1/20W(+-1%,0201)'                   | 'CHIPR0201'    | ''          | ''            | '20180803'
 '33'         | '5%'      | '1/20W'  | '0201LF'  | 'CHIP'   | 'CS03301JE09'(!)        = ''              | ''                 | 'CS03301JE09'           | 'R0201'             | '(SMR0201AW)'                  | '33'      | '5%'    | '1/20W'  | 'DISCRETE' | 'RES CHIP 33 1/20W +-5%(0201)'                     | 'CHIPR0201'    | ''          | ''            | '20180803'
 '33'         | '5%'      | '1/20W'  | '0201LF'  | 'EMPTY'  | 'CS03301JE09'(!)        = ''              | ''                 | 'CS03301JE09'           | 'R0201'             | '(SMR0201AW)'                  | '33'      | '5%'    | '1/20W'  | 'IO'       | 'RES CHIP 33 1/20W +-5%(0201)'                     | 'CHIPR0201'    | ''          | ''            | '20180803'
 '33.2'       | '1%'      | '1/20W'  | '0201LF'  | 'CHIP'   | 'CS03321FE00'(!)        = ''              | ''                 | 'CS03321FE00'           | 'R0201'             | '(SMR0201AW)'                  | '33.2'    | '1%'    | '1/20W'  | 'DISCRETE' | 'RES CHIP 33.2 1/20W +-1%(0201)'                   | 'CHIPR0201'    | ''          | ''            | '20180803'
 '33.2'       | '1%'      | '1/20W'  | '0201LF'  | 'EMPTY'  | 'CS03321FE00'(!)        = ''              | ''                 | 'CS03321FE00'           | 'R0201'             | '(SMR0201AW)'                  | '33.2'    | '1%'    | '1/20W'  | 'IO'       | 'RES CHIP 33.2 1/20W +-1%(0201)'                   | 'CHIPR0201'    | ''          | ''            | '20180803'
 '75'         | '1%'      | '1/20W'  | '0201LF'  | 'CHIP'   | 'CS07501FE05'(!)        = ''              | ''                 | 'CS07501FE05'           | 'R0201'             | '(SMR0201AW)'                  | '75'      | '1%'    | '1/20W'  | 'DISCRETE' | 'RES CHIP 75 1/20W +-1%(0201)'                     | 'CHIPR0201'    | ''          | ''            | '20180803'
 '75'         | '1%'      | '1/20W'  | '0201LF'  | 'EMPTY'  | 'CS07501FE05'(!)        = ''              | ''                 | 'CS07501FE05'           | 'R0201'             | '(SMR0201AW)'                  | '75'      | '1%'    | '1/20W'  | 'IO'       | 'RES CHIP 75 1/20W +-1%(0201)'                     | 'CHIPR0201'    | ''          | ''            | '20180803'
 '120'        | '1%'      | '1/20W'  | '0201LF'  | 'CHIP'   | 'CS11201FE01'(!)        = 'End of Design' | 'Comp-Release Qty' | 'CS11201FE01'           | 'R0201'             | '(SMR0201AW)'                  | '120'     | '1%'    | '1/20W'  | 'DISCRETE' | 'RES CHIP 120 1/20W +-1%(0201)'                    | 'CHIPR0201'    | ''          | ''            | '20180803'
 '120'        | '1%'      | '1/20W'  | '0201LF'  | 'EMPTY'  | 'CS11201FE01'(!)        = 'End of Design' | 'Comp-Release Qty' | 'CS11201FE01'           | 'R0201'             | '(SMR0201AW)'                  | '120'     | '1%'    | '1/20W'  | 'IO'       | 'RES CHIP 120 1/20W +-1%(0201)'                    | 'CHIPR0201'    | ''          | ''            | '20180803'
 '220'        | '1%'      | '1/20W'  | '0201LF'  | 'CHIP'   | 'CS12201FE11'(!)        = 'End of Design' | 'Comp-Approve'     | 'CS12201FE11'           | 'R0201'             | '(SMR0201AW)'                  | '220'     | '1%'    | '1/20W'  | 'DISCRETE' | 'RES CHIP 220(1/20W,+-1%,0201)'                    | 'CHIPR0201'    | ''          | ''            | '20180803'
 '220'        | '1%'      | '1/20W'  | '0201LF'  | 'EMPTY'  | 'CS12201FE11'(!)        = 'End of Design' | 'Comp-Approve'     | 'CS12201FE11'           | 'R0201'             | '(SMR0201AW)'                  | '220'     | '1%'    | '1/20W'  | 'IO'       | 'RES CHIP 220(1/20W,+-1%,0201)'                    | 'CHIPR0201'    | ''          | ''            | '20180803'
 '221'        | '1%'      | '1/20W'  | '0201LF'  | 'CHIP'   | 'CS12211FE07'(!)        = ''              | ''                 | 'CS12211FE07'           | 'R0201'             | '(SMR0201AW)'                  | '221'     | '1%'    | '1/20W'  | 'DISCRETE' | 'RES CHIP 221 1/20W +-1%(0201)'                    | 'CHIPR0201'    | ''          | ''            | '20180803'
 '221'        | '1%'      | '1/20W'  | '0201LF'  | 'EMPTY'  | 'CS12211FE07'(!)        = ''              | ''                 | 'CS12211FE07'           | 'R0201'             | '(SMR0201AW)'                  | '221'     | '1%'    | '1/20W'  | 'IO'       | 'RES CHIP 221 1/20W +-1%(0201)'                    | 'CHIPR0201'    | ''          | ''            | '20180803'
 '300'        | '5%'      | '1/20W'  | '0201LF'  | 'CHIP'   | 'CS13001JE00'(!)        = ''              | ''                 | 'CS13001JE00'           | 'R0201'             | '(SMR0201AW)'                  | '300'     | '5%'    | '1/20W'  | 'DISCRETE' | 'RES CHIP 300 1/20W +-5%(0201)'                    | 'CHIPR0201'    | ''          | ''            | '20180803'
 '300'        | '5%'      | '1/20W'  | '0201LF'  | 'EMPTY'  | 'CS13001JE00'(!)        = ''              | ''                 | 'CS13001JE00'           | 'R0201'             | '(SMR0201AW)'                  | '300'     | '5%'    | '1/20W'  | 'IO'       | 'RES CHIP 300 1/20W +-5%(0201)'                    | 'CHIPR0201'    | ''          | ''            | '20180803'
 '330'        | '5%'      | '1/20W'  | '0201LF'  | 'CHIP'   | 'CS13301JE00'(!)        = ''              | ''                 | 'CS13301JE00'           | 'R0201'             | '(SMR0201AW)'                  | '330'     | '5%'    | '1/20W'  | 'DISCRETE' | 'RES CHIP 330 1/20W +-5%(0201)'                    | 'CHIPR0201'    | ''          | ''            | '20180803'
 '330'        | '5%'      | '1/20W'  | '0201LF'  | 'EMPTY'  | 'CS13301JE00'(!)        = ''              | ''                 | 'CS13301JE00'           | 'R0201'             | '(SMR0201AW)'                  | '330'     | '5%'    | '1/20W'  | 'IO'       | 'RES CHIP 330 1/20W +-5%(0201)'                    | 'CHIPR0201'    | ''          | ''            | '20180803'
 '332'        | '1%'      | '1/20W'  | '0201LF'  | 'CHIP'   | 'CS13321FE01'(!)        = ''              | ''                 | 'CS13321FE01'           | 'R0201'             | '(SMR0201AW)'                  | '332'     | '1%'    | '1/20W'  | 'DISCRETE' | 'RES CHIP 332 1/20W +-1%(0201)'                    | 'CHIPR0201'    | ''          | ''            | '20180803'
 '332'        | '1%'      | '1/20W'  | '0201LF'  | 'EMPTY'  | 'CS13321FE01'(!)        = ''              | ''                 | 'CS13321FE01'           | 'R0201'             | '(SMR0201AW)'                  | '332'     | '1%'    | '1/20W'  | 'IO'       | 'RES CHIP 332 1/20W +-1%(0201)'                    | 'CHIPR0201'    | ''          | ''            | '20180803'
 '475'        | '1%'      | '1/20W'  | '0201LF'  | 'CHIP'   | 'CS14751FE00'(!)        = ''              | ''                 | 'CS14751FE00'           | 'R0201'             | '(SMR0201AW)'                  | '475'     | '1%'    | '1/20W'  | 'DISCRETE' | 'RES CHIP 475 1/20W,+-1%(0201)'                    | 'CHIPR0201'    | ''          | ''            | '20180803'
 '475'        | '1%'      | '1/20W'  | '0201LF'  | 'EMPTY'  | 'CS14751FE00'(!)        = ''              | ''                 | 'CS14751FE00'           | 'R0201'             | '(SMR0201AW)'                  | '475'     | '1%'    | '1/20W'  | 'IO'       | 'RES CHIP 475 1/20W,+-1%(0201)'                    | 'CHIPR0201'    | ''          | ''            | '20180803'
 '680'        | '5%'      | '1/20W'  | '0201LF'  | 'CHIP'   | 'CS16801JE00'(!)        = ''              | ''                 | 'CS16801JE00'           | 'R0201'             | '(SMR0201AW)'                  | '680'     | '5%'    | '1/20W'  | 'DISCRETE' | 'RES CHIP 680 1/20W +-5%(0201)'                    | 'CHIPR0201'    | ''          | ''            | '20180803'
 '680'        | '5%'      | '1/20W'  | '0201LF'  | 'EMPTY'  | 'CS16801JE00'(!)        = ''              | ''                 | 'CS16801JE00'           | 'R0201'             | '(SMR0201AW)'                  | '680'     | '5%'    | '1/20W'  | 'IO'       | 'RES CHIP 680 1/20W +-5%(0201)'                    | 'CHIPR0201'    | ''          | ''            | '20180803'
 '1.5K'       | '1%'      | '1/20W'  | '0201LF'  | 'CHIP'   | 'CS21501FE01'(!)        = ''              | ''                 | 'CS21501FE01'           | 'R0201'             | '(SMR0201AW)'                  | '1.5K'    | '1%'    | '1/20W'  | 'DISCRETE' | 'RES CHIP 1.5K 1/20W +-1%(0201)'                   | 'CHIPR0201'    | ''          | ''            | '20180803'
 '1.5K'       | '1%'      | '1/20W'  | '0201LF'  | 'EMPTY'  | 'CS21501FE01'(!)        = ''              | ''                 | 'CS21501FE01'           | 'R0201'             | '(SMR0201AW)'                  | '1.5K'    | '1%'    | '1/20W'  | 'IO'       | 'RES CHIP 1.5K 1/20W +-1%(0201)'                   | 'CHIPR0201'    | ''          | ''            | '20180803'
 '2.2K'       | '5%'      | '1/20W'  | '0201LF'  | 'CHIP'   | 'CS22201JE00'(!)        = ''              | ''                 | 'CS22201JE00'           | 'R0201'             | '(SMR0201AW)'                  | '2.2K'    | '5%'    | '1/20W'  | 'DISCRETE' | 'RES CHIP 2.2K 1/20W +-5%(0201)'                   | 'CHIPR0201'    | ''          | ''            | '20180803'
 '2.2K'       | '5%'      | '1/20W'  | '0201LF'  | 'EMPTY'  | 'CS22201JE00'(!)        = ''              | ''                 | 'CS22201JE00'           | 'R0201'             | '(SMR0201AW)'                  | '2.2K'    | '5%'    | '1/20W'  | 'IO'       | 'RES CHIP 2.2K 1/20W +-5%(0201)'                   | 'CHIPR0201'    | ''          | ''            | '20180803'
 '2.21K'      | '1%'      | '1/20W'  | '0201LF'  | 'CHIP'   | 'CS22211FE09'(!)        = ''              | ''                 | 'CS22211FE09'           | 'R0201'             | '(SMR0201AW)'                  | '2.21K'   | '1%'    | '1/20W'  | 'DISCRETE' | 'RES CHIP 2.21K 1/20W +-1%(0201)'                  | 'CHIPR0201'    | ''          | ''            | '20180806'
 '2.21K'      | '1%'      | '1/20W'  | '0201LF'  | 'EMPTY'  | 'CS22211FE09'(!)        = ''              | ''                 | 'CS22211FE09'           | 'R0201'             | '(SMR0201AW)'                  | '2.21K'   | '1%'    | '1/20W'  | 'IO'       | 'RES CHIP 2.21K 1/20W +-1%(0201)'                  | 'CHIPR0201'    | ''          | ''            | '20180806'
 '2.2'        | '1%'      | '1/20W'  | '0201LF'  | 'CHIP'   | 'CS-2201FE01'(!)        = 'End of Design' | 'Comp-Approve'     | 'CS-2201FE01'           | 'R0201'             | '(SMR0201AW)'                  | '2.2'     | '1%'    | '1/20W'  | 'DISCRETE' | 'RES CHIP 2.2 1/20W +-1%(0201)'                    | 'CHIPR0201'    | ''          | ''            | '20180806'
 '2.2'        | '1%'      | '1/20W'  | '0201LF'  | 'EMPTY'  | 'CS-2201FE01'(!)        = 'End of Design' | 'Comp-Approve'     | 'CS-2201FE01'           | 'R0201'             | '(SMR0201AW)'                  | '2.2'     | '1%'    | '1/20W'  | 'IO'       | 'RES CHIP 2.2 1/20W +-1%(0201)'                    | 'CHIPR0201'    | ''          | ''            | '20180806'
 '24.9'       | '1%'      | '1/20W'  | '0201LF'  | 'CHIP'   | 'CS02491FE00'(!)        = ''              | ''                 | 'CS02491FE00'           | 'R0201'             | '(SMR0201AW)'                  | '24.9'    | '1%'    | '1/20W'  | 'DISCRETE' | 'RES CHIP 24.9 1/20W +-1%(0201)'                   | 'CHIPR0201'    | ''          | ''            | '20180806'
 '24.9'       | '1%'      | '1/20W'  | '0201LF'  | 'EMPTY'  | 'CS02491FE00'(!)        = ''              | ''                 | 'CS02491FE00'           | 'R0201'             | '(SMR0201AW)'                  | '24.9'    | '1%'    | '1/20W'  | 'IO'       | 'RES CHIP 24.9 1/20W +-1%(0201)'                   | 'CHIPR0201'    | ''          | ''            | '20180806'
 '27.4'       | '1%'      | '1/20W'  | '0201LF'  | 'CHIP'   | 'CS02741FE07'(!)        = ''              | ''                 | 'CS02741FE07'           | 'R0201'             | '(SMR0201AW)'                  | '27.4'    | '1%'    | '1/20W'  | 'DISCRETE' | 'RES CHIP 27.4 1/20W +-1%(0201)'                   | 'CHIPR0201'    | ''          | ''            | '20180806'
 '27.4'       | '1%'      | '1/20W'  | '0201LF'  | 'EMPTY'  | 'CS02741FE07'(!)        = ''              | ''                 | 'CS02741FE07'           | 'R0201'             | '(SMR0201AW)'                  | '27.4'    | '1%'    | '1/20W'  | 'IO'       | 'RES CHIP 27.4 1/20W +-1%(0201)'                   | 'CHIPR0201'    | ''          | ''            | '20180806'
 '113'        | '1%'      | '1/20W'  | '0201LF'  | 'CHIP'   | 'CS11131FE01'(!)        = ''              | ''                 | 'CS11131FE01'           | 'R0201'             | '(SMR0201AW)'                  | '113'     | '1%'    | '1/20W'  | 'DISCRETE' | 'RES CHIP 113(1/20W,+-1%,0201)'                    | 'CHIPR0201'    | ''          | ''            | '20180806'
 '113'        | '1%'      | '1/20W'  | '0201LF'  | 'EMPTY'  | 'CS11131FE01'(!)        = ''              | ''                 | 'CS11131FE01'           | 'R0201'             | '(SMR0201AW)'                  | '113'     | '1%'    | '1/20W'  | 'IO'       | 'RES CHIP 113(1/20W,+-1%,0201)'                    | 'CHIPR0201'    | ''          | ''            | '20180806'
 '130'        | '1%'      | '1/20W'  | '0201LF'  | 'CHIP'   | 'CS11301FE03'(!)        = ''              | ''                 | 'CS11301FE03'           | 'R0201'             | '(SMR0201AW)'                  | '130'     | '1%'    | '1/20W'  | 'DISCRETE' | 'RES CHIP 130(1/20W,+-1%,0201)'                    | 'CHIPR0201'    | ''          | ''            | '20180806'
 '130'        | '1%'      | '1/20W'  | '0201LF'  | 'EMPTY'  | 'CS11301FE03'(!)        = ''              | ''                 | 'CS11301FE03'           | 'R0201'             | '(SMR0201AW)'                  | '130'     | '1%'    | '1/20W'  | 'IO'       | 'RES CHIP 130(1/20W,+-1%,0201)'                    | 'CHIPR0201'    | ''          | ''            | '20180806'
 '499'        | '1%'      | '1/20W'  | '0201LF'  | 'CHIP'   | 'CS14991FE00'(!)        = ''              | ''                 | 'CS14991FE00'           | 'R0201'             | '(SMR0201AW)'                  | '499'     | '1%'    | '1/20W'  | 'DISCRETE' | 'RES CHIP 499 1/20W +-1%(0201)'                    | 'CHIPR0201'    | ''          | ''            | '20180806'
 '499'        | '1%'      | '1/20W'  | '0201LF'  | 'EMPTY'  | 'CS14991FE00'(!)        = ''              | ''                 | 'CS14991FE00'           | 'R0201'             | '(SMR0201AW)'                  | '499'     | '1%'    | '1/20W'  | 'IO'       | 'RES CHIP 499 1/20W +-1%(0201)'                    | 'CHIPR0201'    | ''          | ''            | '20180806'
 '1.21K'      | '1%'      | '1/20W'  | '0201LF'  | 'CHIP'   | 'CS21211FE00'(!)        = ''              | ''                 | 'CS21211FE00'           | 'R0201'             | '(SMR0201AW)'                  | '1.21K'   | '1%'    | '1/20W'  | 'DISCRETE' | 'RES CHIP 1.21K 1/20W +-1%(0201)'                  | 'CHIPR0201'    | ''          | ''            | '20180806'
 '1.21K'      | '1%'      | '1/20W'  | '0201LF'  | 'EMPTY'  | 'CS21211FE00'(!)        = ''              | ''                 | 'CS21211FE00'           | 'R0201'             | '(SMR0201AW)'                  | '1.21K'   | '1%'    | '1/20W'  | 'IO'       | 'RES CHIP 1.21K 1/20W +-1%(0201)'                  | 'CHIPR0201'    | ''          | ''            | '20180806'
 '2.7K'       | '1%'      | '1/20W'  | '0201LF'  | 'CHIP'   | 'CS22701FE02'(!)        = ''              | ''                 | 'CS22701FE02'           | 'R0201'             | '(SMR0201AW)'                  | '2.7K'    | '1%'    | '1/20W'  | 'DISCRETE' | 'RES CHIP 2.7K(1/20W,+-1%,0201)'                   | 'CHIPR0201'    | ''          | ''            | '20180806'
 '2.7K'       | '1%'      | '1/20W'  | '0201LF'  | 'EMPTY'  | 'CS22701FE02'(!)        = ''              | ''                 | 'CS22701FE02'           | 'R0201'             | '(SMR0201AW)'                  | '2.7K'    | '1%'    | '1/20W'  | 'IO'       | 'RES CHIP 2.7K(1/20W,+-1%,0201)'                   | 'CHIPR0201'    | ''          | ''            | '20180806'
 '5.36K'      | '1%'      | '1/20W'  | '0201LF'  | 'CHIP'   | 'CS25361FE00'(!)        = ''              | ''                 | 'CS25361FE00'           | 'R0201'             | '(SMR0201AW)'                  | '5.36K'   | '1%'    | '1/20W'  | 'DISCRETE' | 'RES CHIP 5.36K 1/20W +-1%(0201)'                  | 'CHIPR0201'    | ''          | ''            | '20180806'
 '5.36K'      | '1%'      | '1/20W'  | '0201LF'  | 'EMPTY'  | 'CS25361FE00'(!)        = ''              | ''                 | 'CS25361FE00'           | 'R0201'             | '(SMR0201AW)'                  | '5.36K'   | '1%'    | '1/20W'  | 'IO'       | 'RES CHIP 5.36K 1/20W +-1%(0201)'                  | 'CHIPR0201'    | ''          | ''            | '20180806'
 '6.49K'      | '1%'      | '1/20W'  | '0201LF'  | 'CHIP'   | 'CS26491FE00'(!)        = ''              | ''                 | 'CS26491FE00'           | 'R0201'             | '(SMR0201AW)'                  | '6.49K'   | '1%'    | '1/20W'  | 'DISCRETE' | 'RES CHIP 6.49K 1/20W +-1%(0201)'                  | 'CHIPR0201'    | ''          | ''            | '20180806'
 '6.49K'      | '1%'      | '1/20W'  | '0201LF'  | 'EMPTY'  | 'CS26491FE00'(!)        = ''              | ''                 | 'CS26491FE00'           | 'R0201'             | '(SMR0201AW)'                  | '6.49K'   | '1%'    | '1/20W'  | 'IO'       | 'RES CHIP 6.49K 1/20W +-1%(0201)'                  | 'CHIPR0201'    | ''          | ''            | '20180806'
 '6.65K'      | '1%'      | '1/20W'  | '0201LF'  | 'CHIP'   | 'CS26651FE01'(!)        = ''              | ''                 | 'CS26651FE01'           | 'R0201'             | '(SMR0201AW)'                  | '6.65K'   | '1%'    | '1/20W'  | 'DISCRETE' | 'RES CHIP 6.65K 1/20W +-1%(0201)'                  | 'CHIPR0201'    | ''          | ''            | '20180806'
 '6.65K'      | '1%'      | '1/20W'  | '0201LF'  | 'EMPTY'  | 'CS26651FE01'(!)        = ''              | ''                 | 'CS26651FE01'           | 'R0201'             | '(SMR0201AW)'                  | '6.65K'   | '1%'    | '1/20W'  | 'IO'       | 'RES CHIP 6.65K 1/20W +-1%(0201)'                  | 'CHIPR0201'    | ''          | ''            | '20180806'
 '6.98K'      | '1%'      | '1/20W'  | '0201LF'  | 'CHIP'   | 'CS26981FE00'(!)        = ''              | ''                 | 'CS26981FE00'           | 'R0201'             | '(SMR0201AW)'                  | '6.98K'   | '1%'    | '1/20W'  | 'DISCRETE' | 'RES CHIP 6.98K 1/20W +-1%(0201)'                  | 'CHIPR0201'    | ''          | ''            | '20180806'
 '6.98K'      | '1%'      | '1/20W'  | '0201LF'  | 'EMPTY'  | 'CS26981FE00'(!)        = ''              | ''                 | 'CS26981FE00'           | 'R0201'             | '(SMR0201AW)'                  | '6.98K'   | '1%'    | '1/20W'  | 'IO'       | 'RES CHIP 6.98K 1/20W +-1%(0201)'                  | 'CHIPR0201'    | ''          | ''            | '20180806'
 '9.09K'      | '1'       | '1/20W'  | '0201LF'  | 'CHIP'   | 'CS29091FE00'(!)        = ''              | ''                 | 'CS29091FE00'           | 'R0201'             | '(SMR0201AW)'                  | '9.09K'   | '1'     | '1/20W'  | 'DISCRETE' | 'RES CHIP 9.09K 1/20W +-1(0201)'                   | 'CHIPR0201'    | ''          | ''            | '20180806'
 '9.09K'      | '1'       | '1/20W'  | '0201LF'  | 'EMPTY'  | 'CS29091FE00'(!)        = ''              | ''                 | 'CS29091FE00'           | 'R0201'             | '(SMR0201AW)'                  | '9.09K'   | '1'     | '1/20W'  | 'IO'       | 'RES CHIP 9.09K 1/20W +-1(0201)'                   | 'CHIPR0201'    | ''          | ''            | '20180806'
 '11.3K'      | '1%'      | '1/20W'  | '0201LF'  | 'CHIP'   | 'CS31131FE03'(!)        = ''              | ''                 | 'CS31131FE03'           | 'R0201'             | '(SMR0201AW)'                  | '11.3K'   | '1%'    | '1/20W'  | 'DISCRETE' | 'RES CHIP 11.3K(1/20W,+-1%,0201)'                  | 'CHIPR0201'    | ''          | ''            | '20180806'
 '11.3K'      | '1%'      | '1/20W'  | '0201LF'  | 'EMPTY'  | 'CS31131FE03'(!)        = ''              | ''                 | 'CS31131FE03'           | 'R0201'             | '(SMR0201AW)'                  | '11.3K'   | '1%'    | '1/20W'  | 'IO'       | 'RES CHIP 11.3K(1/20W,+-1%,0201)'                  | 'CHIPR0201'    | ''          | ''            | '20180806'
 '22.1K'      | '1%'      | '1/20W'  | '0201LF'  | 'CHIP'   | 'CS32211FE00'(!)        = ''              | ''                 | 'CS32211FE00'           | 'R0201'             | '(SMR0201AW)'                  | '22.1K'   | '1%'    | '1/20W'  | 'DISCRETE' | 'RES CHIP 22.1K 1/20W +-1%(0201)'                  | 'CHIPR0201'    | ''          | ''            | '20180806'
 '22.1K'      | '1%'      | '1/20W'  | '0201LF'  | 'EMPTY'  | 'CS32211FE00'(!)        = ''              | ''                 | 'CS32211FE00'           | 'R0201'             | '(SMR0201AW)'                  | '22.1K'   | '1%'    | '1/20W'  | 'IO'       | 'RES CHIP 22.1K 1/20W +-1%(0201)'                  | 'CHIPR0201'    | ''          | ''            | '20180806'
 '22.6K'      | '1%'      | '1/20W'  | '0201LF'  | 'CHIP'   | 'CS32261FE01'(!)        = ''              | ''                 | 'CS32261FE01'           | 'R0201'             | '(SMR0201AW)'                  | '22.6K'   | '1%'    | '1/20W'  | 'DISCRETE' | 'RES CHIP 22.6K 1/20W +-1%(0201)'                  | 'CHIPR0201'    | ''          | ''            | '20180806'
 '22.6K'      | '1%'      | '1/20W'  | '0201LF'  | 'EMPTY'  | 'CS32261FE01'(!)        = ''              | ''                 | 'CS32261FE01'           | 'R0201'             | '(SMR0201AW)'                  | '22.6K'   | '1%'    | '1/20W'  | 'IO'       | 'RES CHIP 22.6K 1/20W +-1%(0201)'                  | 'CHIPR0201'    | ''          | ''            | '20180806'
 '2.49K'      | '1%'      | '1/20W'  | '0201LF'  | 'CHIP'   | 'CS22491FE02'(!)        = ''              | ''                 | 'CS22491FE02'           | 'R0201'             | '(SMR0201AW)'                  | '2.49K'   | '1%'    | '1/20W'  | 'DISCRETE' | 'RES CHIP 2.49K(1/20W,+-1%,0201)'                  | 'CHIPR0201'    | ''          | ''            | '20180806'
 '2.49K'      | '1%'      | '1/20W'  | '0201LF'  | 'EMPTY'  | 'CS22491FE02'(!)        = ''              | ''                 | 'CS22491FE02'           | 'R0201'             | '(SMR0201AW)'                  | '2.49K'   | '1%'    | '1/20W'  | 'IO'       | 'RES CHIP 2.49K(1/20W,+-1%,0201)'                  | 'CHIPR0201'    | ''          | ''            | '20180806'
 '2.87K'      | '1%'      | '1/20W'  | '0201LF'  | 'CHIP'   | 'CS22871FE01'(!)        = ''              | ''                 | 'CS22871FE01'           | 'R0201'             | '(SMR0201AW)'                  | '2.87K'   | '1%'    | '1/20W'  | 'DISCRETE' | 'RES CHIP 2.87K(1/20W,+-1%,0201)'                  | 'CHIPR0201'    | ''          | ''            | '20180806'
 '2.87K'      | '1%'      | '1/20W'  | '0201LF'  | 'EMPTY'  | 'CS22871FE01'(!)        = ''              | ''                 | 'CS22871FE01'           | 'R0201'             | '(SMR0201AW)'                  | '2.87K'   | '1%'    | '1/20W'  | 'IO'       | 'RES CHIP 2.87K(1/20W,+-1%,0201)'                  | 'CHIPR0201'    | ''          | ''            | '20180806'
 '3.3K'       | '5%'      | '1/20W'  | '0201LF'  | 'CHIP'   | 'CS23301JE02'(!)        = ''              | ''                 | 'CS23301JE02'           | 'R0201'             | '(SMR0201AW)'                  | '3.3K'    | '5%'    | '1/20W'  | 'DISCRETE' | 'RES CHIP 3.3K 1/20W +-5%(0201)'                   | 'CHIPR0201'    | ''          | ''            | '20180806'
 '3.3K'       | '5%'      | '1/20W'  | '0201LF'  | 'EMPTY'  | 'CS23301JE02'(!)        = ''              | ''                 | 'CS23301JE02'           | 'R0201'             | '(SMR0201AW)'                  | '3.3K'    | '5%'    | '1/20W'  | 'IO'       | 'RES CHIP 3.3K 1/20W +-5%(0201)'                   | 'CHIPR0201'    | ''          | ''            | '20180806'
 '3.32K'      | '1%'      | '1/20W'  | '0201LF'  | 'CHIP'   | 'CS23321FE00'(!)        = ''              | ''                 | 'CS23321FE00'           | 'R0201'             | '(SMR0201AW)'                  | '3.32K'   | '1%'    | '1/20W'  | 'DISCRETE' | 'RES CHIP 3.32K 1/20W +-1%(0201)'                  | 'CHIPR0201'    | ''          | ''            | '20180806'
 '3.32K'      | '1%'      | '1/20W'  | '0201LF'  | 'EMPTY'  | 'CS23321FE00'(!)        = ''              | ''                 | 'CS23321FE00'           | 'R0201'             | '(SMR0201AW)'                  | '3.32K'   | '1%'    | '1/20W'  | 'IO'       | 'RES CHIP 3.32K 1/20W +-1%(0201)'                  | 'CHIPR0201'    | ''          | ''            | '20180806'
 '49.9K'      | '1%'      | '1/20W'  | '0201LF'  | 'CHIP'   | 'CS34991FE02'(!)        = ''              | ''                 | 'CS34991FE02'           | 'R0201'             | '(SMR0201AW)'                  | '49.9K'   | '1%'    | '1/20W'  | 'DISCRETE' | 'RES CHIP 49.9K 1/20W +-1%(0201)'                  | 'CHIPR0201'    | ''          | ''            | '20180806'
 '49.9K'      | '1%'      | '1/20W'  | '0201LF'  | 'EMPTY'  | 'CS34991FE02'(!)        = ''              | ''                 | 'CS34991FE02'           | 'R0201'             | '(SMR0201AW)'                  | '49.9K'   | '1%'    | '1/20W'  | 'IO'       | 'RES CHIP 49.9K 1/20W +-1%(0201)'                  | 'CHIPR0201'    | ''          | ''            | '20180806'
 '5.62K'      | '1%'      | '1/20W'  | '0201LF'  | 'CHIP'   | 'CS25621FE06'(!)        = ''              | ''                 | 'CS25621FE06'           | 'R0201'             | '(SMR0201AW)'                  | '5.62K'   | '1%'    | '1/20W'  | 'DISCRETE' | 'RES CHIP 5.62K(1/20W,+-1%,0201)'                  | 'CHIPR0201'    | ''          | ''            | '20180806'
 '5.62K'      | '1%'      | '1/20W'  | '0201LF'  | 'EMPTY'  | 'CS25621FE06'(!)        = ''              | ''                 | 'CS25621FE06'           | 'R0201'             | '(SMR0201AW)'                  | '5.62K'   | '1%'    | '1/20W'  | 'IO'       | 'RES CHIP 5.62K(1/20W,+-1%,0201)'                  | 'CHIPR0201'    | ''          | ''            | '20180806'
 '56K'        | '1%'      | '1/20W'  | '0201LF'  | 'CHIP'   | 'CS35601FE00'(!)        = 'End of Design' | 'Comp-Approve'     | 'CS35601FE00'           | 'R0201'             | '(SMR0201AW)'                  | '56K'     | '1%'    | '1/20W'  | 'DISCRETE' | 'RES CHIP 56K 1/20W +-1%(0201)'                    | 'CHIPR0201'    | ''          | ''            | '20180806'
 '56K'        | '1%'      | '1/20W'  | '0201LF'  | 'EMPTY'  | 'CS35601FE00'(!)        = 'End of Design' | 'Comp-Approve'     | 'CS35601FE00'           | 'R0201'             | '(SMR0201AW)'                  | '56K'     | '1%'    | '1/20W'  | 'IO'       | 'RES CHIP 56K 1/20W +-1%(0201)'                    | 'CHIPR0201'    | ''          | ''            | '20180806'
 '8.25K'      | '1%'      | '1/20W'  | '0201LF'  | 'CHIP'   | 'CS28251FE00'(!)        = ''              | ''                 | 'CS28251FE00'           | 'R0201'             | '(SMR0201AW)'                  | '8.25K'   | '1%'    | '1/20W'  | 'DISCRETE' | 'RES CHIP 8.25K 1/20W +-1%(0201)'                  | 'CHIPR0201'    | ''          | ''            | '20180806'
 '8.25K'      | '1%'      | '1/20W'  | '0201LF'  | 'EMPTY'  | 'CS28251FE00'(!)        = ''              | ''                 | 'CS28251FE00'           | 'R0201'             | '(SMR0201AW)'                  | '8.25K'   | '1%'    | '1/20W'  | 'IO'       | 'RES CHIP 8.25K 1/20W +-1%(0201)'                  | 'CHIPR0201'    | ''          | ''            | '20180806'
 '10K'        | '5%'      | '1/20W'  | '0201LF'  | 'CHIP'   | 'CS31001JE16'(!)        = ''              | ''                 | 'CS31001JE16'           | 'R0201'             | '(SMR0201AW)'                  | '10K'     | '5%'    | '1/20W'  | 'DISCRETE' | 'RES CHIP 10K 1/20W +-5%(0201)'                    | 'CHIPR0201'    | ''          | ''            | '20140819'
 '10K'        | '5%'      | '1/20W'  | '0201LF'  | 'EMPTY'  | 'CS31001JE16'(!)        = ''              | ''                 | 'CS31001JE16'           | 'R0201'             | '(SMR0201AW)'                  | '10K'     | '5%'    | '1/20W'  | 'IO'       | 'RES CHIP 10K 1/20W +-5%(0201)'                    | 'CHIPR0201'    | ''          | ''            | '20140819'
 '10.2K'      | '1%'      | '1/20W'  | '0201LF'  | 'CHIP'   | 'CS31021FE00'(!)        = ''              | ''                 | 'CS31021FE00'           | 'R0201'             | '(SMR0201AW)'                  | '10.2K'   | '1%'    | '1/20W'  | 'DISCRETE' | 'RES CHIP 10.2K 1/20W +-1%(0201)'                  | 'CHIPR0201'    | ''          | ''            | '20180806'
 '10.2K'      | '1%'      | '1/20W'  | '0201LF'  | 'EMPTY'  | 'CS31021FE00'(!)        = ''              | ''                 | 'CS31021FE00'           | 'R0201'             | '(SMR0201AW)'                  | '10.2K'   | '1%'    | '1/20W'  | 'IO'       | 'RES CHIP 10.2K 1/20W +-1%(0201)'                  | 'CHIPR0201'    | ''          | ''            | '20180806'
 '150K'       | '1%'      | '1/20W'  | '0201LF'  | 'CHIP'   | 'CS41501FE06'(!)        = ''              | ''                 | 'CS41501FE06'           | 'R0201'             | '(SMR0201AW)'                  | '150K'    | '1%'    | '1/20W'  | 'DISCRETE' | 'RES CHIP 150K(1/20W,+-1%,0201)'                   | 'CHIPR0201'    | ''          | ''            | '20180806'
 '150K'       | '1%'      | '1/20W'  | '0201LF'  | 'EMPTY'  | 'CS41501FE06'(!)        = ''              | ''                 | 'CS41501FE06'           | 'R0201'             | '(SMR0201AW)'                  | '150K'    | '1%'    | '1/20W'  | 'IO'       | 'RES CHIP 150K(1/20W,+-1%,0201)'                   | 'CHIPR0201'    | ''          | ''            | '20180806'
 '11.5K'      | '1%'      | '1/20W'  | '0201LF'  | 'CHIP'   | 'CS31151FE03'(!)        = ''              | ''                 | 'CS31151FE03'           | 'R0201'             | '(SMR0201AW)'                  | '11.5K'   | '1%'    | '1/20W'  | 'DISCRETE' | 'RES CHIP 11.5K(1/20W,+-1%,0201)'                  | 'CHIPR0201'    | ''          | ''            | '20180806'
 '11.5K'      | '1%'      | '1/20W'  | '0201LF'  | 'EMPTY'  | 'CS31151FE03'(!)        = ''              | ''                 | 'CS31151FE03'           | 'R0201'             | '(SMR0201AW)'                  | '11.5K'   | '1%'    | '1/20W'  | 'IO'       | 'RES CHIP 11.5K(1/20W,+-1%,0201)'                  | 'CHIPR0201'    | ''          | ''            | '20180806'
 '154K'       | '1%'      | '1/20W'  | '0201LF'  | 'CHIP'   | 'CS41541FE00'(!)        = ''              | ''                 | 'CS41541FE00'           | 'R0201'             | '(SMR0201AW)'                  | '154K'    | '1%'    | '1/20W'  | 'DISCRETE' | 'RES CHIP 154K 1/20W +-1%(0201)'                   | 'CHIPR0201'    | ''          | ''            | '20180806'
 '154K'       | '1%'      | '1/20W'  | '0201LF'  | 'EMPTY'  | 'CS41541FE00'(!)        = ''              | ''                 | 'CS41541FE00'           | 'R0201'             | '(SMR0201AW)'                  | '154K'    | '1%'    | '1/20W'  | 'IO'       | 'RES CHIP 154K 1/20W +-1%(0201)'                   | 'CHIPR0201'    | ''          | ''            | '20180806'
 '12K'        | '1%'      | '1/20W'  | '0201LF'  | 'CHIP'   | 'CS31201FE00'(!)        = 'End of Design' | 'Comp-Approve'     | 'CS31201FE00'           | 'R0201'             | '(SMR0201AW)'                  | '12K'     | '1%'    | '1/20W'  | 'DISCRETE' | 'RES CHIP 12K 1/20W +-1%(0201)'                    | 'CHIPR0201'    | ''          | ''            | '20180806'
 '12K'        | '1%'      | '1/20W'  | '0201LF'  | 'EMPTY'  | 'CS31201FE00'(!)        = 'End of Design' | 'Comp-Approve'     | 'CS31201FE00'           | 'R0201'             | '(SMR0201AW)'                  | '12K'     | '1%'    | '1/20W'  | 'IO'       | 'RES CHIP 12K 1/20W +-1%(0201)'                    | 'CHIPR0201'    | ''          | ''            | '20180806'
 '200K'       | '1%'      | '1/20W'  | '0201LF'  | 'CHIP'   | 'CS42001FE00'(!)        = ''              | ''                 | 'CS42001FE00'           | 'R0201'             | '(SMR0201AW)'                  | '200K'    | '1%'    | '1/20W'  | 'DISCRETE' | 'RES CHIP 200K 1/20W +-1%(0201)'                   | 'CHIPR0201'    | ''          | ''            | '20180806'
 '200K'       | '1%'      | '1/20W'  | '0201LF'  | 'EMPTY'  | 'CS42001FE00'(!)        = ''              | ''                 | 'CS42001FE00'           | 'R0201'             | '(SMR0201AW)'                  | '200K'    | '1%'    | '1/20W'  | 'IO'       | 'RES CHIP 200K 1/20W +-1%(0201)'                   | 'CHIPR0201'    | ''          | ''            | '20180806'
 '15K'        | '1%'      | '1/20W'  | '0201LF'  | 'CHIP'   | 'CS31501FE00'(!)        = ''              | ''                 | 'CS31501FE00'           | 'R0201'             | '(SMR0201AW)'                  | '15K'     | '1%'    | '1/20W'  | 'DISCRETE' | 'RES CHIP 15K 1/20W +-1%(0201)'                    | 'CHIPR0201'    | ''          | ''            | '20180806'
 '15K'        | '1%'      | '1/20W'  | '0201LF'  | 'EMPTY'  | 'CS31501FE00'(!)        = ''              | ''                 | 'CS31501FE00'           | 'R0201'             | '(SMR0201AW)'                  | '15K'     | '1%'    | '1/20W'  | 'IO'       | 'RES CHIP 15K 1/20W +-1%(0201)'                    | 'CHIPR0201'    | ''          | ''            | '20180806'
 '15.8K'      | '1%'      | '1/20W'  | '0201LF'  | 'CHIP'   | 'CS31581FE00'(!)        = ''              | ''                 | 'CS31581FE00'           | 'R0201'             | '(SMR0201AW)'                  | '15.8K'   | '1%'    | '1/20W'  | 'DISCRETE' | 'RES CHIP 15.8K 1/20W +-1%(0201)'                  | 'CHIPR0201'    | ''          | ''            | '20180806'
 '15.8K'      | '1%'      | '1/20W'  | '0201LF'  | 'EMPTY'  | 'CS31581FE00'(!)        = ''              | ''                 | 'CS31581FE00'           | 'R0201'             | '(SMR0201AW)'                  | '15.8K'   | '1%'    | '1/20W'  | 'IO'       | 'RES CHIP 15.8K 1/20W +-1%(0201)'                  | 'CHIPR0201'    | ''          | ''            | '20180806'
 '475K'       | '1%'      | '1/20W'  | '0201LF'  | 'CHIP'   | 'CS44751FE01'(!)        = ''              | ''                 | 'CS44751FE01'           | 'R0201'             | '(SMR0201AW)'                  | '475K'    | '1%'    | '1/20W'  | 'DISCRETE' | 'RES CHIP 475K 1/20W +-1%(0201)'                   | 'CHIPR0201'    | ''          | ''            | '20180806'
 '475K'       | '1%'      | '1/20W'  | '0201LF'  | 'EMPTY'  | 'CS44751FE01'(!)        = ''              | ''                 | 'CS44751FE01'           | 'R0201'             | '(SMR0201AW)'                  | '475K'    | '1%'    | '1/20W'  | 'IO'       | 'RES CHIP 475K 1/20W +-1%(0201)'                   | 'CHIPR0201'    | ''          | ''            | '20180806'
 '10M'        | '5%'      | '1/20W'  | '0201LF'  | 'CHIP'   | 'CS61001JE00'(!)        = ''              | ''                 | 'CS61001JE00'           | 'R0201'             | '(SMR0201AW)'                  | '10M'     | '5%'    | '1/20W'  | 'DISCRETE' | 'RES CHIP 10M 1/20W +-5%(0201)'                    | 'CHIPR0201'    | ''          | ''            | '20180806'
 '10M'        | '5%'      | '1/20W'  | '0201LF'  | 'EMPTY'  | 'CS61001JE00'(!)        = ''              | ''                 | 'CS61001JE00'           | 'R0201'             | '(SMR0201AW)'                  | '10M'     | '5%'    | '1/20W'  | 'IO'       | 'RES CHIP 10M 1/20W +-5%(0201)'                    | 'CHIPR0201'    | ''          | ''            | '20180806'
 '18K'        | '1%'      | '1/20W'  | '0201LF'  | 'CHIP'   | 'CS31801FE01'(!)        = ''              | ''                 | 'CS31801FE01'           | 'R0201'             | '(SMR0201AW)'                  | '18K'     | '1%'    | '1/20W'  | 'DISCRETE' | 'RES CHIP 18K 1/20W +-1%(0201)'                    | 'CHIPR0201'    | ''          | ''            | '20180806'
 '18K'        | '1%'      | '1/20W'  | '0201LF'  | 'EMPTY'  | 'CS31801FE01'(!)        = ''              | ''                 | 'CS31801FE01'           | 'R0201'             | '(SMR0201AW)'                  | '18K'     | '1%'    | '1/20W'  | 'IO'       | 'RES CHIP 18K 1/20W +-1%(0201)'                    | 'CHIPR0201'    | ''          | ''            | '20180806'
 '1.24K'      | '1%'      | '1/20W'  | '0201LF'  | 'CHIP'   | 'CS21241FE00'(!)        = ''              | ''                 | 'CS21241FE00'           | 'R0201'             | '(SMR0201AW)'                  | '1.24K'   | '1%'    | '1/20W'  | 'DISCRETE' | 'RES CHIP 1.24K(1/20W,+-1%,0201)'                  | 'CHIPR0201'    | ''          | ''            | '20180806'
 '1.24K'      | '1%'      | '1/20W'  | '0201LF'  | 'EMPTY'  | 'CS21241FE00'(!)        = ''              | ''                 | 'CS21241FE00'           | 'R0201'             | '(SMR0201AW)'                  | '1.24K'   | '1%'    | '1/20W'  | 'IO'       | 'RES CHIP 1.24K(1/20W,+-1%,0201)'                  | 'CHIPR0201'    | ''          | ''            | '20180806'
 '20K'        | '1%'      | '1/20W'  | '0201LF'  | 'CHIP'   | 'CS32001FE00'(!)        = ''              | ''                 | 'CS32001FE00'           | 'R0201'             | '(SMR0201AW)'                  | '20K'     | '1%'    | '1/20W'  | 'DISCRETE' | 'RES CHIP 20K 1/20W +-1%(0201)'                    | 'CHIPR0201'    | ''          | ''            | '20180806'
 '20K'        | '1%'      | '1/20W'  | '0201LF'  | 'EMPTY'  | 'CS32001FE00'(!)        = ''              | ''                 | 'CS32001FE00'           | 'R0201'             | '(SMR0201AW)'                  | '20K'     | '1%'    | '1/20W'  | 'IO'       | 'RES CHIP 20K 1/20W +-1%(0201)'                    | 'CHIPR0201'    | ''          | ''            | '20180806'
 '20K'        | '5%'      | '1/20W'  | '0201LF'  | 'CHIP'   | 'CS32001JE01'(!)        = ''              | ''                 | 'CS32001JE01'           | 'R0201'             | '(SMR0201AW)'                  | '20K'     | '5%'    | '1/20W'  | 'DISCRETE' | 'RES CHIP 20K 1/20W +-5%(0201)'                    | 'CHIPR0201'    | ''          | ''            | '20180806'
 '20K'        | '5%'      | '1/20W'  | '0201LF'  | 'EMPTY'  | 'CS32001JE01'(!)        = ''              | ''                 | 'CS32001JE01'           | 'R0201'             | '(SMR0201AW)'                  | '20K'     | '5%'    | '1/20W'  | 'IO'       | 'RES CHIP 20K 1/20W +-5%(0201)'                    | 'CHIPR0201'    | ''          | ''            | '20180806'
 '23.2K'      | '1%'      | '1/20W'  | '0201LF'  | 'CHIP'   | 'CS32321FE00'(!)        = ''              | ''                 | 'CS32321FE00'           | 'R0201'             | '(SMR0201AW)'                  | '23.2K'   | '1%'    | '1/20W'  | 'DISCRETE' | 'RES CHIP 23.2K 1/20W +-1%(0201)'                  | 'CHIPR0201'    | ''          | ''            | '20180806'
 '23.2K'      | '1%'      | '1/20W'  | '0201LF'  | 'EMPTY'  | 'CS32321FE00'(!)        = ''              | ''                 | 'CS32321FE00'           | 'R0201'             | '(SMR0201AW)'                  | '23.2K'   | '1%'    | '1/20W'  | 'IO'       | 'RES CHIP 23.2K 1/20W +-1%(0201)'                  | 'CHIPR0201'    | ''          | ''            | '20180806'
 '24.3K'      | '1%'      | '1/20W'  | '0201LF'  | 'CHIP'   | 'CS32431FE01'(!)        = ''              | ''                 | 'CS32431FE01'           | 'R0201'             | '(SMR0201AW)'                  | '24.3K'   | '1%'    | '1/20W'  | 'DISCRETE' | 'RES CHIP 24.3K 1/20W(+-1%,0201)'                  | 'CHIPR0201'    | ''          | ''            | '20180807'
 '24.3K'      | '1%'      | '1/20W'  | '0201LF'  | 'EMPTY'  | 'CS32431FE01'(!)        = ''              | ''                 | 'CS32431FE01'           | 'R0201'             | '(SMR0201AW)'                  | '24.3K'   | '1%'    | '1/20W'  | 'IO'       | 'RES CHIP 24.3K 1/20W(+-1%,0201)'                  | 'CHIPR0201'    | ''          | ''            | '20180807'
 '24.9K'      | '1%'      | '1/20W'  | '0201LF'  | 'CHIP'   | 'CS32491FE04'(!)        = ''              | ''                 | 'CS32491FE04'           | 'R0201'             | '(SMR0201AW)'                  | '24.9K'   | '1%'    | '1/20W'  | 'DISCRETE' | 'RES CHIP 24.9K 1/20W +-1%(0201)'                  | 'CHIPR0201'    | ''          | ''            | '20180807'
 '24.9K'      | '1%'      | '1/20W'  | '0201LF'  | 'EMPTY'  | 'CS32491FE04'(!)        = ''              | ''                 | 'CS32491FE04'           | 'R0201'             | '(SMR0201AW)'                  | '24.9K'   | '1%'    | '1/20W'  | 'IO'       | 'RES CHIP 24.9K 1/20W +-1%(0201)'                  | 'CHIPR0201'    | ''          | ''            | '20180807'
 '25.5K'      | '1%'      | '1/20W'  | '0201LF'  | 'CHIP'   | 'CS32551FE00'(!)        = ''              | ''                 | 'CS32551FE00'           | 'R0201'             | '(SMR0201AW)'                  | '25.5K'   | '1%'    | '1/20W'  | 'DISCRETE' | 'RES CHIP 25.5K 1/20W +-1%(0201)'                  | 'CHIPR0201'    | ''          | ''            | '20180807'
 '25.5K'      | '1%'      | '1/20W'  | '0201LF'  | 'EMPTY'  | 'CS32551FE00'(!)        = ''              | ''                 | 'CS32551FE00'           | 'R0201'             | '(SMR0201AW)'                  | '25.5K'   | '1%'    | '1/20W'  | 'IO'       | 'RES CHIP 25.5K 1/20W +-1%(0201)'                  | 'CHIPR0201'    | ''          | ''            | '20180807'
 '100K'       | '1%'      | '1/20W'  | '0201LF'  | 'CHIP'   | 'CS41001FE08'(!)        = ''              | ''                 | 'CS41001FE08'           | 'R0201'             | '(SMR0201AW)'                  | '100K'    | '1%'    | '1/20W'  | 'DISCRETE' | 'RES CHIP 100K(1/20W,+-1%,0201)'                   | 'CHIPR0201'    | ''          | ''            | '20180807'
 '100K'       | '1%'      | '1/20W'  | '0201LF'  | 'EMPTY'  | 'CS41001FE08'(!)        = ''              | ''                 | 'CS41001FE08'           | 'R0201'             | '(SMR0201AW)'                  | '100K'    | '1%'    | '1/20W'  | 'IO'       | 'RES CHIP 100K(1/20W,+-1%,0201)'                   | 'CHIPR0201'    | ''          | ''            | '20180807'
 '133K'       | '1%'      | '1/20W'  | '0201LF'  | 'CHIP'   | 'CS41331FE00'(!)        = ''              | ''                 | 'CS41331FE00'           | 'R0201'             | '(SMR0201AW)'                  | '133K'    | '1%'    | '1/20W'  | 'DISCRETE' | 'RES CHIP 133K 1/20W +-1%(0201)'                   | 'CHIPR0201'    | ''          | ''            | '20180807'
 '133K'       | '1%'      | '1/20W'  | '0201LF'  | 'EMPTY'  | 'CS41331FE00'(!)        = ''              | ''                 | 'CS41331FE00'           | 'R0201'             | '(SMR0201AW)'                  | '133K'    | '1%'    | '1/20W'  | 'IO'       | 'RES CHIP 133K 1/20W +-1%(0201)'                   | 'CHIPR0201'    | ''          | ''            | '20180807'
 '169K'       | '1%'      | '1/20W'  | '0201LF'  | 'CHIP'   | 'CS41691FE00'(!)        = ''              | ''                 | 'CS41691FE00'           | 'R0201'             | '(SMR0201AW)'                  | '169K'    | '1%'    | '1/20W'  | 'DISCRETE' | 'RES CHIP 169K 1/20W +-1%(0201)'                   | 'CHIPR0201'    | ''          | ''            | '20180807'
 '169K'       | '1%'      | '1/20W'  | '0201LF'  | 'EMPTY'  | 'CS41691FE00'(!)        = ''              | ''                 | 'CS41691FE00'           | 'R0201'             | '(SMR0201AW)'                  | '169K'    | '1%'    | '1/20W'  | 'IO'       | 'RES CHIP 169K 1/20W +-1%(0201)'                   | 'CHIPR0201'    | ''          | ''            | '20180807'
 '249K'       | '1%'      | '1/20W'  | '0201LF'  | 'CHIP'   | 'CS42491FE01'(!)        = ''              | ''                 | 'CS42491FE01'           | 'R0201'             | '(SMR0201AW)'                  | '249K'    | '1%'    | '1/20W'  | 'DISCRETE' | 'RES CHIP 249K 1/20W +-1%(0201)'                   | 'CHIPR0201'    | ''          | ''            | '20180807'
 '249K'       | '1%'      | '1/20W'  | '0201LF'  | 'EMPTY'  | 'CS42491FE01'(!)        = ''              | ''                 | 'CS42491FE01'           | 'R0201'             | '(SMR0201AW)'                  | '249K'    | '1%'    | '1/20W'  | 'IO'       | 'RES CHIP 249K 1/20W +-1%(0201)'                   | 'CHIPR0201'    | ''          | ''            | '20180807'
 '1M'         | '1%'      | '1/20W'  | '0201LF'  | 'CHIP'   | 'CS51001FE00'(!)        = ''              | ''                 | 'CS51001FE00'           | 'R0201'             | '(SMR0201AW)'                  | '1M'      | '1%'    | '1/20W'  | 'DISCRETE' | 'RES CHIP 1M 1/20W +-1%(0201)'                     | 'CHIPR0201'    | ''          | ''            | '20180807'
 '1M'         | '1%'      | '1/20W'  | '0201LF'  | 'EMPTY'  | 'CS51001FE00'(!)        = ''              | ''                 | 'CS51001FE00'           | 'R0201'             | '(SMR0201AW)'                  | '1M'      | '1%'    | '1/20W'  | 'IO'       | 'RES CHIP 1M 1/20W +-1%(0201)'                     | 'CHIPR0201'    | ''          | ''            | '20180807'
 '10'         | '1%'      | '1/20W'  | '0201LF'  | 'CHIP'   | 'CS01001FE00'(!)        = ''              | ''                 | 'CS01001FE00'           | 'R0201'             | '(SMR0201AW)'                  | '10'      | '1%'    | '1/20W'  | 'DISCRETE' | 'RES CHIP 10 1/20W +-1%(0201)'                     | 'CHIPR0201'    | ''          | ''            | '20180807'
 '10'         | '1%'      | '1/20W'  | '0201LF'  | 'EMPTY'  | 'CS01001FE00'(!)        = ''              | ''                 | 'CS01001FE00'           | 'R0201'             | '(SMR0201AW)'                  | '10'      | '1%'    | '1/20W'  | 'IO'       | 'RES CHIP 10 1/20W +-1%(0201)'                     | 'CHIPR0201'    | ''          | ''            | '20180807'
 '510'        | '5%'      | '1/20W'  | '0201LF'  | 'CHIP'   | 'CS15101JE00'(!)        = ''              | ''                 | 'CS15101JE00'           | 'R0201'             | '(SMR0201AW)'                  | '510'     | '5%'    | '1/20W'  | 'DISCRETE' | 'RES CHIP 510(1/20W,+-5%,0201)'                    | 'CHIPR0201'    | ''          | ''            | '20180807'
 '510'        | '5%'      | '1/20W'  | '0201LF'  | 'EMPTY'  | 'CS15101JE00'(!)        = ''              | ''                 | 'CS15101JE00'           | 'R0201'             | '(SMR0201AW)'                  | '510'     | '5%'    | '1/20W'  | 'IO'       | 'RES CHIP 510(1/20W,+-5%,0201)'                    | 'CHIPR0201'    | ''          | ''            | '20180807'
 '68.1'       | '1%'      | '1/20W'  | '0201LF'  | 'CHIP'   | 'CS06811FE01'(!)        = ''              | ''                 | 'CS06811FE01'           | 'R0201'             | '(SMR0201AW)'                  | '68.1'    | '1%'    | '1/20W'  | 'DISCRETE' | 'RES CHIP 68.1 1/20W +-1%(0201)'                   | 'CHIPR0201'    | ''          | ''            | '20180807'
 '68.1'       | '1%'      | '1/20W'  | '0201LF'  | 'EMPTY'  | 'CS06811FE01'(!)        = ''              | ''                 | 'CS06811FE01'           | 'R0201'             | '(SMR0201AW)'                  | '68.1'    | '1%'    | '1/20W'  | 'IO'       | 'RES CHIP 68.1 1/20W +-1%(0201)'                   | 'CHIPR0201'    | ''          | ''            | '20180807'
 '750'        | '1%'      | '1/20W'  | '0201LF'  | 'CHIP'   | 'CS17501FE00'(!)        = ''              | ''                 | 'CS17501FE00'           | 'R0201'             | '(SMR0201AW)'                  | '750'     | '1%'    | '1/20W'  | 'DISCRETE' | 'RES CHIP 750 1/20W +-1%(0201)'                    | 'CHIPR0201'    | ''          | ''            | '20180807'
 '750'        | '1%'      | '1/20W'  | '0201LF'  | 'EMPTY'  | 'CS17501FE00'(!)        = ''              | ''                 | 'CS17501FE00'           | 'R0201'             | '(SMR0201AW)'                  | '750'     | '1%'    | '1/20W'  | 'IO'       | 'RES CHIP 750 1/20W +-1%(0201)'                    | 'CHIPR0201'    | ''          | ''            | '20180807'
 '8.45K'      | '1%'      | '1/20W'  | '0201LF'  | 'CHIP'   | 'CS28451FE01'(!)        = ''              | ''                 | 'CS28451FE01'           | 'R0201'             | '(SMR0201AW)'                  | '8.45K'   | '1%'    | '1/20W'  | 'DISCRETE' | 'RES CHIP 8.45K 1/20W +-1%(0201)'                  | 'CHIPR0201'    | ''          | ''            | '20180807'
 '8.45K'      | '1%'      | '1/20W'  | '0201LF'  | 'EMPTY'  | 'CS28451FE01'(!)        = ''              | ''                 | 'CS28451FE01'           | 'R0201'             | '(SMR0201AW)'                  | '8.45K'   | '1%'    | '1/20W'  | 'IO'       | 'RES CHIP 8.45K 1/20W +-1%(0201)'                  | 'CHIPR0201'    | ''          | ''            | '20180807'
 '12.4K'      | '1%'      | '1/20W'  | '0201LF'  | 'CHIP'   | 'CS31241FE02'(!)        = ''              | ''                 | 'CS31241FE02'           | 'R0201'             | '(SMR0201AW)'                  | '12.4K'   | '1%'    | '1/20W'  | 'DISCRETE' | 'RES CHIP 12.4K 1/20W +-1% (0201) '                | 'CHIPR0201'    | ''          | ''            | '20180807'
 '12.4K'      | '1%'      | '1/20W'  | '0201LF'  | 'EMPTY'  | 'CS31241FE02'(!)        = ''              | ''                 | 'CS31241FE02'           | 'R0201'             | '(SMR0201AW)'                  | '12.4K'   | '1%'    | '1/20W'  | 'IO'       | 'RES CHIP 12.4K 1/20W +-1% (0201) '                | 'CHIPR0201'    | ''          | ''            | '20180807'
 '19.6K'      | '1%'      | '1/20W'  | '0201LF'  | 'CHIP'   | 'CS31961FE01'(!)        = ''              | ''                 | 'CS31961FE01'           | 'R0201'             | '(SMR0201AW)'                  | '19.6K'   | '1%'    | '1/20W'  | 'DISCRETE' | 'RES CHIP 19.6K 1/20W +-1%(0201)'                  | 'CHIPR0201'    | ''          | ''            | '20180807'
 '19.6K'      | '1%'      | '1/20W'  | '0201LF'  | 'EMPTY'  | 'CS31961FE01'(!)        = ''              | ''                 | 'CS31961FE01'           | 'R0201'             | '(SMR0201AW)'                  | '19.6K'   | '1%'    | '1/20W'  | 'IO'       | 'RES CHIP 19.6K 1/20W +-1%(0201)'                  | 'CHIPR0201'    | ''          | ''            | '20180807'
 '44.2'       | '1%'      | '1/20W'  | '0201LF'  | 'CHIP'   | 'CS04421FE00'(!)        = ''              | ''                 | 'CS04421FE00'           | 'R0201'             | '(SMR0201AW)'                  | '44.2'    | '1%'    | '1/20W'  | 'DISCRETE' | 'RES CHIP 44.2 1/20W +-1%(0201)'                   | 'CHIPR0201'    | ''          | ''            | '20180807'
 '44.2'       | '1%'      | '1/20W'  | '0201LF'  | 'EMPTY'  | 'CS04421FE00'(!)        = ''              | ''                 | 'CS04421FE00'           | 'R0201'             | '(SMR0201AW)'                  | '44.2'    | '1%'    | '1/20W'  | 'IO'       | 'RES CHIP 44.2 1/20W +-1%(0201)'                   | 'CHIPR0201'    | ''          | ''            | '20180807'
 '33K'        | '1%'      | '1/20W'  | '0201LF'  | 'CHIP'   | 'CS33301FE00'(!)        = ''              | ''                 | 'CS33301FE00'           | 'R0201'             | '(SMR0201AW)'                  | '33K'     | '1%'    | '1/20W'  | 'DISCRETE' | 'RES CHIP 33K(1/20W,+-1%,0201)'                    | 'CHIPR0201'    | ''          | ''            | '20180807'
 '33K'        | '1%'      | '1/20W'  | '0201LF'  | 'EMPTY'  | 'CS33301FE00'(!)        = ''              | ''                 | 'CS33301FE00'           | 'R0201'             | '(SMR0201AW)'                  | '33K'     | '1%'    | '1/20W'  | 'IO'       | 'RES CHIP 33K(1/20W,+-1%,0201)'                    | 'CHIPR0201'    | ''          | ''            | '20180807'
 '37.4K'      | '1%'      | '1/20W'  | '0201LF'  | 'CHIP'   | 'CS33741FE01'(!)        = ''              | ''                 | 'CS33741FE01'           | 'R0201'             | '(SMR0201AW)'                  | '37.4K'   | '1%'    | '1/20W'  | 'DISCRETE' | 'RES CHIP 37.4K(1/20W,+-1%,0201)'                  | 'CHIPR0201'    | ''          | ''            | '20180807'
 '37.4K'      | '1%'      | '1/20W'  | '0201LF'  | 'EMPTY'  | 'CS33741FE01'(!)        = ''              | ''                 | 'CS33741FE01'           | 'R0201'             | '(SMR0201AW)'                  | '37.4K'   | '1%'    | '1/20W'  | 'IO'       | 'RES CHIP 37.4K(1/20W,+-1%,0201)'                  | 'CHIPR0201'    | ''          | ''            | '20180807'
 '39.2K'      | '1%'      | '1/20W'  | '0201LF'  | 'CHIP'   | 'CS33921FE00'(!)        = ''              | ''                 | 'CS33921FE00'           | 'R0201'             | '(SMR0201AW)'                  | '39.2K'   | '1%'    | '1/20W'  | 'DISCRETE' | 'RES CHIP 39.2K 1/20W +-1%(0201)'                  | 'CHIPR0201'    | ''          | ''            | '20180807'
 '39.2K'      | '1%'      | '1/20W'  | '0201LF'  | 'EMPTY'  | 'CS33921FE00'(!)        = ''              | ''                 | 'CS33921FE00'           | 'R0201'             | '(SMR0201AW)'                  | '39.2K'   | '1%'    | '1/20W'  | 'IO'       | 'RES CHIP 39.2K 1/20W +-1%(0201)'                  | 'CHIPR0201'    | ''          | ''            | '20180807'
 '47.5K'      | '1%'      | '1/20W'  | '0201LF'  | 'CHIP'   | 'CS34751FE02'(!)        = ''              | ''                 | 'CS34751FE02'           | 'R0201'             | '(SMR0201AW)'                  | '47.5K'   | '1%'    | '1/20W'  | 'DISCRETE' | 'RES CHIP 47.5K 1/20W +-1%(0201)'                  | 'CHIPR0201'    | ''          | ''            | '20180807'
 '47.5K'      | '1%'      | '1/20W'  | '0201LF'  | 'EMPTY'  | 'CS34751FE02'(!)        = ''              | ''                 | 'CS34751FE02'           | 'R0201'             | '(SMR0201AW)'                  | '47.5K'   | '1%'    | '1/20W'  | 'IO'       | 'RES CHIP 47.5K 1/20W +-1%(0201)'                  | 'CHIPR0201'    | ''          | ''            | '20180807'
 '52.3K'      | '1%'      | '1/20W'  | '0201LF'  | 'CHIP'   | 'CS35231FE01'(!)        = ''              | ''                 | 'CS35231FE01'           | 'R0201'             | '(SMR0201AW)'                  | '52.3K'   | '1%'    | '1/20W'  | 'DISCRETE' | 'RES CHIP 52.3K 1/20W +-1%(0201)'                  | 'CHIPR0201'    | ''          | ''            | '20180807'
 '52.3K'      | '1%'      | '1/20W'  | '0201LF'  | 'EMPTY'  | 'CS35231FE01'(!)        = ''              | ''                 | 'CS35231FE01'           | 'R0201'             | '(SMR0201AW)'                  | '52.3K'   | '1%'    | '1/20W'  | 'IO'       | 'RES CHIP 52.3K 1/20W +-1%(0201)'                  | 'CHIPR0201'    | ''          | ''            | '20180807'
 '64.9K'      | '1%'      | '1/20W'  | '0201LF'  | 'CHIP'   | 'CS36491FE00'(!)        = ''              | ''                 | 'CS36491FE00'           | 'R0201'             | '(SMR0201AW)'                  | '64.9K'   | '1%'    | '1/20W'  | 'DISCRETE' | 'RES CHIP 64.9K 1/20W +-1%(0201)'                  | 'CHIPR0201'    | ''          | ''            | '20180807'
 '64.9K'      | '1%'      | '1/20W'  | '0201LF'  | 'EMPTY'  | 'CS36491FE00'(!)        = ''              | ''                 | 'CS36491FE00'           | 'R0201'             | '(SMR0201AW)'                  | '64.9K'   | '1%'    | '1/20W'  | 'IO'       | 'RES CHIP 64.9K 1/20W +-1%(0201)'                  | 'CHIPR0201'    | ''          | ''            | '20180807'
 '66.5K'      | '1%'      | '1/20W'  | '0201LF'  | 'CHIP'   | 'CS36651FE04'(!)        = ''              | ''                 | 'CS36651FE04'           | 'R0201'             | '(SMR0201AW)'                  | '66.5K'   | '1%'    | '1/20W'  | 'DISCRETE' | 'RES CHIP 66.5K 1/20W +-1%(0201)'                  | 'CHIPR0201'    | ''          | ''            | '20180807'
 '66.5K'      | '1%'      | '1/20W'  | '0201LF'  | 'EMPTY'  | 'CS36651FE04'(!)        = ''              | ''                 | 'CS36651FE04'           | 'R0201'             | '(SMR0201AW)'                  | '66.5K'   | '1%'    | '1/20W'  | 'IO'       | 'RES CHIP 66.5K 1/20W +-1%(0201)'                  | 'CHIPR0201'    | ''          | ''            | '20180807'
 '97.6K'      | '1%'      | '1/20W'  | '0201LF'  | 'CHIP'   | 'CS39761FE00'(!)        = ''              | ''                 | 'CS39761FE00'           | 'R0201'             | '(SMR0201AW)'                  | '97.6K'   | '1%'    | '1/20W'  | 'DISCRETE' | 'RES CHIP 97.6K 1/20W,+-1%(0201)'                  | 'CHIPR0201'    | ''          | ''            | '20180807'
 '97.6K'      | '1%'      | '1/20W'  | '0201LF'  | 'EMPTY'  | 'CS39761FE00'(!)        = ''              | ''                 | 'CS39761FE00'           | 'R0201'             | '(SMR0201AW)'                  | '97.6K'   | '1%'    | '1/20W'  | 'IO'       | 'RES CHIP 97.6K 1/20W,+-1%(0201)'                  | 'CHIPR0201'    | ''          | ''            | '20180807'
 '107K'       | '1%'      | '1/20W'  | '0201LF'  | 'CHIP'   | 'CS41071FE00'(!)        = ''              | ''                 | 'CS41071FE00'           | 'R0201'             | '(SMR0201AW)'                  | '107K'    | '1%'    | '1/20W'  | 'DISCRETE' | 'RES CHIP 107K 1/20W +-1%(0201)'                   | 'CHIPR0201'    | ''          | ''            | '20180807'
 '107K'       | '1%'      | '1/20W'  | '0201LF'  | 'EMPTY'  | 'CS41071FE00'(!)        = ''              | ''                 | 'CS41071FE00'           | 'R0201'             | '(SMR0201AW)'                  | '107K'    | '1%'    | '1/20W'  | 'IO'       | 'RES CHIP 107K 1/20W +-1%(0201)'                   | 'CHIPR0201'    | ''          | ''            | '20180807'
 '124K'       | '1%'      | '1/20W'  | '0201LF'  | 'CHIP'   | 'CS41241FE01'(!)        = ''              | ''                 | 'CS41241FE01'           | 'R0201'             | '(SMR0201AW)'                  | '124K'    | '1%'    | '1/20W'  | 'DISCRETE' | 'RES CHIP 124K 1/20W +-1%(0201)'                   | 'CHIPR0201'    | ''          | ''            | '20180807'
 '124K'       | '1%'      | '1/20W'  | '0201LF'  | 'EMPTY'  | 'CS41241FE01'(!)        = ''              | ''                 | 'CS41241FE01'           | 'R0201'             | '(SMR0201AW)'                  | '124K'    | '1%'    | '1/20W'  | 'IO'       | 'RES CHIP 124K 1/20W +-1%(0201)'                   | 'CHIPR0201'    | ''          | ''            | '20180807'
 '130K'       | '1%'      | '1/20W'  | '0201LF'  | 'CHIP'   | 'CS41301FE00'(!)        = ''              | ''                 | 'CS41301FE00'           | 'R0201'             | '(SMR0201AW)'                  | '130K'    | '1%'    | '1/20W'  | 'DISCRETE' | 'RES CHIP 130K 1/20W +-1%(0201)'                   | 'CHIPR0201'    | ''          | ''            | '20180807'
 '130K'       | '1%'      | '1/20W'  | '0201LF'  | 'EMPTY'  | 'CS41301FE00'(!)        = ''              | ''                 | 'CS41301FE00'           | 'R0201'             | '(SMR0201AW)'                  | '130K'    | '1%'    | '1/20W'  | 'IO'       | 'RES CHIP 130K 1/20W +-1%(0201)'                   | 'CHIPR0201'    | ''          | ''            | '20180807'
 '412K'       | '1%'      | '1/20W'  | '0201LF'  | 'CHIP'   | 'CS44121FE00'(!)        = ''              | ''                 | 'CS44121FE00'           | 'R0201'             | '(SMR0201AW)'                  | '412K'    | '1%'    | '1/20W'  | 'DISCRETE' | 'RES CHIP 412K 1/20W +1%(0201)'                    | 'CHIPR0201'    | ''          | ''            | '20180807'
 '412K'       | '1%'      | '1/20W'  | '0201LF'  | 'EMPTY'  | 'CS44121FE00'(!)        = ''              | ''                 | 'CS44121FE00'           | 'R0201'             | '(SMR0201AW)'                  | '412K'    | '1%'    | '1/20W'  | 'IO'       | 'RES CHIP 412K 1/20W +1%(0201)'                    | 'CHIPR0201'    | ''          | ''            | '20180807'
 '470K'       | '1%'      | '1/20W'  | '0201LF'  | 'CHIP'   | 'CS44701FE00'(!)        = 'End of Design' | 'Comp-Approve'     | 'CS44701FE00'           | 'R0201'             | '(SMR0201AW)'                  | '470K'    | '1%'    | '1/20W'  | 'DISCRETE' | 'RES CHIP 470K 1/20W +-1%(0201)'                   | 'CHIPR0201'    | ''          | ''            | '20180807'
 '470K'       | '1%'      | '1/20W'  | '0201LF'  | 'EMPTY'  | 'CS44701FE00'(!)        = 'End of Design' | 'Comp-Approve'     | 'CS44701FE00'           | 'R0201'             | '(SMR0201AW)'                  | '470K'    | '1%'    | '1/20W'  | 'IO'       | 'RES CHIP 470K 1/20W +-1%(0201)'                   | 'CHIPR0201'    | ''          | ''            | '20180807'
 '510K'       | '5%'      | '1/20W'  | '0201LF'  | 'CHIP'   | 'CS45101JE00'(!)        = ''              | ''                 | 'CS45101JE00'           | 'R0201'             | '(SMR0201AW)'                  | '510K'    | '5%'    | '1/20W'  | 'DISCRETE' | 'RES CHIP 510K 1/20W +-5%(0201)'                   | 'CHIPR0201'    | ''          | ''            | '20180807'
 '510K'       | '5%'      | '1/20W'  | '0201LF'  | 'EMPTY'  | 'CS45101JE00'(!)        = ''              | ''                 | 'CS45101JE00'           | 'R0201'             | '(SMR0201AW)'                  | '510K'    | '5%'    | '1/20W'  | 'IO'       | 'RES CHIP 510K 1/20W +-5%(0201)'                   | 'CHIPR0201'    | ''          | ''            | '20180807'
 '562K'       | '1%'      | '1/20W'  | '0201LF'  | 'CHIP'   | 'CS45621FE00'(!)        = ''              | ''                 | 'CS45621FE00'           | 'R0201'             | '(SMR0201AW)'                  | '562K'    | '1%'    | '1/20W'  | 'DISCRETE' | 'RES CHIP 562K 1/20W +-1%(0201)'                   | 'CHIPR0201'    | ''          | ''            | '20180807'
 '562K'       | '1%'      | '1/20W'  | '0201LF'  | 'EMPTY'  | 'CS45621FE00'(!)        = ''              | ''                 | 'CS45621FE00'           | 'R0201'             | '(SMR0201AW)'                  | '562K'    | '1%'    | '1/20W'  | 'IO'       | 'RES CHIP 562K 1/20W +-1%(0201)'                   | 'CHIPR0201'    | ''          | ''            | '20180807'
 '10M'        | '1%'      | '1/20W'  | '0201LF'  | 'CHIP'   | 'CS61001FE00'(!)        = ''              | ''                 | 'CS61001FE00'           | 'R0201'             | '(SMR0201AW)'                  | '10M'     | '1%'    | '1/20W'  | 'DISCRETE' | 'RES CHIP 10M 1/20W +-1%(0201)'                    | 'CHIPR0201'    | ''          | ''            | '20180807'
 '10M'        | '1%'      | '1/20W'  | '0201LF'  | 'EMPTY'  | 'CS61001FE00'(!)        = ''              | ''                 | 'CS61001FE00'           | 'R0201'             | '(SMR0201AW)'                  | '10M'     | '1%'    | '1/20W'  | 'IO'       | 'RES CHIP 10M 1/20W +-1%(0201)'                    | 'CHIPR0201'    | ''          | ''            | '20180807'
 '27K'        | '1%'      | '1/20W'  | '0201LF'  | 'CHIP'   | 'CS32701FE01'(!)        = ''              | ''                 | 'CS32701FE01'           | 'R0201'             | '(SMR0201AW)'                  | '27K'     | '1%'    | '1/20W'  | 'DISCRETE' | 'RES CHIP 27K(1/20W,+-1%,0201)'                    | 'CHIPR0201'    | ''          | ''            | '20180807'
 '27K'        | '1%'      | '1/20W'  | '0201LF'  | 'EMPTY'  | 'CS32701FE01'(!)        = ''              | ''                 | 'CS32701FE01'           | 'R0201'             | '(SMR0201AW)'                  | '27K'     | '1%'    | '1/20W'  | 'IO'       | 'RES CHIP 27K(1/20W,+-1%,0201)'                    | 'CHIPR0201'    | ''          | ''            | '20180807'
 '30.1K'      | '1%'      | '1/20W'  | '0201LF'  | 'CHIP'   | 'CS33011FE00'(!)        = 'End of Design' | 'Comp-Approve'     | 'CS33011FE00'           | 'R0201'             | '(SMR0201AW)'                  | '30.1K'   | '1%'    | '1/20W'  | 'DISCRETE' | 'RES CHIP 30.1K 1/20W +-1%(0201)'                  | 'CHIPR0201'    | ''          | ''            | '20180807'
 '30.1K'      | '1%'      | '1/20W'  | '0201LF'  | 'EMPTY'  | 'CS33011FE00'(!)        = 'End of Design' | 'Comp-Approve'     | 'CS33011FE00'           | 'R0201'             | '(SMR0201AW)'                  | '30.1K'   | '1%'    | '1/20W'  | 'IO'       | 'RES CHIP 30.1K 1/20W +-1%(0201)'                  | 'CHIPR0201'    | ''          | ''            | '20180807'
 '220K'       | '5%'      | '1/20W'  | '0201LF'  | 'CHIP'   | 'CS42201JE00'(!)        = ''              | ''                 | 'CS42201JE00'           | 'R0201'             | '(SMR0201AW)'                  | '220K'    | '5%'    | '1/20W'  | 'DISCRETE' | 'RES CHIP 220K 1/20W +-5% (0201)'                  | 'CHIPR0201'    | ''          | ''            | '20180807'
 '220K'       | '5%'      | '1/20W'  | '0201LF'  | 'EMPTY'  | 'CS42201JE00'(!)        = ''              | ''                 | 'CS42201JE00'           | 'R0201'             | '(SMR0201AW)'                  | '220K'    | '5%'    | '1/20W'  | 'IO'       | 'RES CHIP 220K 1/20W +-5% (0201)'                  | 'CHIPR0201'    | ''          | ''            | '20180807'
 '20'         | '1%'      | '1/20W'  | '0201LF'  | 'CHIP'   | 'CS02001FE00'(!)        = ''              | ''                 | 'CS02001FE00'           | 'R0201'             | '(SMR0201AW)'                  | '20'      | '1%'    | '1/20W'  | 'DISCRETE' | 'RES CHIP 20 1/20W +-1%(0201)'                     | 'CHIPR0201'    | ''          | ''            | '20120118'
 '20'         | '1%'      | '1/20W'  | '0201LF'  | 'EMPTY'  | 'CS02001FE00'(!)        = ''              | ''                 | 'CS02001FE00'           | 'R0201'             | '(SMR0201AW)'                  | '20'      | '1%'    | '1/20W'  | 'IO'       | 'RES CHIP 20 1/20W +-1%(0201)'                     | 'CHIPR0201'    | ''          | ''            | '20120118'
 '121'        | '1%'      | '1/20W'  | '0201LF'  | 'CHIP'   | 'CS11211FE00'(!)        = ''              | ''                 | 'CS11211FE00'           | 'R0201'             | '(SMR0201AW)'                  | '121'     | '1%'    | '1/20W'  | 'DISCRETE' | 'RES CHIP 121 1/20W +-1%(0201)'                    | 'CHIPR0201'    | ''          | ''            | '20180808'
 '121'        | '1%'      | '1/20W'  | '0201LF'  | 'EMPTY'  | 'CS11211FE00'(!)        = ''              | ''                 | 'CS11211FE00'           | 'R0201'             | '(SMR0201AW)'                  | '121'     | '1%'    | '1/20W'  | 'IO'       | 'RES CHIP 121 1/20W +-1%(0201)'                    | 'CHIPR0201'    | ''          | ''            | '20180808'
 '2.4K'       | '1%'      | '1/20W'  | '0201LF'  | 'CHIP'   | 'CS22401FE00'(!)        = ''              | ''                 | 'CS22401FE00'           | 'R0201'             | '(SMR0201AW)'                  | '2.4K'    | '1%'    | '1/20W'  | 'DISCRETE' | 'RES CHIP 2.4K 1/20W +-1%(0201)'                   | 'CHIPR0201'    | ''          | ''            | '20180808'
 '2.4K'       | '1%'      | '1/20W'  | '0201LF'  | 'EMPTY'  | 'CS22401FE00'(!)        = ''              | ''                 | 'CS22401FE00'           | 'R0201'             | '(SMR0201AW)'                  | '2.4K'    | '1%'    | '1/20W'  | 'IO'       | 'RES CHIP 2.4K 1/20W +-1%(0201)'                   | 'CHIPR0201'    | ''          | ''            | '20180808'
 '2.49K'      | '1%'      | '1/20W'  | '0201LF'  | 'CHIP'   | 'CS22491FE00'(!)        = 'End of Design' | 'Comp-Approve'     | 'CS22491FE00'           | 'R0201'             | '(SMR0201AW)'                  | '2.49K'   | '1%'    | '1/20W'  | 'DISCRETE' | 'RES CHIP 2.49K(1/20W.+-1%.0201)HF'                | 'CHIPR0201'    | ''          | ''            | '20110106'
 '2.49K'      | '1%'      | '1/20W'  | '0201LF'  | 'EMPTY'  | 'CS22491FE00'(!)        = 'End of Design' | 'Comp-Approve'     | 'CS22491FE00'           | 'R0201'             | '(SMR0201AW)'                  | '2.49K'   | '1%'    | '1/20W'  | 'IO'       | 'RES CHIP 2.49K(1/20W.+-1%.0201)HF'                | 'CHIPR0201'    | ''          | ''            | '20110106'
 '2.7K'       | '5%'      | '1/20W'  | '0201LF'  | 'CHIP'   | 'CS22701JE00'(!)        = ''              | ''                 | 'CS22701JE00'           | 'R0201'             | '(SMR0201AW)'                  | '2.7K'    | '5%'    | '1/20W'  | 'DISCRETE' | 'RES CHIP 2.7K 1/20W +-5%(0201)'                   | 'CHIPR0201'    | ''          | ''            | '20180808'
 '2.7K'       | '5%'      | '1/20W'  | '0201LF'  | 'EMPTY'  | 'CS22701JE00'(!)        = ''              | ''                 | 'CS22701JE00'           | 'R0201'             | '(SMR0201AW)'                  | '2.7K'    | '5%'    | '1/20W'  | 'IO'       | 'RES CHIP 2.7K 1/20W +-5%(0201)'                   | 'CHIPR0201'    | ''          | ''            | '20180808'
 '4.02K'      | '1%'      | '1/20W'  | '0201LF'  | 'CHIP'   | 'CS24021FE01'(!)        = ''              | ''                 | 'CS24021FE01'           | 'R0201'             | '(SMR0201AW)'                  | '4.02K'   | '1%'    | '1/20W'  | 'DISCRETE' | 'RES CHIP 4.02K 1/20W +-1%(0201)'                  | 'CHIPR0201'    | ''          | ''            | '20180808'
 '4.02K'      | '1%'      | '1/20W'  | '0201LF'  | 'EMPTY'  | 'CS24021FE01'(!)        = ''              | ''                 | 'CS24021FE01'           | 'R0201'             | '(SMR0201AW)'                  | '4.02K'   | '1%'    | '1/20W'  | 'IO'       | 'RES CHIP 4.02K 1/20W +-1%(0201)'                  | 'CHIPR0201'    | ''          | ''            | '20180808'
 '4.42K'      | '1%'      | '1/20W'  | '0201LF'  | 'CHIP'   | 'CS24421FE01'(!)        = ''              | ''                 | 'CS24421FE01'           | 'R0201'             | '(SMR0201AW)'                  | '4.42K'   | '1%'    | '1/20W'  | 'DISCRETE' | 'RES CHIP 4.42K 1/20W +-1%(0201)'                  | 'CHIPR0201'    | ''          | ''            | '20180808'
 '4.42K'      | '1%'      | '1/20W'  | '0201LF'  | 'EMPTY'  | 'CS24421FE01'(!)        = ''              | ''                 | 'CS24421FE01'           | 'R0201'             | '(SMR0201AW)'                  | '4.42K'   | '1%'    | '1/20W'  | 'IO'       | 'RES CHIP 4.42K 1/20W +-1%(0201)'                  | 'CHIPR0201'    | ''          | ''            | '20180808'
 '4.75K'      | '1%'      | '1/20W'  | '0201LF'  | 'CHIP'   | 'CS24751FE01'(!)        = ''              | ''                 | 'CS24751FE01'           | 'R0201'             | '(SMR0201AW)'                  | '4.75K'   | '1%'    | '1/20W'  | 'DISCRETE' | 'RES CHIP 4.75K (1/20W,+-1%,0201)'                 | 'CHIPR0201'    | ''          | ''            | '20180808'
 '4.75K'      | '1%'      | '1/20W'  | '0201LF'  | 'EMPTY'  | 'CS24751FE01'(!)        = ''              | ''                 | 'CS24751FE01'           | 'R0201'             | '(SMR0201AW)'                  | '4.75K'   | '1%'    | '1/20W'  | 'IO'       | 'RES CHIP 4.75K (1/20W,+-1%,0201)'                 | 'CHIPR0201'    | ''          | ''            | '20180808'
 '4.87K'      | '1%'      | '1/20W'  | '0201LF'  | 'CHIP'   | 'CS24871FE00'(!)        = ''              | ''                 | 'CS24871FE00'           | 'R0201'             | '(SMR0201AW)'                  | '4.87K'   | '1%'    | '1/20W'  | 'DISCRETE' | 'RES CHIP 4.87K 1/20W +-1%(0201)'                  | 'CHIPR0201'    | ''          | ''            | '20180808'
 '4.87K'      | '1%'      | '1/20W'  | '0201LF'  | 'EMPTY'  | 'CS24871FE00'(!)        = ''              | ''                 | 'CS24871FE00'           | 'R0201'             | '(SMR0201AW)'                  | '4.87K'   | '1%'    | '1/20W'  | 'IO'       | 'RES CHIP 4.87K 1/20W +-1%(0201)'                  | 'CHIPR0201'    | ''          | ''            | '20180808'
 '34.8K'      | '1%'      | '1/20W'  | '0201LF'  | 'CHIP'   | 'CS33481FE01'(!)        = ''              | ''                 | 'CS33481FE01'           | 'R0201'             | '(SMR0201AW)'                  | '34.8K'   | '1%'    | '1/20W'  | 'DISCRETE' | 'RES CHIP 34.8K 1/20W +-1%(0201)'                  | 'CHIPR0201'    | ''          | ''            | '20180808'
 '34.8K'      | '1%'      | '1/20W'  | '0201LF'  | 'EMPTY'  | 'CS33481FE01'(!)        = ''              | ''                 | 'CS33481FE01'           | 'R0201'             | '(SMR0201AW)'                  | '34.8K'   | '1%'    | '1/20W'  | 'IO'       | 'RES CHIP 34.8K 1/20W +-1%(0201)'                  | 'CHIPR0201'    | ''          | ''            | '20180808'
 '6.19K'      | '1%'      | '1/20W'  | '0201LF'  | 'CHIP'   | 'CS26191FE00'(!)        = ''              | ''                 | 'CS26191FE00'           | 'R0201'             | '(SMR0201AW)'                  | '6.19K'   | '1%'    | '1/20W'  | 'DISCRETE' | 'RES CHIP 6.19K 1/20W +-1%(0201)'                  | 'CHIPR0201'    | ''          | ''            | '20180808'
 '6.19K'      | '1%'      | '1/20W'  | '0201LF'  | 'EMPTY'  | 'CS26191FE00'(!)        = ''              | ''                 | 'CS26191FE00'           | 'R0201'             | '(SMR0201AW)'                  | '6.19K'   | '1%'    | '1/20W'  | 'IO'       | 'RES CHIP 6.19K 1/20W +-1%(0201)'                  | 'CHIPR0201'    | ''          | ''            | '20180808'
 '402'        | '1%'      | '1/20W'  | '0201LF'  | 'CHIP'   | 'CS14021FE01'(!)        = ''              | ''                 | 'CS14021FE01'           | 'R0201'             | '(SMR0201AW)'                  | '402'     | '1%'    | '1/20W'  | 'DISCRETE' | 'RES CHIP 402 1/20W +-1%(0201)'                    | 'CHIPR0201'    | ''          | ''            | '20180808'
 '402'        | '1%'      | '1/20W'  | '0201LF'  | 'EMPTY'  | 'CS14021FE01'(!)        = ''              | ''                 | 'CS14021FE01'           | 'R0201'             | '(SMR0201AW)'                  | '402'     | '1%'    | '1/20W'  | 'IO'       | 'RES CHIP 402 1/20W +-1%(0201)'                    | 'CHIPR0201'    | ''          | ''            | '20180808'
 '6.81K'      | '1%'      | '1/20W'  | '0201LF'  | 'CHIP'   | 'CS26811FE00'(!)        = ''              | ''                 | 'CS26811FE00'           | 'R0201'             | '(SMR0201AW)'                  | '6.81K'   | '1%'    | '1/20W'  | 'DISCRETE' | 'RES CHIP 6.81K 1/20W +-1%(0201)'                  | 'CHIPR0201'    | ''          | ''            | '20180808'
 '6.81K'      | '1%'      | '1/20W'  | '0201LF'  | 'EMPTY'  | 'CS26811FE00'(!)        = ''              | ''                 | 'CS26811FE00'           | 'R0201'             | '(SMR0201AW)'                  | '6.81K'   | '1%'    | '1/20W'  | 'IO'       | 'RES CHIP 6.81K 1/20W +-1%(0201)'                  | 'CHIPR0201'    | ''          | ''            | '20180808'
 '7.5K'       | '1%'      | '1/20W'  | '0201LF'  | 'CHIP'   | 'CS27501FE00'(!)        = ''              | ''                 | 'CS27501FE00'           | 'R0201'             | '(SMR0201AW)'                  | '7.5K'    | '1%'    | '1/20W'  | 'DISCRETE' | 'RES CHIP 7.5K 1/20W +-1%(0201)'                   | 'CHIPR0201'    | ''          | ''            | '20180808'
 '7.5K'       | '1%'      | '1/20W'  | '0201LF'  | 'EMPTY'  | 'CS27501FE00'(!)        = ''              | ''                 | 'CS27501FE00'           | 'R0201'             | '(SMR0201AW)'                  | '7.5K'    | '1%'    | '1/20W'  | 'IO'       | 'RES CHIP 7.5K 1/20W +-1%(0201)'                   | 'CHIPR0201'    | ''          | ''            | '20180808'
 '8.66K'      | '1%'      | '1/20W'  | '0201LF'  | 'CHIP'   | 'CS28661FE00'(!)        = ''              | ''                 | 'CS28661FE00'           | 'R0201'             | '(SMR0201AW)'                  | '8.66K'   | '1%'    | '1/20W'  | 'DISCRETE' | 'RES CHIP 8.66K 1/20W,+-1%(0201)'                  | 'CHIPR0201'    | ''          | ''            | '20180808'
 '8.66K'      | '1%'      | '1/20W'  | '0201LF'  | 'EMPTY'  | 'CS28661FE00'(!)        = ''              | ''                 | 'CS28661FE00'           | 'R0201'             | '(SMR0201AW)'                  | '8.66K'   | '1%'    | '1/20W'  | 'IO'       | 'RES CHIP 8.66K 1/20W,+-1%(0201)'                  | 'CHIPR0201'    | ''          | ''            | '20180808'
 '11K'        | '1%'      | '1/20W'  | '0201LF'  | 'CHIP'   | 'CS31101FE00'(!)        = ''              | ''                 | 'CS31101FE00'           | 'R0201'             | '(SMR0201AW)'                  | '11K'     | '1%'    | '1/20W'  | 'DISCRETE' | 'RES CHIP 11K 1/20W +-1% (0201)'                   | 'CHIPR0201'    | ''          | ''            | '20180808'
 '11K'        | '1%'      | '1/20W'  | '0201LF'  | 'EMPTY'  | 'CS31101FE00'(!)        = ''              | ''                 | 'CS31101FE00'           | 'R0201'             | '(SMR0201AW)'                  | '11K'     | '1%'    | '1/20W'  | 'IO'       | 'RES CHIP 11K 1/20W +-1% (0201)'                   | 'CHIPR0201'    | ''          | ''            | '20180808'
 '11.8K'      | '1%'      | '1/20W'  | '0201LF'  | 'CHIP'   | 'CS31181FE01'(!)        = ''              | ''                 | 'CS31181FE01'           | 'R0201'             | '(SMR0201AW)'                  | '11.8K'   | '1%'    | '1/20W'  | 'DISCRETE' | 'RES CHIP 11.8K 1/20W +-1%(0201)'                  | 'CHIPR0201'    | ''          | ''            | '20180809'
 '11.8K'      | '1%'      | '1/20W'  | '0201LF'  | 'EMPTY'  | 'CS31181FE01'(!)        = ''              | ''                 | 'CS31181FE01'           | 'R0201'             | '(SMR0201AW)'                  | '11.8K'   | '1%'    | '1/20W'  | 'IO'       | 'RES CHIP 11.8K 1/20W +-1%(0201)'                  | 'CHIPR0201'    | ''          | ''            | '20180809'
 '12.1K'      | '1%'      | '1/20W'  | '0201LF'  | 'CHIP'   | 'CS31211FE08'(!)        = ''              | ''                 | 'CS31211FE08'           | 'R0201'             | '(SMR0201AW)'                  | '12.1K'   | '1%'    | '1/20W'  | 'DISCRETE' | 'RES CHIP 12.1K 1/20W +-1%(0201)'                  | 'CHIPR0201'    | ''          | ''            | '20180809'
 '12.1K'      | '1%'      | '1/20W'  | '0201LF'  | 'EMPTY'  | 'CS31211FE08'(!)        = ''              | ''                 | 'CS31211FE08'           | 'R0201'             | '(SMR0201AW)'                  | '12.1K'   | '1%'    | '1/20W'  | 'IO'       | 'RES CHIP 12.1K 1/20W +-1%(0201)'                  | 'CHIPR0201'    | ''          | ''            | '20180809'
 '13K'        | '1%'      | '1/20W'  | '0201LF'  | 'CHIP'   | 'CS31301FE01'(!)        = ''              | ''                 | 'CS31301FE01'           | 'R0201'             | '(SMR0201AW)'                  | '13K'     | '1%'    | '1/20W'  | 'DISCRETE' | 'RES CHIP 13K 1/20W +-1%(0201)'                    | 'CHIPR0201'    | ''          | ''            | '20180808'
 '13K'        | '1%'      | '1/20W'  | '0201LF'  | 'EMPTY'  | 'CS31301FE01'(!)        = ''              | ''                 | 'CS31301FE01'           | 'R0201'             | '(SMR0201AW)'                  | '13K'     | '1%'    | '1/20W'  | 'IO'       | 'RES CHIP 13K 1/20W +-1%(0201)'                    | 'CHIPR0201'    | ''          | ''            | '20180808'
 '14K'        | '1%'      | '1/20W'  | '0201LF'  | 'CHIP'   | 'CS31401FE01'(!)        = ''              | ''                 | 'CS31401FE01'           | 'R0201'             | '(SMR0201AW)'                  | '14K'     | '1%'    | '1/20W'  | 'DISCRETE' | 'RES CHIP 14K 1/20W +-1%(0201)'                    | 'CHIPR0201'    | ''          | ''            | '20180808'
 '14K'        | '1%'      | '1/20W'  | '0201LF'  | 'EMPTY'  | 'CS31401FE01'(!)        = ''              | ''                 | 'CS31401FE01'           | 'R0201'             | '(SMR0201AW)'                  | '14K'     | '1%'    | '1/20W'  | 'IO'       | 'RES CHIP 14K 1/20W +-1%(0201)'                    | 'CHIPR0201'    | ''          | ''            | '20180808'
 '14.3K'      | '1%'      | '1/20W'  | '0201LF'  | 'CHIP'   | 'CS31431FE00'(!)        = ''              | ''                 | 'CS31431FE00'           | 'R0201'             | '(SMR0201AW)'                  | '14.3K'   | '1%'    | '1/20W'  | 'DISCRETE' | 'RES CHIP 14.3K 1/20W +-1%(0201)'                  | 'CHIPR0201'    | ''          | ''            | '20180808'
 '14.3K'      | '1%'      | '1/20W'  | '0201LF'  | 'EMPTY'  | 'CS31431FE00'(!)        = ''              | ''                 | 'CS31431FE00'           | 'R0201'             | '(SMR0201AW)'                  | '14.3K'   | '1%'    | '1/20W'  | 'IO'       | 'RES CHIP 14.3K 1/20W +-1%(0201)'                  | 'CHIPR0201'    | ''          | ''            | '20180808'
 '47.5'       | '1%'      | '1/20W'  | '0201LF'  | 'CHIP'   | 'CS04751FE00'(!)        = ''              | ''                 | 'CS04751FE00'           | 'R0201'             | '(SMR0201AW)'                  | '47.5'    | '1%'    | '1/20W'  | 'DISCRETE' | 'RES CHIP 47.5 1/20W +-1%(0201)'                   | 'CHIPR0201'    | ''          | ''            | '20180808'
 '47.5'       | '1%'      | '1/20W'  | '0201LF'  | 'EMPTY'  | 'CS04751FE00'(!)        = ''              | ''                 | 'CS04751FE00'           | 'R0201'             | '(SMR0201AW)'                  | '47.5'    | '1%'    | '1/20W'  | 'IO'       | 'RES CHIP 47.5 1/20W +-1%(0201)'                   | 'CHIPR0201'    | ''          | ''            | '20180808'
 '21K'        | '1%'      | '1/20W'  | '0201LF'  | 'CHIP'   | 'CS32101FE00'(!)        = ''              | ''                 | 'CS32101FE00'           | 'R0201'             | '(SMR0201AW)'                  | '21K'     | '1%'    | '1/20W'  | 'DISCRETE' | 'RES CHIP 21K(1/20W,+-1%,0201)'                    | 'CHIPR0201'    | ''          | ''            | '20180808'
 '21K'        | '1%'      | '1/20W'  | '0201LF'  | 'EMPTY'  | 'CS32101FE00'(!)        = ''              | ''                 | 'CS32101FE00'           | 'R0201'             | '(SMR0201AW)'                  | '21K'     | '1%'    | '1/20W'  | 'IO'       | 'RES CHIP 21K(1/20W,+-1%,0201)'                    | 'CHIPR0201'    | ''          | ''            | '20180808'
 '22K'        | '1%'      | '1/20W'  | '0201LF'  | 'CHIP'   | 'CS32201FE00'(!)        = 'End of Design' | 'Comp-Approve'     | 'CS32201FE00'           | 'R0201'             | '(SMR0201AW)'                  | '22K'     | '1%'    | '1/20W'  | 'DISCRETE' | 'RES CHIP 22K 1/20W +-1%(0201)'                    | 'CHIPR0201'    | ''          | ''            | '20180808'
 '22K'        | '1%'      | '1/20W'  | '0201LF'  | 'EMPTY'  | 'CS32201FE00'(!)        = 'End of Design' | 'Comp-Approve'     | 'CS32201FE00'           | 'R0201'             | '(SMR0201AW)'                  | '22K'     | '1%'    | '1/20W'  | 'IO'       | 'RES CHIP 22K 1/20W +-1%(0201)'                    | 'CHIPR0201'    | ''          | ''            | '20180808'
 '26.1K'      | '1%'      | '1/20W'  | '0201LF'  | 'CHIP'   | 'CS32611FE01'(!)        = ''              | ''                 | 'CS32611FE01'           | 'R0201'             | '(SMR0201AW)'                  | '26.1K'   | '1%'    | '1/20W'  | 'DISCRETE' | 'RES CHIP 26.1K 1/20W +-1%(0201)'                  | 'CHIPR0201'    | ''          | ''            | '20180808'
 '26.1K'      | '1%'      | '1/20W'  | '0201LF'  | 'EMPTY'  | 'CS32611FE01'(!)        = ''              | ''                 | 'CS32611FE01'           | 'R0201'             | '(SMR0201AW)'                  | '26.1K'   | '1%'    | '1/20W'  | 'IO'       | 'RES CHIP 26.1K 1/20W +-1%(0201)'                  | 'CHIPR0201'    | ''          | ''            | '20180808'
 '26.7K'      | '1%'      | '1/20W'  | '0201LF'  | 'CHIP'   | 'CS32671FE00'(!)        = ''              | ''                 | 'CS32671FE00'           | 'R0201'             | '(SMR0201AW)'                  | '26.7K'   | '1%'    | '1/20W'  | 'DISCRETE' | 'RES CHIP 26.7K 1/20W +-1%(0201)'                  | 'CHIPR0201'    | ''          | ''            | '20180809'
 '26.7K'      | '1%'      | '1/20W'  | '0201LF'  | 'EMPTY'  | 'CS32671FE00'(!)        = ''              | ''                 | 'CS32671FE00'           | 'R0201'             | '(SMR0201AW)'                  | '26.7K'   | '1%'    | '1/20W'  | 'IO'       | 'RES CHIP 26.7K 1/20W +-1%(0201)'                  | 'CHIPR0201'    | ''          | ''            | '20180809'
 '1K'         | '5%'      | '1/20W'  | '0201LF'  | 'CHIP'   | 'CS21001JE14'(!)        = ''              | ''                 | 'CS21001JE14'           | 'R0201'             | '(SMR0201AW)'                  | '1K'      | '5%'    | '1/20W'  | 'DISCRETE' | 'RES CHIP 1K(1/20W,+-5%,0201)'                     | 'CHIPR0201'    | ''          | ''            | '20180808'
 '1K'         | '5%'      | '1/20W'  | '0201LF'  | 'EMPTY'  | 'CS21001JE14'(!)        = ''              | ''                 | 'CS21001JE14'           | 'R0201'             | '(SMR0201AW)'                  | '1K'      | '5%'    | '1/20W'  | 'IO'       | 'RES CHIP 1K(1/20W,+-5%,0201)'                     | 'CHIPR0201'    | ''          | ''            | '20180808'
 '8.2K'       | '5%'      | '1/20W'  | '0201LF'  | 'CHIP'   | 'CS28201JE00'(!)        = ''              | ''                 | 'CS28201JE00'           | 'R0201'             | '(SMR0201AW)'                  | '8.2K'    | '5%'    | '1/20W'  | 'DISCRETE' | 'RES CHIP 8.2K 1/20W +-5%(0201)'                   | 'CHIPR0201'    | ''          | ''            | '20180808'
 '8.2K'       | '5%'      | '1/20W'  | '0201LF'  | 'EMPTY'  | 'CS28201JE00'(!)        = ''              | ''                 | 'CS28201JE00'           | 'R0201'             | '(SMR0201AW)'                  | '8.2K'    | '5%'    | '1/20W'  | 'IO'       | 'RES CHIP 8.2K 1/20W +-5%(0201)'                   | 'CHIPR0201'    | ''          | ''            | '20180808'
 '47'         | '1%'      | '1/20W'  | '0201LF'  | 'CHIP'   | 'CS04701FE01'(!)        = ''              | ''                 | 'CS04701FE01'           | 'R0201'             | '(SMR0201AW)'                  | '47'      | '1%'    | '1/20W'  | 'DISCRETE' | 'RES CHIP 47 1/20W +-1%(0201)'                     | 'CHIPR0201'    | ''          | ''            | '20180809'
 '47'         | '1%'      | '1/20W'  | '0201LF'  | 'EMPTY'  | 'CS04701FE01'(!)        = ''              | ''                 | 'CS04701FE01'           | 'R0201'             | '(SMR0201AW)'                  | '47'      | '1%'    | '1/20W'  | 'IO'       | 'RES CHIP 47 1/20W +-1%(0201)'                     | 'CHIPR0201'    | ''          | ''            | '20180809'
 '1'          | '1%'      | '1/20W'  | '0201LF'  | 'CHIP'   | 'CS-1001FE00'(!)        = ''              | ''                 | 'CS-1001FE00'           | 'R0201'             | '(SMR0201AW)'                  | '1'       | '1%'    | '1/20W'  | 'DISCRETE' | 'RES CHIP 1 1/20W +-1%(0201)'                      | 'CHIPR0201'    | ''          | ''            | '20180809'
 '1'          | '1%'      | '1/20W'  | '0201LF'  | 'EMPTY'  | 'CS-1001FE00'(!)        = ''              | ''                 | 'CS-1001FE00'           | 'R0201'             | '(SMR0201AW)'                  | '1'       | '1%'    | '1/20W'  | 'IO'       | 'RES CHIP 1 1/20W +-1%(0201)'                      | 'CHIPR0201'    | ''          | ''            | '20180809'
 '5.9K'       | '0.1%'    | '1/20W'  | '0201LF'  | 'CHIP'   | 'CS25901BE00'(!)        = ''              | ''                 | 'CS25901BE00'           | 'R0201'             | '(SMR0201AW)'                  | '5.9K'    | '0.1%'  | '1/20W'  | 'DISCRETE' | 'RES CHIP 5.9K 1/20W +-0.1%(0201) '                | 'CHIPR0201'    | ''          | ''            | '20180809'
 '5.9K'       | '0.1%'    | '1/20W'  | '0201LF'  | 'EMPTY'  | 'CS25901BE00'(!)        = ''              | ''                 | 'CS25901BE00'           | 'R0201'             | '(SMR0201AW)'                  | '5.9K'    | '0.1%'  | '1/20W'  | 'IO'       | 'RES CHIP 5.9K 1/20W +-0.1%(0201) '                | 'CHIPR0201'    | ''          | ''            | '20180809'
 '10K'        | '0.1%'    | '1/20W'  | '0201LF'  | 'CHIP'   | 'CS31001BE02'(!)        = ''              | ''                 | 'CS31001BE02'           | 'R0201'             | '(SMR0201AW)'                  | '10K'     | '0.1%'  | '1/20W'  | 'DISCRETE' | 'RES CHIP 10K 1/20W +-0.1%(0201) '                 | 'CHIPR0201'    | ''          | ''            | '20180809'
 '10K'        | '0.1%'    | '1/20W'  | '0201LF'  | 'EMPTY'  | 'CS31001BE02'(!)        = ''              | ''                 | 'CS31001BE02'           | 'R0201'             | '(SMR0201AW)'                  | '10K'     | '0.1%'  | '1/20W'  | 'IO'       | 'RES CHIP 10K 1/20W +-0.1%(0201) '                 | 'CHIPR0201'    | ''          | ''            | '20180809'
 '249'        | '1%'      | '1/20W'  | '0201LF'  | 'CHIP'   | 'CS12491FE00'(!)        = ''              | ''                 | 'CS12491FE00'           | 'R0201'             | '(SMR0201AW)'                  | '249'     | '1%'    | '1/20W'  | 'DISCRETE' | 'RES CHIP 249 1/20W +-1%(0201)'                    | 'CHIPR0201'    | ''          | ''            | '20180809'
 '249'        | '1%'      | '1/20W'  | '0201LF'  | 'EMPTY'  | 'CS12491FE00'(!)        = ''              | ''                 | 'CS12491FE00'           | 'R0201'             | '(SMR0201AW)'                  | '249'     | '1%'    | '1/20W'  | 'IO'       | 'RES CHIP 249 1/20W +-1%(0201)'                    | 'CHIPR0201'    | ''          | ''            | '20180809'
 '562'        | '1%'      | '1/20W'  | '0201LF'  | 'CHIP'   | 'CS15621FE00'(!)        = ''              | ''                 | 'CS15621FE00'           | 'R0201'             | '(SMR0201AW)'                  | '562'     | '1%'    | '1/20W'  | 'DISCRETE' | 'RES CHIP 562 1/20W +-1% (0201)  '                 | 'CHIPR0201'    | ''          | ''            | '20180809'
 '562'        | '1%'      | '1/20W'  | '0201LF'  | 'EMPTY'  | 'CS15621FE00'(!)        = ''              | ''                 | 'CS15621FE00'           | 'R0201'             | '(SMR0201AW)'                  | '562'     | '1%'    | '1/20W'  | 'IO'       | 'RES CHIP 562 1/20W +-1% (0201)  '                 | 'CHIPR0201'    | ''          | ''            | '20180809'
 '1K'         | '0.1%'    | '1/20W'  | '0201LF'  | 'CHIP'   | 'CS21001BE01'(!)        = ''              | ''                 | 'CS21001BE01'           | 'R0201'             | '(SMR0201AW)'                  | '1K'      | '0.1%'  | '1/20W'  | 'DISCRETE' | 'RES CHIP 1K 1/20W +-0.1%(0201) '                  | 'CHIPR0201'    | ''          | ''            | '20180809'
 '1K'         | '0.1%'    | '1/20W'  | '0201LF'  | 'EMPTY'  | 'CS21001BE01'(!)        = ''              | ''                 | 'CS21001BE01'           | 'R0201'             | '(SMR0201AW)'                  | '1K'      | '0.1%'  | '1/20W'  | 'IO'       | 'RES CHIP 1K 1/20W +-0.1%(0201) '                  | 'CHIPR0201'    | ''          | ''            | '20180809'
 '1.02K'      | '1%'      | '1/20W'  | '0201LF'  | 'CHIP'   | 'CS21021FE00'(!)        = ''              | ''                 | 'CS21021FE00'           | 'R0201'             | '(SMR0201AW)'                  | '1.02K'   | '1%'    | '1/20W'  | 'DISCRETE' | 'RES CHIP 1.02K 1/20W +-1%(0201)'                  | 'CHIPR0201'    | ''          | ''            | '20180809'
 '1.02K'      | '1%'      | '1/20W'  | '0201LF'  | 'EMPTY'  | 'CS21021FE00'(!)        = ''              | ''                 | 'CS21021FE00'           | 'R0201'             | '(SMR0201AW)'                  | '1.02K'   | '1%'    | '1/20W'  | 'IO'       | 'RES CHIP 1.02K 1/20W +-1%(0201)'                  | 'CHIPR0201'    | ''          | ''            | '20180809'
 '1.82K'      | '1%'      | '1/20W'  | '0201LF'  | 'CHIP'   | 'CS21821FE00'(!)        = ''              | ''                 | 'CS21821FE00'           | 'R0201'             | '(SMR0201AW)'                  | '1.82K'   | '1%'    | '1/20W'  | 'DISCRETE' | 'RES CHIP 1.82K 1/20W +-1%(0201)'                  | 'CHIPR0201'    | ''          | ''            | '20180809'
 '1.82K'      | '1%'      | '1/20W'  | '0201LF'  | 'EMPTY'  | 'CS21821FE00'(!)        = ''              | ''                 | 'CS21821FE00'           | 'R0201'             | '(SMR0201AW)'                  | '1.82K'   | '1%'    | '1/20W'  | 'IO'       | 'RES CHIP 1.82K 1/20W +-1%(0201)'                  | 'CHIPR0201'    | ''          | ''            | '20180809'
 '27'         | '1%'      | '1/20W'  | '0201LF'  | 'CHIP'   | 'CS02701FE00'(!)        = 'End of Design' | 'Comp-Approve'     | 'CS02701FE00'           | 'R0201'             | '(SMR0201AW)'                  | '27'      | '1%'    | '1/20W'  | 'DISCRETE' | 'RES CHIP 27 1/20W +-1% (0201)'                    | 'CHIPR0201'    | ''          | ''            | '20180809'
 '27'         | '1%'      | '1/20W'  | '0201LF'  | 'EMPTY'  | 'CS02701FE00'(!)        = 'End of Design' | 'Comp-Approve'     | 'CS02701FE00'           | 'R0201'             | '(SMR0201AW)'                  | '27'      | '1%'    | '1/20W'  | 'IO'       | 'RES CHIP 27 1/20W +-1% (0201)'                    | 'CHIPR0201'    | ''          | ''            | '20180809'
 '1.43K'      | '1%'      | '1/20W'  | '0201LF'  | 'CHIP'   | 'CS21431FE01'(!)        = ''              | ''                 | 'CS21431FE01'           | 'R0201'             | '(SMR0201AW)'                  | '1.43K'   | '1%'    | '1/20W'  | 'DISCRETE' | 'RES CHIP 1.43K 1/20W +-1%(0201)'                  | 'CHIPR0201'    | ''          | ''            | '20180809'
 '1.43K'      | '1%'      | '1/20W'  | '0201LF'  | 'EMPTY'  | 'CS21431FE01'(!)        = ''              | ''                 | 'CS21431FE01'           | 'R0201'             | '(SMR0201AW)'                  | '1.43K'   | '1%'    | '1/20W'  | 'IO'       | 'RES CHIP 1.43K 1/20W +-1%(0201)'                  | 'CHIPR0201'    | ''          | ''            | '20180809'
 '2.21K'      | '1%'      | '1/20W'  | '0201LF'  | 'CHIP'   | 'CS22211FE00'(!)        = ''              | ''                 | 'CS22211FE00'           | 'R0201'             | '(SMR0201AW)'                  | '2.21K'   | '1%'    | '1/20W'  | 'DISCRETE' | 'RES CHIP 2.21K 1/20W +-1%(0201)HF'                | 'CHIPR0201'    | ''          | ''            | '20180809'
 '2.21K'      | '1%'      | '1/20W'  | '0201LF'  | 'EMPTY'  | 'CS22211FE00'(!)        = ''              | ''                 | 'CS22211FE00'           | 'R0201'             | '(SMR0201AW)'                  | '2.21K'   | '1%'    | '1/20W'  | 'IO'       | 'RES CHIP 2.21K 1/20W +-1%(0201)HF'                | 'CHIPR0201'    | ''          | ''            | '20180809'
 '54.9K'      | '1%'      | '1/20W'  | '0201LF'  | 'CHIP'   | 'CS35491FE01'(!)        = ''              | ''                 | 'CS35491FE01'           | 'R0201'             | '(SMR0201AW)'                  | '54.9K'   | '1%'    | '1/20W'  | 'DISCRETE' | 'RES CHIP 54.9K 1/20W +-1% (0201)'                 | 'CHIPR0201'    | ''          | ''            | '20180809'
 '54.9K'      | '1%'      | '1/20W'  | '0201LF'  | 'EMPTY'  | 'CS35491FE01'(!)        = ''              | ''                 | 'CS35491FE01'           | 'R0201'             | '(SMR0201AW)'                  | '54.9K'   | '1%'    | '1/20W'  | 'IO'       | 'RES CHIP 54.9K 1/20W +-1% (0201)'                 | 'CHIPR0201'    | ''          | ''            | '20180809'
 '36K'        | '1%'      | '1/20W'  | '0201LF'  | 'CHIP'   | 'CS33601FE02'(!)        = 'End of Design' | 'Comp-Approve'     | 'CS33601FE02'           | 'R0201'             | '(SMR0201AW)'                  | '36K'     | '1%'    | '1/20W'  | 'DISCRETE' | 'RES CHIP 36K 1/20W +-1%(0201)'                    | 'CHIPR0201'    | ''          | ''            | '20180809'
 '36K'        | '1%'      | '1/20W'  | '0201LF'  | 'EMPTY'  | 'CS33601FE02'(!)        = 'End of Design' | 'Comp-Approve'     | 'CS33601FE02'           | 'R0201'             | '(SMR0201AW)'                  | '36K'     | '1%'    | '1/20W'  | 'IO'       | 'RES CHIP 36K 1/20W +-1%(0201)'                    | 'CHIPR0201'    | ''          | ''            | '20180809'
 '165K'       | '1%'      | '1/20W'  | '0201LF'  | 'CHIP'   | 'CS41651FE01'(!)        = ''              | ''                 | 'CS41651FE01'           | 'R0201'             | '(SMR0201AW)'                  | '165K'    | '1%'    | '1/20W'  | 'DISCRETE' | 'RES CHIP 165K 1/20W +-1%(0201)'                   | 'CHIPR0201'    | ''          | ''            | '20180809'
 '165K'       | '1%'      | '1/20W'  | '0201LF'  | 'EMPTY'  | 'CS41651FE01'(!)        = ''              | ''                 | 'CS41651FE01'           | 'R0201'             | '(SMR0201AW)'                  | '165K'    | '1%'    | '1/20W'  | 'IO'       | 'RES CHIP 165K 1/20W +-1%(0201)'                   | 'CHIPR0201'    | ''          | ''            | '20180809'
 '100'        | '0.1%'    | '1/20W'  | '0201LF'  | 'CHIP'   | 'CS11001BE00'(!)        = ''              | ''                 | 'CS11001BE00'           | 'R0201'             | '(SMR0201AW)'                  | '100'     | '0.1%'  | '1/20W'  | 'DISCRETE' | 'RES CHIP 100 1/20W +-0.1%(0201) '                 | 'CHIPR0201'    | ''          | ''            | '20180809'
 '100'        | '0.1%'    | '1/20W'  | '0201LF'  | 'EMPTY'  | 'CS11001BE00'(!)        = ''              | ''                 | 'CS11001BE00'           | 'R0201'             | '(SMR0201AW)'                  | '100'     | '0.1%'  | '1/20W'  | 'IO'       | 'RES CHIP 100 1/20W +-0.1%(0201) '                 | 'CHIPR0201'    | ''          | ''            | '20180809'
 '2K'         | '0.1%'    | '1/20W'  | '0201LF'  | 'CHIP'   | 'CS22001BE00'(!)        = ''              | ''                 | 'CS22001BE00'           | 'R0201'             | '(SMR0201AW)'                  | '2K'      | '0.1%'  | '1/20W'  | 'DISCRETE' | 'RES CHIP 2K 1/20W +-0.1%(0201) '                  | 'CHIPR0201'    | ''          | ''            | '20180809'
 '2K'         | '0.1%'    | '1/20W'  | '0201LF'  | 'EMPTY'  | 'CS22001BE00'(!)        = ''              | ''                 | 'CS22001BE00'           | 'R0201'             | '(SMR0201AW)'                  | '2K'      | '0.1%'  | '1/20W'  | 'IO'       | 'RES CHIP 2K 1/20W +-0.1%(0201) '                  | 'CHIPR0201'    | ''          | ''            | '20180809'
 '249'        | '0.1%'    | '1/20W'  | '0201LF'  | 'CHIP'   | 'CS12491BE00'(!)        = ''              | ''                 | 'CS12491BE00'           | 'R0201'             | '(SMR0201AW)'                  | '249'     | '0.1%'  | '1/20W'  | 'DISCRETE' | 'RES CHIP 249 1/20W +-0.1%(0201) '                 | 'CHIPR0201'    | ''          | ''            | '20180809'
 '249'        | '0.1%'    | '1/20W'  | '0201LF'  | 'EMPTY'  | 'CS12491BE00'(!)        = ''              | ''                 | 'CS12491BE00'           | 'R0201'             | '(SMR0201AW)'                  | '249'     | '0.1%'  | '1/20W'  | 'IO'       | 'RES CHIP 249 1/20W +-0.1%(0201) '                 | 'CHIPR0201'    | ''          | ''            | '20180809'
 '22'         | '5%'      | '1/20W'  | '0201LF'  | 'CHIP'   | 'CS02201JE00'(!)        = ''              | ''                 | 'CS02201JE00'           | 'R0201'             | '(SMR0201AW)'                  | '22'      | '5%'    | '1/20W'  | 'DISCRETE' | 'RES CHIP 22 1/20W +-5%(0201)'                     | 'CHIPR0201'    | ''          | ''            | '20180809'
 '22'         | '5%'      | '1/20W'  | '0201LF'  | 'EMPTY'  | 'CS02201JE00'(!)        = ''              | ''                 | 'CS02201JE00'           | 'R0201'             | '(SMR0201AW)'                  | '22'      | '5%'    | '1/20W'  | 'IO'       | 'RES CHIP 22 1/20W +-5%(0201)'                     | 'CHIPR0201'    | ''          | ''            | '20180809'
 '49.9'       | '0.1%'    | '1/20W'  | '0201LF'  | 'CHIP'   | 'CS04991BE00'(!)        = ''              | ''                 | 'CS04991BE00'           | 'R0201'             | '(SMR0201AW)'                  | '49.9'    | '0.1%'  | '1/20W'  | 'DISCRETE' | 'RES CHIP 49.9 1/20W +-0.1%(0201) '                | 'CHIPR0201'    | ''          | ''            | '20180809'
 '49.9'       | '0.1%'    | '1/20W'  | '0201LF'  | 'EMPTY'  | 'CS04991BE00'(!)        = ''              | ''                 | 'CS04991BE00'           | 'R0201'             | '(SMR0201AW)'                  | '49.9'    | '0.1%'  | '1/20W'  | 'IO'       | 'RES CHIP 49.9 1/20W +-0.1%(0201) '                | 'CHIPR0201'    | ''          | ''            | '20180809'
 '86.6K'      | '1%'      | '1/20W'  | '0201LF'  | 'CHIP'   | 'CS38661FE00'(!)        = ''              | ''                 | 'CS38661FE00'           | 'R0201'             | '(SMR0201AW)'                  | '86.6K'   | '1%'    | '1/20W'  | 'DISCRETE' | 'RES CHIP 86.6K 1/20W +-1%(0201)'                  | 'CHIPR0201'    | ''          | ''            | '20180810'
 '86.6K'      | '1%'      | '1/20W'  | '0201LF'  | 'EMPTY'  | 'CS38661FE00'(!)        = ''              | ''                 | 'CS38661FE00'           | 'R0201'             | '(SMR0201AW)'                  | '86.6K'   | '1%'    | '1/20W'  | 'IO'       | 'RES CHIP 86.6K 1/20W +-1%(0201)'                  | 'CHIPR0201'    | ''          | ''            | '20180810'
 '470'        | '5%'      | '1/20W'  | '0201LF'  | 'CHIP'   | 'CS14701JE00'(!)        = ''              | ''                 | 'CS14701JE00'           | 'R0201'             | '(SMR0201AW)'                  | '470'     | '5%'    | '1/20W'  | 'DISCRETE' | 'RES CHIP 470 1/20W +-5%(0201)'                    | 'CHIPR0201'    | ''          | ''            | '20180810'
 '470'        | '5%'      | '1/20W'  | '0201LF'  | 'EMPTY'  | 'CS14701JE00'(!)        = ''              | ''                 | 'CS14701JE00'           | 'R0201'             | '(SMR0201AW)'                  | '470'     | '5%'    | '1/20W'  | 'IO'       | 'RES CHIP 470 1/20W +-5%(0201)'                    | 'CHIPR0201'    | ''          | ''            | '20180810'
 '165'        | '1%'      | '1/20W'  | '0201LF'  | 'CHIP'   | 'CS11651FE00'(!)        = ''              | ''                 | 'CS11651FE00'           | 'R0201'             | '(SMR0201AW)'                  | '165'     | '1%'    | '1/20W'  | 'DISCRETE' | 'RES CHIP 165 1/20W +-1%(0201)'                    | 'CHIPR0201'    | ''          | ''            | '20180823'
 '165'        | '1%'      | '1/20W'  | '0201LF'  | 'EMPTY'  | 'CS11651FE00'(!)        = ''              | ''                 | 'CS11651FE00'           | 'R0201'             | '(SMR0201AW)'                  | '165'     | '1%'    | '1/20W'  | 'IO'       | 'RES CHIP 165 1/20W +-1%(0201)'                    | 'CHIPR0201'    | ''          | ''            | '20180823'
 '3K'         | '1%'      | '1/20W'  | '0201LF'  | 'CHIP'   | 'CS23001FE02'(!)        = ''              | ''                 | 'CS23001FE02'           | 'R0201'             | '(SMR0201AW)'                  | '3K'      | '1%'    | '1/20W'  | 'DISCRETE' | 'RES CHIP 3K 1/20W+-1%(0201)'                      | 'CHIPR0201'    | ''          | ''            | '20180823'
 '3K'         | '1%'      | '1/20W'  | '0201LF'  | 'EMPTY'  | 'CS23001FE02'(!)        = ''              | ''                 | 'CS23001FE02'           | 'R0201'             | '(SMR0201AW)'                  | '3K'      | '1%'    | '1/20W'  | 'IO'       | 'RES CHIP 3K 1/20W+-1%(0201)'                      | 'CHIPR0201'    | ''          | ''            | '20180823'
 '665'        | '1%'      | '1/20W'  | '0201LF'  | 'CHIP'   | 'CS16651FE00'(!)        = ''              | ''                 | 'CS16651FE00'           | 'R0201'             | '(SMR0201AW)'                  | '665'     | '1%'    | '1/20W'  | 'DISCRETE' | 'RES CHIP 665 1/20W +-1%(0201) '                   | 'CHIPR0201'    | ''          | ''            | '20180823'
 '665'        | '1%'      | '1/20W'  | '0201LF'  | 'EMPTY'  | 'CS16651FE00'(!)        = ''              | ''                 | 'CS16651FE00'           | 'R0201'             | '(SMR0201AW)'                  | '665'     | '1%'    | '1/20W'  | 'IO'       | 'RES CHIP 665 1/20W +-1%(0201) '                   | 'CHIPR0201'    | ''          | ''            | '20180823'
 '549K'       | '1%'      | '1/16W'  | '0402LF'  | 'CHIP'   | 'CS45492FB16'(!)        = 'End of Design' | 'Comp-Approve'     | 'CS45492FB16'           | 'R0402'             | '(R0402-0201)'                 | '549K'    | '1%'    | '1/16W'  | 'DISCRETE' | 'RES CHIP 549K 1/16W +-1%( 0402)'                  | 'CHIPR0402'    | ''          | ''            | '20180830'
 '549K'       | '1%'      | '1/16W'  | '0402LF'  | 'EMPTY'  | 'CS45492FB16'(!)        = 'End of Design' | 'Comp-Approve'     | 'CS45492FB16'           | 'R0402'             | '(R0402-0201)'                 | '549K'    | '1%'    | '1/16W'  | 'IO'       | 'RES CHIP 549K 1/16W +-1%( 0402)'                  | 'CHIPR0402'    | ''          | ''            | '20180830'
 '1.74K'      | '1%'      | '1/20W'  | '0201LF'  | 'CHIP'   | 'CS21741FE00'(!)        = ''              | ''                 | 'CS21741FE00'           | 'R0201'             | '(SMR0201AW)'                  | '1.74K'   | '1%'    | '1/20W'  | 'DISCRETE' | 'RES CHIP 1.74K 1/20W +-1%(0201) '                 | 'CHIPR0201'    | ''          | ''            | '20180830'
 '1.74K'      | '1%'      | '1/20W'  | '0201LF'  | 'EMPTY'  | 'CS21741FE00'(!)        = ''              | ''                 | 'CS21741FE00'           | 'R0201'             | '(SMR0201AW)'                  | '1.74K'   | '1%'    | '1/20W'  | 'IO'       | 'RES CHIP 1.74K 1/20W +-1%(0201) '                 | 'CHIPR0201'    | ''          | ''            | '20180830'
 '15.4K'      | '1%'      | '1/20W'  | '0201LF'  | 'CHIP'   | 'CS31541FE00'(!)        = ''              | ''                 | 'CS31541FE00'           | 'R0201'             | '(SMR0201AW)'                  | '15.4K'   | '1%'    | '1/20W'  | 'DISCRETE' | 'RES CHIP 15.4K 1/20W +-1%(0201)'                  | 'CHIPR0201'    | ''          | ''            | '20180830'
 '15.4K'      | '1%'      | '1/20W'  | '0201LF'  | 'EMPTY'  | 'CS31541FE00'(!)        = ''              | ''                 | 'CS31541FE00'           | 'R0201'             | '(SMR0201AW)'                  | '15.4K'   | '1%'    | '1/20W'  | 'IO'       | 'RES CHIP 15.4K 1/20W +-1%(0201)'                  | 'CHIPR0201'    | ''          | ''            | '20180830'
 '19.1K'      | '1%'      | '1/20W'  | '0201LF'  | 'CHIP'   | 'CS31911FE01'(!)        = ''              | ''                 | 'CS31911FE01'           | 'R0201'             | '(SMR0201AW)'                  | '19.1K'   | '1%'    | '1/20W'  | 'DISCRETE' | 'RES CHIP 19.1K 1/20W +-1%(0201)'                  | 'CHIPR0201'    | ''          | ''            | '20180830'
 '19.1K'      | '1%'      | '1/20W'  | '0201LF'  | 'EMPTY'  | 'CS31911FE01'(!)        = ''              | ''                 | 'CS31911FE01'           | 'R0201'             | '(SMR0201AW)'                  | '19.1K'   | '1%'    | '1/20W'  | 'IO'       | 'RES CHIP 19.1K 1/20W +-1%(0201)'                  | 'CHIPR0201'    | ''          | ''            | '20180830'
 '3.74K'      | '1%'      | '1/20W'  | '0201LF'  | 'CHIP'   | 'CS23741FE01'(!)        = ''              | ''                 | 'CS23741FE01'           | 'R0201'             | '(SMR0201AW)'                  | '3.74K'   | '1%'    | '1/20W'  | 'DISCRETE' | 'RES CHIP 3.74K 1/20W +-1%(0201)'                  | 'CHIPR0201'    | ''          | ''            | '20180830'
 '3.74K'      | '1%'      | '1/20W'  | '0201LF'  | 'EMPTY'  | 'CS23741FE01'(!)        = ''              | ''                 | 'CS23741FE01'           | 'R0201'             | '(SMR0201AW)'                  | '3.74K'   | '1%'    | '1/20W'  | 'IO'       | 'RES CHIP 3.74K 1/20W +-1%(0201)'                  | 'CHIPR0201'    | ''          | ''            | '20180830'
 '42.2K'      | '1%'      | '1/20W'  | '0201LF'  | 'CHIP'   | 'CS34221FE01'(!)        = ''              | ''                 | 'CS34221FE01'           | 'R0201'             | '(SMR0201AW)'                  | '42.2K'   | '1%'    | '1/20W'  | 'DISCRETE' | 'RES CHIP 42.2K 1/20W +-1%(0201)'                  | 'CHIPR0201'    | ''          | ''            | '20180830'
 '42.2K'      | '1%'      | '1/20W'  | '0201LF'  | 'EMPTY'  | 'CS34221FE01'(!)        = ''              | ''                 | 'CS34221FE01'           | 'R0201'             | '(SMR0201AW)'                  | '42.2K'   | '1%'    | '1/20W'  | 'IO'       | 'RES CHIP 42.2K 1/20W +-1%(0201)'                  | 'CHIPR0201'    | ''          | ''            | '20180830'
 '75K'        | '1%'      | '1/20W'  | '0201LF'  | 'CHIP'   | 'CS37501FE00'(!)        = ''              | ''                 | 'CS37501FE00'           | 'R0201'             | '(SMR0201AW)'                  | '75K'     | '1%'    | '1/20W'  | 'DISCRETE' | 'RES CHIP 75K 1/20W +-1%(0201)'                    | 'CHIPR0201'    | ''          | ''            | '20180830'
 '75K'        | '1%'      | '1/20W'  | '0201LF'  | 'EMPTY'  | 'CS37501FE00'(!)        = ''              | ''                 | 'CS37501FE00'           | 'R0201'             | '(SMR0201AW)'                  | '75K'     | '1%'    | '1/20W'  | 'IO'       | 'RES CHIP 75K 1/20W +-1%(0201)'                    | 'CHIPR0201'    | ''          | ''            | '20180830'
 '84.5K'      | '1%'      | '1/20W'  | '0201LF'  | 'CHIP'   | 'CS38451FE00'(!)        = ''              | ''                 | 'CS38451FE00'           | 'R0201'             | '(SMR0201AW)'                  | '84.5K'   | '1%'    | '1/20W'  | 'DISCRETE' | 'RES CHIP 84.5K 1/20W,+-1%(0201)'                  | 'CHIPR0201'    | ''          | ''            | '20180830'
 '84.5K'      | '1%'      | '1/20W'  | '0201LF'  | 'EMPTY'  | 'CS38451FE00'(!)        = ''              | ''                 | 'CS38451FE00'           | 'R0201'             | '(SMR0201AW)'                  | '84.5K'   | '1%'    | '1/20W'  | 'IO'       | 'RES CHIP 84.5K 1/20W,+-1%(0201)'                  | 'CHIPR0201'    | ''          | ''            | '20180830'
 '9.76K'      | '1%'      | '1/20W'  | '0201LF'  | 'CHIP'   | 'CS29761FE00'(!)        = ''              | ''                 | 'CS29761FE00'           | 'R0201'             | '(SMR0201AW)'                  | '9.76K'   | '1%'    | '1/20W'  | 'DISCRETE' | 'RES CHIP 9.76K 1/20W +-1%(0201)'                  | 'CHIPR0201'    | ''          | ''            | '20180831'
 '9.76K'      | '1%'      | '1/20W'  | '0201LF'  | 'EMPTY'  | 'CS29761FE00'(!)        = ''              | ''                 | 'CS29761FE00'           | 'R0201'             | '(SMR0201AW)'                  | '9.76K'   | '1%'    | '1/20W'  | 'IO'       | 'RES CHIP 9.76K 1/20W +-1%(0201)'                  | 'CHIPR0201'    | ''          | ''            | '20180831'
 '45.3K'      | '1%'      | '1/20W'  | '0201LF'  | 'CHIP'   | 'CS34531FE01'(!)        = ''              | ''                 | 'CS34531FE01'           | 'R0201'             | '(SMR0201AW)'                  | '45.3K'   | '1%'    | '1/20W'  | 'DISCRETE' | 'RES CHIP 45.3K 1/20W +-1%(0201)'                  | 'CHIPR0201'    | ''          | ''            | '20180831'
 '45.3K'      | '1%'      | '1/20W'  | '0201LF'  | 'EMPTY'  | 'CS34531FE01'(!)        = ''              | ''                 | 'CS34531FE01'           | 'R0201'             | '(SMR0201AW)'                  | '45.3K'   | '1%'    | '1/20W'  | 'IO'       | 'RES CHIP 45.3K 1/20W +-1%(0201)'                  | 'CHIPR0201'    | ''          | ''            | '20180831'
 '147K'       | '1%'      | '1/20W'  | '0201LF'  | 'CHIP'   | 'CS41471FE00'(!)        = ''              | ''                 | 'CS41471FE00'           | 'R0201'             | '(SMR0201AW)'                  | '147K'    | '1%'    | '1/20W'  | 'DISCRETE' | 'RES CHIP 147K 1/20W +-1%(0201)'                   | 'CHIPR0201'    | ''          | ''            | '20180903'
 '147K'       | '1%'      | '1/20W'  | '0201LF'  | 'EMPTY'  | 'CS41471FE00'(!)        = ''              | ''                 | 'CS41471FE00'           | 'R0201'             | '(SMR0201AW)'                  | '147K'    | '1%'    | '1/20W'  | 'IO'       | 'RES CHIP 147K 1/20W +-1%(0201)'                   | 'CHIPR0201'    | ''          | ''            | '20180903'
 '28K'        | '1%'      | '1/20W'  | '0201LF'  | 'CHIP'   | 'CS32801FE00'(!)        = ''              | ''                 | 'CS32801FE00'           | 'R0201'             | '(SMR0201AW)'                  | '28K'     | '1%'    | '1/20W'  | 'DISCRETE' | 'RES CHIP 28K 1/20W +-1%(0201)'                    | 'CHIPR0201'    | ''          | ''            | '20180903'
 '28K'        | '1%'      | '1/20W'  | '0201LF'  | 'EMPTY'  | 'CS32801FE00'(!)        = ''              | ''                 | 'CS32801FE00'           | 'R0201'             | '(SMR0201AW)'                  | '28K'     | '1%'    | '1/20W'  | 'IO'       | 'RES CHIP 28K 1/20W +-1%(0201)'                    | 'CHIPR0201'    | ''          | ''            | '20180903'
 '7.68K'      | '1%'      | '1/20W'  | '0201LF'  | 'CHIP'   | 'CS27681FE00'(!)        = ''              | ''                 | 'CS27681FE00'           | 'R0201'             | '(SMR0201AW)'                  | '7.68K'   | '1%'    | '1/20W'  | 'DISCRETE' | 'RES CHIP 7.68K 1/20W +-1%(0201)'                  | 'CHIPR0201'    | ''          | ''            | '20180903'
 '7.68K'      | '1%'      | '1/20W'  | '0201LF'  | 'EMPTY'  | 'CS27681FE00'(!)        = ''              | ''                 | 'CS27681FE00'           | 'R0201'             | '(SMR0201AW)'                  | '7.68K'   | '1%'    | '1/20W'  | 'IO'       | 'RES CHIP 7.68K 1/20W +-1%(0201)'                  | 'CHIPR0201'    | ''          | ''            | '20180903'
 '38.3K'      | '1%'      | '1/20W'  | '0201LF'  | 'CHIP'   | 'CS33831FE01'(!)        = ''              | ''                 | 'CS33831FE01'           | 'R0201'             | '(SMR0201AW)'                  | '38.3K'   | '1%'    | '1/20W'  | 'DISCRETE' | 'RES CHIP 38.3K 1/20W +-1%(0201)'                  | 'CHIPR0201'    | ''          | ''            | '20180903'
 '38.3K'      | '1%'      | '1/20W'  | '0201LF'  | 'EMPTY'  | 'CS33831FE01'(!)        = ''              | ''                 | 'CS33831FE01'           | 'R0201'             | '(SMR0201AW)'                  | '38.3K'   | '1%'    | '1/20W'  | 'IO'       | 'RES CHIP 38.3K 1/20W +-1%(0201)'                  | 'CHIPR0201'    | ''          | ''            | '20180903'
 '63.4K'      | '1%'      | '1/20W'  | '0201LF'  | 'CHIP'   | 'CS36341FE00'(!)        = ''              | ''                 | 'CS36341FE00'           | 'R0201'             | '(SMR0201AW)'                  | '63.4K'   | '1%'    | '1/20W'  | 'DISCRETE' | 'RES CHIP 63.4K 1/20W +-1% (0201) '                | 'CHIPR0201'    | ''          | ''            | '20180903'
 '63.4K'      | '1%'      | '1/20W'  | '0201LF'  | 'EMPTY'  | 'CS36341FE00'(!)        = ''              | ''                 | 'CS36341FE00'           | 'R0201'             | '(SMR0201AW)'                  | '63.4K'   | '1%'    | '1/20W'  | 'IO'       | 'RES CHIP 63.4K 1/20W +-1% (0201) '                | 'CHIPR0201'    | ''          | ''            | '20180903'
 '560'        | '1%'      | '1/16W'  | '0402LF'  | 'CHIP'   | 'CS15602FB17'(!)        = 'End of Design' | 'Comp-Approve'     | 'CS15602FB17'           | 'R0402'             | '(R0402-0201)'                 | '560'     | '1%'    | '1/16W'  | 'DISCRETE' | 'RES CHIP 560 1/16W +-1%(0402)'                    | 'CHIPR0402'    | ''          | ''            | '20100429'
 '560'        | '1%'      | '1/16W'  | '0402LF'  | 'EMPTY'  | 'CS15602FB17'(!)        = 'End of Design' | 'Comp-Approve'     | 'CS15602FB17'           | 'R0402'             | '(R0402-0201)'                 | '560'     | '1%'    | '1/16W'  | 'IO'       | 'RES CHIP 560 1/16W +-1%(0402)'                    | 'CHIPR0402'    | ''          | ''            | '20100429'
 '2K'         | '0.1%'    | '1/16W'  | '0402LF'  | 'CHIP'   | 'CS22002BB01'(!)        = ''              | ''                 | 'CS22002BB01'           | 'R0402'             | '(R0402-0201)'                 | '2K'      | '0.1%'  | '1/16W'  | 'DISCRETE' | 'RES CHIP 2K 1/16W +-0.1% (0402)'                  | 'CHIPR0402'    | ''          | ''            | '20150911'
 '2K'         | '0.1%'    | '1/16W'  | '0402LF'  | 'EMPTY'  | 'CS22002BB01'(!)        = ''              | ''                 | 'CS22002BB01'           | 'R0402'             | '(R0402-0201)'                 | '2K'      | '0.1%'  | '1/16W'  | 'IO'       | 'RES CHIP 2K 1/16W +-0.1% (0402)'                  | 'CHIPR0402'    | ''          | ''            | '20150911'
 '220'        | '5%'      | '1/20W'  | '0201LF'  | 'CHIP '  | 'CS12201JE04'(!)        = ''              | ''                 | 'CS12201JE04'           | 'R0201'             | '(SMR0201AW)'                  | '220'     | '5%'    | '1/20W'  | 'DISCRETE' | 'RES CHIP 220(1/20W,+-5%,0201)'                    | 'CHIPR0201'    | ''          | ''            | '20181024'
 '220'        | '5%'      | '1/20W'  | '0201LF'  | 'EMPTY'  | 'CS12201JE04'(!)        = ''              | ''                 | 'CS12201JE04'           | 'R0201'             | '(SMR0201AW)'                  | '220'     | '5%'    | '1/20W'  | 'IO'       | 'RES CHIP 220(1/20W,+-5%,0201)'                    | 'CHIPR0201'    | ''          | ''            | '20181024'
 '330'        | '1%'      | '1/4W'   | '1206LF'  | 'CHIP'   | 'CS13306F200'(!)        = ''              | ''                 | 'CS13306F200'           | 'R1206XJ'           | '(SMR1206AW)'                  | '330'     | '1%'    | '1/4W'   | 'DISCRETE' | 'RES CHIP 330 1/4W+-1%(1206)'                      | 'CHIPR1206'    | ''          | ''            | '20100429'
 '330'        | '1%'      | '1/4W'   | '1206LF'  | 'EMPTY'  | 'CS13306F200'(!)        = ''              | ''                 | 'CS13306F200'           | 'R1206XJ'           | '(SMR1206AW)'                  | '330'     | '1%'    | '1/4W'   | 'IO'       | 'RES CHIP 330 1/4W+-1%(1206)'                      | 'CHIPR1206'    | ''          | ''            | '20100429'
 '249'        | '1%'      | '1/4W'   | '1206LF'  | 'CHIP'   | 'CS12496F200'(!)        = ''              | ''                 | 'CS12496F200'           | 'R1206XJ'           | '(SMR1206AW)'                  | '249'     | '1%'    | '1/4W'   | 'DISCRETE' | 'RES CHIP 249 1/4W +-1%(1206)'                     | 'CHIPR1206'    | ''          | ''            | '20181031'
 '249'        | '1%'      | '1/4W'   | '1206LF'  | 'EMPTY'  | 'CS12496F200'(!)        = ''              | ''                 | 'CS12496F200'           | 'R1206XJ'           | '(SMR1206AW)'                  | '249'     | '1%'    | '1/4W'   | 'IO'       | 'RES CHIP 249 1/4W +-1%(1206)'                     | 'CHIPR1206'    | ''          | ''            | '20181031'
 '910K'       | '1%'      | '1/16W'  | '0402LF'  | 'CHIP'   | 'CS49102FB07'(!)        = 'End of Design' | 'Comp-Approve'     | 'CS49102FB07'           | 'R0402'             | '(R0402-0201)'                 | '910K'    | '1%'    | '1/16W'  | 'DISCRETE' | 'RES CHIP 910K 1/16W +-1%(0402)'                   | 'CHIPR0402'    | ''          | ''            | '20181031'
 '910K'       | '1%'      | '1/16W'  | '0402LF'  | 'EMPTY'  | 'CS49102FB07'(!)        = 'End of Design' | 'Comp-Approve'     | 'CS49102FB07'           | 'R0402'             | '(R0402-0201)'                 | '910K'    | '1%'    | '1/16W'  | 'IO'       | 'RES CHIP 910K 1/16W +-1%(0402)'                   | 'CHIPR0402'    | ''          | ''            | '20181031'
 '1.78M'      | '1%'      | '1/16W'  | '0402LF'  | 'CHIP'   | 'CS51782FB00'(!)        = ''              | ''                 | 'CS51782FB00'           | 'R0402'             | '(R0402-0201)'                 | '1.78M'   | '1%'    | '1/16W'  | 'DISCRETE' | 'RES CHIP 1.78M 1/16W +-1%(0402)'                  | 'CHIPR0402'    | ''          | ''            | '20181101'
 '1.78M'      | '1%'      | '1/16W'  | '0402LF'  | 'EMPTY'  | 'CS51782FB00'(!)        = ''              | ''                 | 'CS51782FB00'           | 'R0402'             | '(R0402-0201)'                 | '1.78M'   | '1%'    | '1/16W'  | 'IO'       | 'RES CHIP 1.78M 1/16W +-1%(0402)'                  | 'CHIPR0402'    | ''          | ''            | '20181101'
 '0.005'      | '1%'      | '1W'     | '1206LF'  | 'CHIP'   | 'CS+0058F200'(!)        = ''              | ''                 | 'CS+0058F200'           | 'R1206XK'           | '(SMR1206AW)'                  | '0.005'   | '1%'    | '1W'     | 'DISCRETE' | 'RES CHIP  0.005  1W +-1%(1206)'                   | 'CHIPR1206'    | ''          | ''            | '20181113'
 '0.005'      | '1%'      | '1W'     | '1206LF'  | 'EMPTY'  | 'CS+0058F200'(!)        = ''              | ''                 | 'CS+0058F200'           | 'R1206XK'           | '(SMR1206AW)'                  | '0.005'   | '1%'    | '1W'     | 'IO'       | 'RES CHIP  0.005  1W +-1%(1206)'                   | 'CHIPR1206'    | ''          | ''            | '20181113'
 '316'        | '1%'      | '1/16W'  | '0402LF'  | 'CHIP'   | 'CS13162FB02'(!)        = 'End of Design' | 'Comp-Approve'     | 'CS13162FB02'           | 'R0402'             | '(R0402-0201)'                 | '316'     | '1%'    | '1/16W'  | 'DISCRETE' | 'RES CHIP 316 1/16W +-1%(0402)'                    | 'CHIPR0402'    | ''          | ''            | '20181113'
 '316'        | '1%'      | '1/16W'  | '0402LF'  | 'EMPTY'  | 'CS13162FB02'(!)        = 'End of Design' | 'Comp-Approve'     | 'CS13162FB02'           | 'R0402'             | '(R0402-0201)'                 | '316'     | '1%'    | '1/16W'  | 'IO'       | 'RES CHIP 316 1/16W +-1%(0402)'                    | 'CHIPR0402'    | ''          | ''            | '20181113'
 '1.69K'      | '1%'      | '1/4W'   | '1206LF'  | 'CHIP'   | 'CS21696F200'(!)        = 'End of Design' | 'Comp-Approve'     | 'CS21696F200'           | 'R1206XB'           | '(SMR1206AW)'                  | '1.69K'   | '1%'    | '1/4W'   | 'DISCRETE' | 'RES CHIP 1.69K 1/4W +-1% (1206)'                  | 'CHIPR1206'    | ''          | ''            | '20150413'
 '1.69K'      | '1%'      | '1/4W'   | '1206LF'  | 'EMPTY'  | 'CS21696F200'(!)        = 'End of Design' | 'Comp-Approve'     | 'CS21696F200'           | 'R1206XB'           | '(SMR1206AW)'                  | '1.69K'   | '1%'    | '1/4W'   | 'IO'       | 'RES CHIP 1.69K 1/4W +-1% (1206)'                  | 'CHIPR1206'    | ''          | ''            | '20150413'
 '1.47K'      | '1%'      | '1/4W'   | '1206LF'  | 'CHIP'   | 'CS21476F200'(!)        = ''              | ''                 | 'CS21476F200'           | 'R1206XI'           | '(SMR1206AW)'                  | '1.47K'   | '1%'    | '1/4W'   | 'DISCRETE' | 'RES CHIP 1.47K 1/4W +-1%(1206)'                   | 'CHIPR1206'    | ''          | ''            | '20181113'
 '1.47K'      | '1%'      | '1/4W'   | '1206LF'  | 'EMPTY'  | 'CS21476F200'(!)        = ''              | ''                 | 'CS21476F200'           | 'R1206XI'           | '(SMR1206AW)'                  | '1.47K'   | '1%'    | '1/4W'   | 'IO'       | 'RES CHIP 1.47K 1/4W +-1%(1206)'                   | 'CHIPR1206'    | ''          | ''            | '20181113'
 '866'        | '1%'      | '1/4W'   | '1206LF'  | 'CHIP'   | 'CS18666F200'(!)        = ''              | ''                 | 'CS18666F200'           | 'R1206XF'           | '(SMR1206AW)'                  | '866'     | '1%'    | '1/4W'   | 'DISCRETE' | 'RES CHIP 866 1/4W +-1%(1206)'                     | 'CHIPR1206'    | ''          | ''            | '20181122'
 '866'        | '1%'      | '1/4W'   | '1206LF'  | 'EMPTY'  | 'CS18666F200'(!)        = ''              | ''                 | 'CS18666F200'           | 'R1206XF'           | '(SMR1206AW)'                  | '866'     | '1%'    | '1/4W'   | 'IO'       | 'RES CHIP 866 1/4W +-1%(1206)'                     | 'CHIPR1206'    | ''          | ''            | '20181122'
 '910'        | '1%'      | '1/4W'   | '1206LF'  | 'CHIP'   | 'CS19106F200'(!)        = ''              | ''                 | 'CS19106F200'           | 'R1206XF'           | '(SMR1206AW)'                  | '910'     | '1%'    | '1/4W'   | 'DISCRETE' | 'RES CHIP 910 1/4W +-1%(1206)'                     | 'CHIPR1206'    | ''          | ''            | '20181122'
 '910'        | '1%'      | '1/4W'   | '1206LF'  | 'EMPTY'  | 'CS19106F200'(!)        = ''              | ''                 | 'CS19106F200'           | 'R1206XF'           | '(SMR1206AW)'                  | '910'     | '1%'    | '1/4W'   | 'IO'       | 'RES CHIP 910 1/4W +-1%(1206)'                     | 'CHIPR1206'    | ''          | ''            | '20181122'
 '237K'       | '1%'      | '1/8W'   | '0805LF'  | 'CHIP'   | 'CS42374FA19'(!)        = ''              | ''                 | 'CS42374FA19'           | 'R0805'             | '(SMR0805AW)'                  | '237K'    | '1%'    | '1/8W'   | 'DISCRETE' | 'RES CHIP 237K 1/8W +-1%(2012)'                    | 'CHIPR0805'    | ''          | ''            | '20181122'
 '237K'       | '1%'      | '1/8W'   | '0805LF'  | 'EMPTY'  | 'CS42374FA19'(!)        = ''              | ''                 | 'CS42374FA19'           | 'R0805'             | '(SMR0805AW)'                  | '237K'    | '1%'    | '1/8W'   | 'IO'       | 'RES CHIP 237K 1/8W +-1%(2012)'                    | 'CHIPR0805'    | ''          | ''            | '20181122'
 '7.32K'      | '1%'      | '1/20W'  | '0201LF'  | 'CHIP'   | 'CS27321FE01'(!)        = ''              | ''                 | 'CS27321FE01'           | 'R0201'             | '(SMR0201AW)'                  | '7.32K'   | '1%'    | '1/20W'  | 'DISCRETE' | 'RES CHIP 7.32K 1/20W +-1%(0201)'                  | 'CHIPR0201'    | ''          | ''            | '20181219'
 '7.32K'      | '1%'      | '1/20W'  | '0201LF'  | 'EMPTY'  | 'CS27321FE01'(!)        = ''              | ''                 | 'CS27321FE01'           | 'R0201'             | '(SMR0201AW)'                  | '7.32K'   | '1%'    | '1/20W'  | 'IO'       | 'RES CHIP 7.32K 1/20W +-1%(0201)'                  | 'CHIPR0201'    | ''          | ''            | '20181219'
 '0.01'       | '1%'      | '2W'     | '2512LF'  | 'CHIP'   | 'CS+010AFR01'(!)        = ''              | ''                 | 'CS+010AFR01'           | 'R2512XT'           | '(SMR2512AW)'                  | '0.01'    | '1%'    | '2W'     | 'DISCRETE' | 'RES CHIP 0.01 2W +-1%(2512)AEC'                   | 'CHIP2512'     | ''          | ''            | '20190103'
 '0.01'       | '1%'      | '2W'     | '2512LF'  | 'EMPTY'  | 'CS+010AFR01'(!)        = ''              | ''                 | 'CS+010AFR01'           | 'R2512XT'           | '(SMR2512AW)'                  | '0.01'    | '1%'    | '2W'     | 'IO'       | 'RES CHIP 0.01 2W +-1%(2512)AEC'                   | 'CHIP2512'     | ''          | ''            | '20190103'
 '360'        | '1%'      | '1/8W'   | '0805LF'  | 'CHIP'   | 'CS13604FA00'(!)        = ''              | ''                 | 'CS13604FA00'           | 'R0805'             | '(SMR0805AW)'                  | '360'     | '1%'    | '1/8W'   | 'DISCRETE' | 'RES CHIP 360 1/8W +-1%(0805)'                     | 'CHIPR0805'    | ''          | ''            | '20190103'
 '360'        | '1%'      | '1/8W'   | '0805LF'  | 'EMPTY'  | 'CS13604FA00'(!)        = ''              | ''                 | 'CS13604FA00'           | 'R0805'             | '(SMR0805AW)'                  | '360'     | '1%'    | '1/8W'   | 'IO'       | 'RES CHIP 360 1/8W +-1%(0805)'                     | 'CHIPR0805'    | ''          | ''            | '20190103'
 '887'        | '1%'      | '1/8W'   | '0805LF'  | 'CHIP'   | 'CS18874FA00'(!)        = ''              | ''                 | 'CS18874FA00'           | 'R0805'             | '(SMR0805AW)'                  | '887'     | '1%'    | '1/8W'   | 'DISCRETE' | 'RES CHIP 887 1/8W +-1%(0805)'                     | 'CHIPR0805'    | ''          | ''            | '20190104'
 '887'        | '1%'      | '1/8W'   | '0805LF'  | 'EMPTY'  | 'CS18874FA00'(!)        = ''              | ''                 | 'CS18874FA00'           | 'R0805'             | '(SMR0805AW)'                  | '887'     | '1%'    | '1/8W'   | 'IO'       | 'RES CHIP 887 1/8W +-1%(0805)'                     | 'CHIPR0805'    | ''          | ''            | '20190104'
 '43.2K'      | '1%'      | '1/16W'  | '0402LF'  | 'CHIP'   | 'CS34322FB00'(!)        = 'End of Design' | 'Comp-Approve'     | 'CS34322FB00'           | 'R0402'             | '(R0402-0201)'                 | '43.2K'   | '1%'    | '1/16W'  | 'DISCRETE' | 'RES CHIP 43.2K 1/16W +-1%(0402)'                  | 'CHIPR0402'    | ''          | ''            | '20190107'
 '43.2K'      | '1%'      | '1/16W'  | '0402LF'  | 'EMPTY'  | 'CS34322FB00'(!)        = 'End of Design' | 'Comp-Approve'     | 'CS34322FB00'           | 'R0402'             | '(R0402-0201)'                 | '43.2K'   | '1%'    | '1/16W'  | 'IO'       | 'RES CHIP 43.2K 1/16W +-1%(0402)'                  | 'CHIPR0402'    | ''          | ''            | '20190107'
 '21K'        | '1%'      | '1/10W'  | '0603LF'  | 'CHIP'   | 'CS32103F911'(!)        = ''              | ''                 | 'CS32103F911'           | 'R0603'             | '(SMR0603AW)'                  | '21K'     | '1%'    | '1/10W'  | 'DISCRETE' | 'RES CHIP 21K 1/10W+-1%(0603)'                     | 'CHIPR0603'    | ''          | ''            | '20190111'
 '21K'        | '1%'      | '1/10W'  | '0603LF'  | 'EMPTY'  | 'CS32103F911'(!)        = ''              | ''                 | 'CS32103F911'           | 'R0603'             | '(SMR0603AW)'                  | '21K'     | '1%'    | '1/10W'  | 'IO'       | 'RES CHIP 21K 1/10W+-1%(0603)'                     | 'CHIPR0603'    | ''          | ''            | '20190111'
 '909'        | '0.1%'    | '1/16W'  | '0402LF'  | 'CHIP'   | 'CS19092BB00'(!)        = ''              | ''                 | 'CS19092BB00'           | 'R0402'             | '(R0402-0201)'                 | '909'     | '0.1%'  | '1/16W'  | 'DISCRETE' | 'RES CHIP 909 1/16W +-0.1%(0402)EF'                | 'CHIPR0402'    | ''          | ''            | '20190115'
 '909'        | '0.1%'    | '1/16W'  | '0402LF'  | 'EMPTY'  | 'CS19092BB00'(!)        = ''              | ''                 | 'CS19092BB00'           | 'R0402'             | '(R0402-0201)'                 | '909'     | '0.1%'  | '1/16W'  | 'IO'       | 'RES CHIP 909 1/16W +-0.1%(0402)EF'                | 'CHIPR0402'    | ''          | ''            | '20190115'
 '90.9K'      | '0.1%'    | '1/16W'  | '0402LF'  | 'CHIP'   | 'CS39092BB00'(!)        = ''              | ''                 | 'CS39092BB00'           | 'R0402'             | '(R0402-0201)'                 | '90.9K'   | '0.1%'  | '1/16W'  | 'DISCRETE' | 'RES CHIP 90.9K 1/16W +-0.1%(0402)EF'              | 'CHIPR0402'    | ''          | ''            | '20190115'
 '90.9K'      | '0.1%'    | '1/16W'  | '0402LF'  | 'EMPTY'  | 'CS39092BB00'(!)        = ''              | ''                 | 'CS39092BB00'           | 'R0402'             | '(R0402-0201)'                 | '90.9K'   | '0.1%'  | '1/16W'  | 'IO'       | 'RES CHIP 90.9K 1/16W +-0.1%(0402)EF'              | 'CHIPR0402'    | ''          | ''            | '20190115'
 '240'        | '0.5%'    | '1/16W'  | '0402LF'  | 'CHIP'   | 'CS12402DB00'(!)        = 'End of Design' | 'Comp-Approve'     | 'CS12402DB00'           | 'R0402'             | '(R0402-0201)'                 | '240'     | '0.5%'  | '1/16W'  | 'DISCRETE' | 'RES CHIP 240 1/16W +-0.5%(0402)'                  | 'CHIPR0402'    | ''          | ''            | '20190115'
 '240'        | '0.5%'    | '1/16W'  | '0402LF'  | 'EMPTY'  | 'CS12402DB00'(!)        = 'End of Design' | 'Comp-Approve'     | 'CS12402DB00'           | 'R0402'             | '(R0402-0201)'                 | '240'     | '0.5%'  | '1/16W'  | 'IO'       | 'RES CHIP 240 1/16W +-0.5%(0402)'                  | 'CHIPR0402'    | ''          | ''            | '20190115'
 '11.8K'      | '0.1%'    | '1/16W'  | '0402LF'  | 'CHIP'   | 'CS31182BB00'(!)        = ''              | ''                 | 'CS31182BB00'           | 'R0402'             | '(R0402-0201)'                 | '11.8K'   | '0.1%'  | '1/16W'  | 'DISCRETE' | 'RES CHIP 11.8K 1/16W +-0.1%(0402)'                | 'CHIPR0402'    | ''          | ''            | '20190117'
 '11.8K'      | '0.1%'    | '1/16W'  | '0402LF'  | 'EMPTY'  | 'CS31182BB00'(!)        = ''              | ''                 | 'CS31182BB00'           | 'R0402'             | '(R0402-0201)'                 | '11.8K'   | '0.1%'  | '1/16W'  | 'IO'       | 'RES CHIP 11.8K 1/16W +-0.1%(0402)'                | 'CHIPR0402'    | ''          | ''            | '20190117'
 '12.4K'      | '0.1%'    | '1/16W'  | '0402LF'  | 'CHIP'   | 'CS31242BB00'(!)        = 'End of Design' | 'Comp-Approve'     | 'CS31242BB00'           | 'R0402'             | '(R0402-0201)'                 | '12.4K'   | '0.1%'  | '1/16W'  | 'DISCRETE' | 'RES CHIP 12.4K 1/16W +-0.1%( 0402)'               | 'CHIPR0402'    | ''          | ''            | '20190117'
 '12.4K'      | '0.1%'    | '1/16W'  | '0402LF'  | 'EMPTY'  | 'CS31242BB00'(!)        = 'End of Design' | 'Comp-Approve'     | 'CS31242BB00'           | 'R0402'             | '(R0402-0201)'                 | '12.4K'   | '0.1%'  | '1/16W'  | 'IO'       | 'RES CHIP 12.4K 1/16W +-0.1%( 0402)'               | 'CHIPR0402'    | ''          | ''            | '20190117'
 '42.2'       | '1%'      | '1/20W'  | '0201LF'  | 'CHIP'   | 'CS04221FE00'(!)        = ''              | ''                 | 'CS04221FE00'           | 'R0201'             | '(SMR0201AW)'                  | '42.2'    | '1%'    | '1/20W'  | 'DISCRETE' | 'RES CHIP 42.2 (1/20W,+-1%,0201)'                  | 'CHIPR0201'    | ''          | ''            | '20190123'
 '42.2'       | '1%'      | '1/20W'  | '0201LF'  | 'EMPTY'  | 'CS04221FE00'(!)        = ''              | ''                 | 'CS04221FE00'           | 'R0201'             | '(SMR0201AW)'                  | '42.2'    | '1%'    | '1/20W'  | 'IO'       | 'RES CHIP 42.2 (1/20W,+-1%,0201)'                  | 'CHIPR0201'    | ''          | ''            | '20190123'
 '43.2'       | '1%'      | '1/20W'  | '0201LF'  | 'CHIP'   | 'CS04321FE01'(!)        = ''              | ''                 | 'CS04321FE01'           | 'R0201'             | '(SMR0201AW)'                  | '43.2'    | '1%'    | '1/20W'  | 'DISCRETE' | 'RES CHIP 43.2 1/20W +-1%(0201)'                   | 'CHIPR0201'    | ''          | ''            | '20190124'
 '43.2'       | '1%'      | '1/20W'  | '0201LF'  | 'EMPTY'  | 'CS04321FE01'(!)        = ''              | ''                 | 'CS04321FE01'           | 'R0201'             | '(SMR0201AW)'                  | '43.2'    | '1%'    | '1/20W'  | 'IO'       | 'RES CHIP 43.2 1/20W +-1%(0201)'                   | 'CHIPR0201'    | ''          | ''            | '20190124'
 '4.75K'      | '1%'      | '1/16W'  | '0402LF'  | 'CHIP'   | 'CS24752FB03'(!)        = 'End of Design' | 'Comp-Approve'     | 'CS24752FB03'           | 'R0402'             | '(R0402-0201)'                 | '4.75K'   | '1%'    | '1/16W'  | 'DISCRETE' | 'RES CHIP 4.75K 1/16W +-1%(0402)EF'                | 'CHIPR0402'    | ''          | ''            | '20190124'
 '4.75K'      | '1%'      | '1/16W'  | '0402LF'  | 'EMPTY'  | 'CS24752FB03'(!)        = 'End of Design' | 'Comp-Approve'     | 'CS24752FB03'           | 'R0402'             | '(R0402-0201)'                 | '4.75K'   | '1%'    | '1/16W'  | 'IO'       | 'RES CHIP 4.75K 1/16W +-1%(0402)EF'                | 'CHIPR0402'    | ''          | ''            | '20190124'
 '15'         | '1%'      | '1/16W'  | '0402LF'  | 'CHIP'   | 'CS01502FB03'(!)        = 'End of Design' | 'Comp-Approve'     | 'CS01502FB03'           | 'R0402'             | '(R0402-0201)'                 | '15'      | '1%'    | '1/16W'  | 'DISCRETE' | 'RES CHIP 15 1/16W +-1%(0402)EF'                   | 'CHIPR0402'    | ''          | ''            | '20190212'
 '15'         | '1%'      | '1/16W'  | '0402LF'  | 'EMPTY'  | 'CS01502FB03'(!)        = 'End of Design' | 'Comp-Approve'     | 'CS01502FB03'           | 'R0402'             | '(R0402-0201)'                 | '15'      | '1%'    | '1/16W'  | 'IO'       | 'RES CHIP 15 1/16W +-1%(0402)EF'                   | 'CHIPR0402'    | ''          | ''            | '20190212'
 '825'        | '1%'      | '1/4W'   | '1206LF'  | 'CHIP'   | 'CS18256F200'(!)        = ''              | ''                 | 'CS18256F200'           | 'R1206XF'           | '(SMR1206AW)'                  | '825'     | '1%'    | '1/4W'   | 'DISCRETE' | 'RES CHIP 825 1/4W +-1%(1206)'                     | 'CHIPR1206'    | ''          | ''            | '20190214'
 '825'        | '1%'      | '1/4W'   | '1206LF'  | 'EMPTY'  | 'CS18256F200'(!)        = ''              | ''                 | 'CS18256F200'           | 'R1206XF'           | '(SMR1206AW)'                  | '825'     | '1%'    | '1/4W'   | 'IO'       | 'RES CHIP 825 1/4W +-1%(1206)'                     | 'CHIPR1206'    | ''          | ''            | '20190214'
 '20M'        | '5%'      | '1/10W'  | '0603LF'  | 'CHIP'   | 'CS62003J914'(!)        = ''              | ''                 | 'CS62003J914'           | 'R0603'             | '(SMR0603AW)'                  | '20M'     | '5%'    | '1/10W'  | 'DISCRETE' | 'RES CHIP 20M  1/10W +-5%(0603)'                   | 'CHIPR0603'    | ''          | ''            | '20100429'
 '20M'        | '5%'      | '1/10W'  | '0603LF'  | 'EMPTY'  | 'CS62003J914'(!)        = ''              | ''                 | 'CS62003J914'           | 'R0603'             | '(SMR0603AW)'                  | '20M'     | '5%'    | '1/10W'  | 'IO'       | 'RES CHIP 20M  1/10W +-5%(0603)'                   | 'CHIPR0603'    | ''          | ''            | '20100429'
 '3.3K'       | '5%'      | '1/8W'   | '0805LF'  | 'CHIP'   | 'CS23304JA01'(!)        = ''              | ''                 | 'CS23304JA01'           | 'R0805'             | '(SMR0805AW)'                  | '3.3K'    | '5%'    | '1/8W'   | 'DISCRETE' | 'RES CHIP 3.3K 1/8W +-5%(0805)'                    | 'CHIPR0805'    | ''          | ''            | '20190318'
 '3.3K'       | '5%'      | '1/8W'   | '0805LF'  | 'EMPTY'  | 'CS23304JA01'(!)        = ''              | ''                 | 'CS23304JA01'           | 'R0805'             | '(SMR0805AW)'                  | '3.3K'    | '5%'    | '1/8W'   | 'IO'       | 'RES CHIP 3.3K 1/8W +-5%(0805)'                    | 'CHIPR0805'    | ''          | ''            | '20190318'
 '162'        | '1%'      | '1/16W'  | '0402LF'  | 'CHIP'   | 'CS11622FB01'(!)        = 'End of Design' | 'Comp-Approve'     | 'CS11622FB01'           | 'R0402'             | '(R0402-0201)'                 | '162'     | '1%'    | '1/16W'  | 'DISCRETE' | 'RES CHIP 162 1/16W +-1%(0402)EF'                  | 'CHIPR0402'    | ''          | ''            | '20190325'
 '162'        | '1%'      | '1/16W'  | '0402LF'  | 'EMPTY'  | 'CS11622FB01'(!)        = 'End of Design' | 'Comp-Approve'     | 'CS11622FB01'           | 'R0402'             | '(R0402-0201)'                 | '162'     | '1%'    | '1/16W'  | 'IO'       | 'RES CHIP 162 1/16W +-1%(0402)EF'                  | 'CHIPR0402'    | ''          | ''            | '20190325'
 '681'        | '1%'      | '1/16W'  | '0402LF'  | 'CHIP'   | 'CS16812FB02'(!)        = 'End of Design' | 'Comp-Approve'     | 'CS16812FB02'           | 'R0402'             | '(R0402-0201)'                 | '681'     | '1%'    | '1/16W'  | 'DISCRETE' | 'RES CHIP 681 1/16W +-1%(0402)EF'                  | 'CHIPR0402'    | ''          | ''            | '20190325'
 '681'        | '1%'      | '1/16W'  | '0402LF'  | 'EMPTY'  | 'CS16812FB02'(!)        = 'End of Design' | 'Comp-Approve'     | 'CS16812FB02'           | 'R0402'             | '(R0402-0201)'                 | '681'     | '1%'    | '1/16W'  | 'IO'       | 'RES CHIP 681 1/16W +-1%(0402)EF'                  | 'CHIPR0402'    | ''          | ''            | '20190325'
 '1.82M'      | '1%'      | '1/16W'  | '0402LF'  | 'CHIP'   | 'CS51822FB00'(!)        = ''              | ''                 | 'CS51822FB00'           | 'R0402'             | '(R0402-0201)'                 | '1.82M'   | '1%'    | '1/16W'  | 'DISCRETE' | 'RES CHIP 1.82M 1/16W +-1%(0402)'                  | 'CHIPR0402'    | ''          | ''            | '20190429'
 '1.82M'      | '1%'      | '1/16W'  | '0402LF'  | 'EMPTY'  | 'CS51822FB00'(!)        = ''              | ''                 | 'CS51822FB00'           | 'R0402'             | '(R0402-0201)'                 | '1.82M'   | '1%'    | '1/16W'  | 'IO'       | 'RES CHIP 1.82M 1/16W +-1%(0402)'                  | 'CHIPR0402'    | ''          | ''            | '20190429'
 '240'        | '1%'      | '1/8W'   | '0805LF'  | 'CHIP'   | 'CS12404FA01'(!)        = ''              | ''                 | 'CS12404FA01'           | 'R0805'             | '(SMR0805AW)'                  | '240'     | '1%'    | '1/8W'   | 'DISCRETE' | 'RES CHIP 240 1/8W +-1%(0805)'                     | 'CHIPR0805'    | ''          | ''            | '20190521'
 '240'        | '1%'      | '1/8W'   | '0805LF'  | 'EMPTY'  | 'CS12404FA01'(!)        = ''              | ''                 | 'CS12404FA01'           | 'R0805'             | '(SMR0805AW)'                  | '240'     | '1%'    | '1/8W'   | 'IO'       | 'RES CHIP 240 1/8W +-1%(0805)'                     | 'CHIPR0805'    | ''          | ''            | '20190521'
 '1.62K'      | '0.1%'    | '1/16W'  | '0402LF'  | 'CHIP'   | 'CS21622BB00'(!)        = ''              | ''                 | 'CS21622BB00'           | 'R0402'             | '(R0402-0201)'                 | '1.62K'   | '0.1%'  | '1/16W'  | 'DISCRETE' | 'RES CHIP 1.62K 1/16W +-0.1%(0402)'                | 'CHIPR0402'    | ''          | ''            | '20190527'
 '1.62K'      | '0.1%'    | '1/16W'  | '0402LF'  | 'EMPTY'  | 'CS21622BB00'(!)        = ''              | ''                 | 'CS21622BB00'           | 'R0402'             | '(R0402-0201)'                 | '1.62K'   | '0.1%'  | '1/16W'  | 'IO'       | 'RES CHIP 1.62K 1/16W +-0.1%(0402)'                | 'CHIPR0402'    | ''          | ''            | '20190527'
 '95.3K'      | '0.1%'    | '1/8W'   | '0805LF'  | 'CHIP'   | 'CS39534BA00'(!)        = ''              | ''                 | 'CS39534BA00'           | 'R0805'             | '(SMR0805AW)'                  | '95.3K'   | '0.1%'  | '1/8W'   | 'DISCRETE' | 'RES CHIP 95.3K 1/8W +-0.1%(0805)'                 | 'CHIPR0805'    | ''          | ''            | '20190529'
 '95.3K'      | '0.1%'    | '1/8W'   | '0805LF'  | 'EMPTY'  | 'CS39534BA00'(!)        = ''              | ''                 | 'CS39534BA00'           | 'R0805'             | '(SMR0805AW)'                  | '95.3K'   | '0.1%'  | '1/8W'   | 'IO'       | 'RES CHIP 95.3K 1/8W +-0.1%(0805)'                 | 'CHIPR0805'    | ''          | ''            | '20190529'
 '909'        | '1%'      | '1/16W'  | '0402LF'  | 'CHIP'   | 'CS19092FB03'(!)        = 'End of Design' | 'Comp-Approve'     | 'CS19092FB03'           | 'R0402'             | '(R0402-0201)'                 | '909'     | '1%'    | '1/16W'  | 'DISCRETE' | 'RES CHIP 909 1/16W +-1%(0402)EF'                  | 'CHIPR0402'    | ''          | ''            | '20190614'
 '909'        | '1%'      | '1/16W'  | '0402LF'  | 'EMPTY'  | 'CS19092FB03'(!)        = 'End of Design' | 'Comp-Approve'     | 'CS19092FB03'           | 'R0402'             | '(R0402-0201)'                 | '909'     | '1%'    | '1/16W'  | 'IO'       | 'RES CHIP 909 1/16W +-1%(0402)EF'                  | 'CHIPR0402'    | ''          | ''            | '20190614'
 '90.9K'      | '1%'      | '1/16W'  | '0402LF'  | 'CHIP'   | 'CS39092FB04'(!)        = 'End of Design' | 'Comp-Approve'     | 'CS39092FB04'           | 'R0402'             | '(R0402-0201)'                 | '90.9K'   | '1%'    | '1/16W'  | 'DISCRETE' | 'RES CHIP 90.9K 1/16W +-1%(0402)EF'                | 'CHIPR0402'    | ''          | ''            | '20190715'
 '90.9K'      | '1%'      | '1/16W'  | '0402LF'  | 'EMPTY'  | 'CS39092FB04'(!)        = 'End of Design' | 'Comp-Approve'     | 'CS39092FB04'           | 'R0402'             | '(R0402-0201)'                 | '90.9K'   | '1%'    | '1/16W'  | 'IO'       | 'RES CHIP 90.9K 1/16W +-1%(0402)EF'                | 'CHIPR0402'    | ''          | ''            | '20190715'
 '33.2K'      | '1%'      | '1/16W'  | '0402LF'  | 'CHIP'   | 'CS33322FB03'(!)        = 'End of Design' | 'Comp-Approve'     | 'CS33322FB03'           | 'R0402'             | '(R0402-0201)'                 | '33.2K'   | '1%'    | '1/16W'  | 'DISCRETE' | 'RES CHIP 33.2K 1/16W +-1%(0402)EF'                | 'CHIPR0402'    | ''          | ''            | '20190715'
 '33.2K'      | '1%'      | '1/16W'  | '0402LF'  | 'EMPTY'  | 'CS33322FB03'(!)        = 'End of Design' | 'Comp-Approve'     | 'CS33322FB03'           | 'R0402'             | '(R0402-0201)'                 | '33.2K'   | '1%'    | '1/16W'  | 'IO'       | 'RES CHIP 33.2K 1/16W +-1%(0402)EF'                | 'CHIPR0402'    | ''          | ''            | '20190715'
 '5.6K'       | '1%'      | '1/16W'  | '0402LF'  | 'CHIP'   | 'CS25602FB04'(!)        = ''              | ''                 | 'CS25602FB04'           | 'R0402'             | '(R0402-0201)'                 | '5.6K'    | '1%'    | '1/16W'  | 'DISCRETE' | 'RES CHIP 5.6K 1/16W +-1%(0402)EF'                 | 'CHIPR0402'    | ''          | ''            | '20190711'
 '5.6K'       | '1%'      | '1/16W'  | '0402LF'  | 'EMPTY'  | 'CS25602FB04'(!)        = ''              | ''                 | 'CS25602FB04'           | 'R0402'             | '(R0402-0201)'                 | '5.6K'    | '1%'    | '1/16W'  | 'IO'       | 'RES CHIP 5.6K 1/16W +-1%(0402)EF'                 | 'CHIPR0402'    | ''          | ''            | '20190711'
 '56K'        | '1%'      | '1/16W'  | '0402LF'  | 'CHIP'   | 'CS35602FB00'(!)        = ''              | ''                 | 'CS35602FB00'           | 'R0402'             | '(R0402-0201)'                 | '56K'     | '1%'    | '1/16W'  | 'DISCRETE' | 'RES CHIP 56K 1/16W +-1%(0402)EF'                  | 'CHIPR0402'    | ''          | ''            | '20190711'
 '56K'        | '1%'      | '1/16W'  | '0402LF'  | 'EMPTY'  | 'CS35602FB00'(!)        = ''              | ''                 | 'CS35602FB00'           | 'R0402'             | '(R0402-0201)'                 | '56K'     | '1%'    | '1/16W'  | 'IO'       | 'RES CHIP 56K 1/16W +-1%(0402)EF'                  | 'CHIPR0402'    | ''          | ''            | '20190711'
 '59K'        | '1%'      | '1/16W'  | '0402LF'  | 'CHIP'   | 'CS35902FB01'(!)        = 'End of Design' | 'Comp-Approve'     | 'CS35902FB01'           | 'R0402'             | '(R0402-0201)'                 | '59K'     | '1%'    | '1/16W'  | 'DISCRETE' | 'RES CHIP 59K 1/16W +-1%(0402)EF'                  | 'CHIPR0402'    | ''          | ''            | '20190711'
 '59K'        | '1%'      | '1/16W'  | '0402LF'  | 'EMPTY'  | 'CS35902FB01'(!)        = 'End of Design' | 'Comp-Approve'     | 'CS35902FB01'           | 'R0402'             | '(R0402-0201)'                 | '59K'     | '1%'    | '1/16W'  | 'IO'       | 'RES CHIP 59K 1/16W +-1%(0402)EF'                  | 'CHIPR0402'    | ''          | ''            | '20190711'
 '71.5K'      | '1%'      | '1/16W'  | '0402LF'  | 'CHIP'   | 'CS37152FB05'(!)        = ''              | ''                 | 'CS37152FB05'           | 'R0402'             | '(R0402-0201)'                 | '71.5K'   | '1%'    | '1/16W'  | 'DISCRETE' | 'RES CHIP 71.5K 1/16W +-1%(0402)EF'                | 'CHIPR0402'    | ''          | ''            | '20190717'
 '71.5K'      | '1%'      | '1/16W'  | '0402LF'  | 'EMPTY'  | 'CS37152FB05'(!)        = ''              | ''                 | 'CS37152FB05'           | 'R0402'             | '(R0402-0201)'                 | '71.5K'   | '1%'    | '1/16W'  | 'IO'       | 'RES CHIP 71.5K 1/16W +-1%(0402)EF'                | 'CHIPR0402'    | ''          | ''            | '20190717'
 '24.3K'      | '1%'      | '1/16W'  | '0402LF'  | 'CHIP'   | 'CS32432FB03'(!)        = ''              | ''                 | 'CS32432FB03'           | 'R0402'             | '(R0402-0201)'                 | '24.3K'   | '1%'    | '1/16W'  | 'DISCRETE' | 'RES CHIP 24.3K 1/16W +-1%(0402)EF'                | 'CHIPR0402'    | ''          | ''            | '20190717'
 '24.3K'      | '1%'      | '1/16W'  | '0402LF'  | 'EMPTY'  | 'CS32432FB03'(!)        = ''              | ''                 | 'CS32432FB03'           | 'R0402'             | '(R0402-0201)'                 | '24.3K'   | '1%'    | '1/16W'  | 'IO'       | 'RES CHIP 24.3K 1/16W +-1%(0402)EF'                | 'CHIPR0402'    | ''          | ''            | '20190717'
 '115K'       | '1%'      | '1/16W'  | '0402LF'  | 'CHIP'   | 'CS41152FB03'(!)        = 'End of Design' | 'Comp-Approve'     | 'CS41152FB03'           | 'R0402'             | '(R0402-0201)'                 | '115K'    | '1%'    | '1/16W'  | 'DISCRETE' | 'RES CHIP 115K 1/16W +-1%(0402)EF'                 | 'CHIPR0402'    | ''          | ''            | '20190718'
 '115K'       | '1%'      | '1/16W'  | '0402LF'  | 'EMPTY'  | 'CS41152FB03'(!)        = 'End of Design' | 'Comp-Approve'     | 'CS41152FB03'           | 'R0402'             | '(R0402-0201)'                 | '115K'    | '1%'    | '1/16W'  | 'IO'       | 'RES CHIP 115K 1/16W +-1%(0402)EF'                 | 'CHIPR0402'    | ''          | ''            | '20190718'
 '6.04K'      | '1%'      | '1/16W'  | '0402LF'  | 'CHIP'   | 'CS26042FB04'(!)        = 'End of Design' | 'Comp-Approve'     | 'CS26042FB04'           | 'R0402'             | '(R0402-0201)'                 | '6.04K'   | '1%'    | '1/16W'  | 'DISCRETE' | 'RES CHIP 6.04K 1/16W +-1%(0402)EF'                | 'CHIPR0402'    | ''          | ''            | '20190717'
 '6.04K'      | '1%'      | '1/16W'  | '0402LF'  | 'EMPTY'  | 'CS26042FB04'(!)        = 'End of Design' | 'Comp-Approve'     | 'CS26042FB04'           | 'R0402'             | '(R0402-0201)'                 | '6.04K'   | '1%'    | '1/16W'  | 'IO'       | 'RES CHIP 6.04K 1/16W +-1%(0402)EF'                | 'CHIPR0402'    | ''          | ''            | '20190717'
 '1.33K'      | '1%'      | '1/16W'  | '0402LF'  | 'CHIP'   | 'CS21332FB05'(!)        = ''              | ''                 | 'CS21332FB05'           | 'R0402'             | '(R0402-0201)'                 | '1.33K'   | '1%'    | '1/16W'  | 'DISCRETE' | 'RES CHIP 1.33K 1/16W +-1%(0402)EF'                | 'CHIPR0402'    | ''          | ''            | '20190717'
 '1.33K'      | '1%'      | '1/16W'  | '0402LF'  | 'EMPTY'  | 'CS21332FB05'(!)        = ''              | ''                 | 'CS21332FB05'           | 'R0402'             | '(R0402-0201)'                 | '1.33K'   | '1%'    | '1/16W'  | 'IO'       | 'RES CHIP 1.33K 1/16W +-1%(0402)EF'                | 'CHIPR0402'    | ''          | ''            | '20190717'
 '1'          | '5%'      | '1/16W'  | '0402LF'  | 'CHIP'   | 'CS-1002JB10'(!)        = 'End of Design' | 'Comp-Approve'     | 'CS-1002JB10'           | 'R0402'             | '(R0402-0201)'                 | '1'       | '5%'    | '1/16W'  | 'DISCRETE' | 'RES CHIP 1 1/16W +-5%(0402)EF'                    | 'CHIPR0402'    | ''          | ''            | '20190717'
 '1'          | '5%'      | '1/16W'  | '0402LF'  | 'EMPTY'  | 'CS-1002JB10'(!)        = 'End of Design' | 'Comp-Approve'     | 'CS-1002JB10'           | 'R0402'             | '(R0402-0201)'                 | '1'       | '5%'    | '1/16W'  | 'IO'       | 'RES CHIP 1 1/16W +-5%(0402)EF'                    | 'CHIPR0402'    | ''          | ''            | '20190717'
 '40.2K'      | '1%'      | '1/20W'  | '0201LF'  | 'CHIP'   | 'CS34021FE02'(!)        = ''              | ''                 | 'CS34021FE02'           | 'R0201'             | '(SMR0201AW)'                  | '40.2K'   | '1%'    | '1/20W'  | 'DISCRETE' | 'RES CHIP 40.2K 1/20W +-1%(0201)'                  | 'CHIPR0201'    | ''          | ''            | '20190718'
 '40.2K'      | '1%'      | '1/20W'  | '0201LF'  | 'EMPTY'  | 'CS34021FE02'(!)        = ''              | ''                 | 'CS34021FE02'           | 'R0201'             | '(SMR0201AW)'                  | '40.2K'   | '1%'    | '1/20W'  | 'IO'       | 'RES CHIP 40.2K 1/20W +-1%(0201)'                  | 'CHIPR0201'    | ''          | ''            | '20190718'
 '200'        | '5%'      | '1/10W'  | '0603LF'  | 'CHIP'   | 'CS12003J901'(!)        = ''              | ''                 | 'CS12003J901'           | 'R0603_H24'         | '(SMR0603AW)'                  | '200'     | '5%'    | '1/10W'  | 'DISCRETE' | 'RES CHIP 200 1/10W +-5%(0603)EF'                  | 'CHIPR0603'    | ''          | ''            | '20190717'
 '200'        | '5%'      | '1/10W'  | '0603LF'  | 'EMPTY'  | 'CS12003J901'(!)        = ''              | ''                 | 'CS12003J901'           | 'R0603_H24'         | '(SMR0603AW)'                  | '200'     | '5%'    | '1/10W'  | 'IO'       | 'RES CHIP 200 1/10W +-5%(0603)EF'                  | 'CHIPR0603'    | ''          | ''            | '20190717'
 '2.2'        | '5%'      | '1/16W'  | '0402LF'  | 'CHIP'   | 'CS-2202JB07'(!)        = 'End of Design' | 'Comp-Approve'     | 'CS-2202JB07'           | 'R0402'             | '(R0402-0201)'                 | '2.2'     | '5%'    | '1/16W'  | 'DISCRETE' | 'RES CHIP 2.2 1/16W +-5%  (0402) EF'               | 'CHIPR0402'    | ''          | ''            | '20190717'
 '2.2'        | '5%'      | '1/16W'  | '0402LF'  | 'EMPTY'  | 'CS-2202JB07'(!)        = 'End of Design' | 'Comp-Approve'     | 'CS-2202JB07'           | 'R0402'             | '(R0402-0201)'                 | '2.2'     | '5%'    | '1/16W'  | 'IO'       | 'RES CHIP 2.2 1/16W +-5%  (0402) EF'               | 'CHIPR0402'    | ''          | ''            | '20190717'
 '4.42K'      | '1%'      | '1/16W'  | '0402LF'  | 'CHIP'   | 'CS24422FB03'(!)        = 'End of Design' | 'Comp-Approve'     | 'CS24422FB03'           | 'R0402'             | '(R0402-0201)'                 | '4.42K'   | '1%'    | '1/16W'  | 'DISCRETE' | 'RES CHIP 4.42K 1/16W +-1%(0402)EF'                | 'CHIPR0402'    | ''          | ''            | '20190717'
 '4.42K'      | '1%'      | '1/16W'  | '0402LF'  | 'EMPTY'  | 'CS24422FB03'(!)        = 'End of Design' | 'Comp-Approve'     | 'CS24422FB03'           | 'R0402'             | '(R0402-0201)'                 | '4.42K'   | '1%'    | '1/16W'  | 'IO'       | 'RES CHIP 4.42K 1/16W +-1%(0402)EF'                | 'CHIPR0402'    | ''          | ''            | '20190717'
 '4.99K'      | '1%'      | '1/16W'  | '0402LF'  | 'CHIP'   | 'CS24992FB07'(!)        = 'End of Design' | 'Comp-Approve'     | 'CS24992FB07'           | 'R0402'             | '(R0402-0201)'                 | '4.99K'   | '1%'    | '1/16W'  | 'DISCRETE' | 'RES CHIP 4.99K 1/16W +-1%(0402)EF'                | 'CHIPR0402'    | ''          | ''            | '20190717'
 '4.99K'      | '1%'      | '1/16W'  | '0402LF'  | 'EMPTY'  | 'CS24992FB07'(!)        = 'End of Design' | 'Comp-Approve'     | 'CS24992FB07'           | 'R0402'             | '(R0402-0201)'                 | '4.99K'   | '1%'    | '1/16W'  | 'IO'       | 'RES CHIP 4.99K 1/16W +-1%(0402)EF'                | 'CHIPR0402'    | ''          | ''            | '20190717'
 '8.25K'      | '0.1%'    | '1/16W'  | '0402LF'  | 'CHIP'   | 'CS28252BB01'(!)        = ''              | ''                 | 'CS28252BB01'           | 'R0402'             | '(R0402-0201)'                 | '8.25K'   | '0.1%'  | '1/16W'  | 'DISCRETE' | 'RES CHIP 8.25K 1/16W +-0.1%(0402)EF'              | 'CHIPR0402'    | ''          | ''            | '20190717'
 '8.25K'      | '0.1%'    | '1/16W'  | '0402LF'  | 'EMPTY'  | 'CS28252BB01'(!)        = ''              | ''                 | 'CS28252BB01'           | 'R0402'             | '(R0402-0201)'                 | '8.25K'   | '0.1%'  | '1/16W'  | 'IO'       | 'RES CHIP 8.25K 1/16W +-0.1%(0402)EF'              | 'CHIPR0402'    | ''          | ''            | '20190717'
 '8.87K'      | '1%'      | '1/16W'  | '0402LF'  | 'CHIP'   | 'CS28872FB01'(!)        = 'End of Design' | 'Comp-Approve'     | 'CS28872FB01'           | 'R0402'             | '(R0402-0201)'                 | '8.87K'   | '1%'    | '1/16W'  | 'DISCRETE' | 'RES CHIP 8.87K 1/16W +-1%(0402)EF'                | 'CHIPR0402'    | ''          | ''            | '20190718'
 '8.87K'      | '1%'      | '1/16W'  | '0402LF'  | 'EMPTY'  | 'CS28872FB01'(!)        = 'End of Design' | 'Comp-Approve'     | 'CS28872FB01'           | 'R0402'             | '(R0402-0201)'                 | '8.87K'   | '1%'    | '1/16W'  | 'IO'       | 'RES CHIP 8.87K 1/16W +-1%(0402)EF'                | 'CHIPR0402'    | ''          | ''            | '20190718'
 '18.2K'      | '1%'      | '1/16W'  | '0402LF'  | 'CHIP'   | 'CS31822FB02'(!)        = 'End of Design' | 'Comp-Approve'     | 'CS31822FB02'           | 'R0402'             | '(R0402-0201)'                 | '18.2K'   | '1%'    | '1/16W'  | 'DISCRETE' | 'RES CHIP 18.2K 1/16W +-1%(0402)EF'                | 'CHIPR0402'    | ''          | ''            | '20190718'
 '18.2K'      | '1%'      | '1/16W'  | '0402LF'  | 'EMPTY'  | 'CS31822FB02'(!)        = 'End of Design' | 'Comp-Approve'     | 'CS31822FB02'           | 'R0402'             | '(R0402-0201)'                 | '18.2K'   | '1%'    | '1/16W'  | 'IO'       | 'RES CHIP 18.2K 1/16W +-1%(0402)EF'                | 'CHIPR0402'    | ''          | ''            | '20190718'
 '31.6K'      | '1%'      | '1/16W'  | '0402LF'  | 'CHIP'   | 'CS33162FB02'(!)        = 'End of Design' | 'Comp-Approve'     | 'CS33162FB02'           | 'R0402'             | '(R0402-0201)'                 | '31.6K'   | '1%'    | '1/16W'  | 'DISCRETE' | 'RES CHIP 31.6K 1/16W +-1%(0402)EF'                | 'CHIPR0402'    | ''          | ''            | '20190718'
 '31.6K'      | '1%'      | '1/16W'  | '0402LF'  | 'EMPTY'  | 'CS33162FB02'(!)        = 'End of Design' | 'Comp-Approve'     | 'CS33162FB02'           | 'R0402'             | '(R0402-0201)'                 | '31.6K'   | '1%'    | '1/16W'  | 'IO'       | 'RES CHIP 31.6K 1/16W +-1%(0402)EF'                | 'CHIPR0402'    | ''          | ''            | '20190718'
 '41.2K'      | '1%'      | '1/16W'  | '0402LF'  | 'CHIP'   | 'CS34122FB03'(!)        = 'End of Design' | 'Comp-Approve'     | 'CS34122FB03'           | 'R0402'             | '(R0402-0201)'                 | '41.2K'   | '1%'    | '1/16W'  | 'DISCRETE' | 'RES CHIP 41.2K 1/16W +-1%(0402)EF'                | 'CHIPR0402'    | ''          | ''            | '20190718'
 '41.2K'      | '1%'      | '1/16W'  | '0402LF'  | 'EMPTY'  | 'CS34122FB03'(!)        = 'End of Design' | 'Comp-Approve'     | 'CS34122FB03'           | 'R0402'             | '(R0402-0201)'                 | '41.2K'   | '1%'    | '1/16W'  | 'IO'       | 'RES CHIP 41.2K 1/16W +-1%(0402)EF'                | 'CHIPR0402'    | ''          | ''            | '20190718'
 '47K'        | '5%'      | '1/16W'  | '0402LF'  | 'CHIP'   | 'CS34702JB09'(!)        = ''              | ''                 | 'CS34702JB09'           | 'R0402'             | '(R0402-0201)'                 | '47K'     | '5%'    | '1/16W'  | 'DISCRETE' | 'RES CHIP 47K 1/16W +-5%(0402)EF'                  | 'CHIPR0402'    | ''          | ''            | '20190718'
 '47K'        | '5%'      | '1/16W'  | '0402LF'  | 'EMPTY'  | 'CS34702JB09'(!)        = ''              | ''                 | 'CS34702JB09'           | 'R0402'             | '(R0402-0201)'                 | '47K'     | '5%'    | '1/16W'  | 'IO'       | 'RES CHIP 47K 1/16W +-5%(0402)EF'                  | 'CHIPR0402'    | ''          | ''            | '20190718'
 '53.6K'      | '1%'      | '1/16W'  | '0402LF'  | 'CHIP'   | 'CS35362FB02'(!)        = 'End of Design' | 'Comp-Approve'     | 'CS35362FB02'           | 'R0402'             | '(R0402-0201)'                 | '53.6K'   | '1%'    | '1/16W'  | 'DISCRETE' | 'RES CHIP 53.6K 1/16W +-1%(0402)EF'                | 'CHIPR0402'    | ''          | ''            | '20190718'
 '53.6K'      | '1%'      | '1/16W'  | '0402LF'  | 'EMPTY'  | 'CS35362FB02'(!)        = 'End of Design' | 'Comp-Approve'     | 'CS35362FB02'           | 'R0402'             | '(R0402-0201)'                 | '53.6K'   | '1%'    | '1/16W'  | 'IO'       | 'RES CHIP 53.6K 1/16W +-1%(0402)EF'                | 'CHIPR0402'    | ''          | ''            | '20190718'
 '60.4K'      | '0.1%'    | '1/16W'  | '0402LF'  | 'CHIP'   | 'CS36042BB01'(!)        = ''              | ''                 | 'CS36042BB01'           | 'R0402'             | '(R0402-0201)'                 | '60.4K'   | '0.1%'  | '1/16W'  | 'DISCRETE' | 'RES CHIP 60.4K 1/16W +-0.1%(0402)EF'              | 'CHIPR0402'    | ''          | ''            | '20190718'
 '60.4K'      | '0.1%'    | '1/16W'  | '0402LF'  | 'EMPTY'  | 'CS36042BB01'(!)        = ''              | ''                 | 'CS36042BB01'           | 'R0402'             | '(R0402-0201)'                 | '60.4K'   | '0.1%'  | '1/16W'  | 'IO'       | 'RES CHIP 60.4K 1/16W +-0.1%(0402)EF'              | 'CHIPR0402'    | ''          | ''            | '20190718'
 '61.9K'      | '1%'      | '1/16W'  | '0402LF'  | 'CHIP'   | 'CS36192FB04'(!)        = 'End of Design' | 'Comp-Approve'     | 'CS36192FB04'           | 'R0402'             | '(R0402-0201)'                 | '61.9K'   | '1%'    | '1/16W'  | 'DISCRETE' | 'RES CHIP 61.9K 1/16W +-1%(0402)EF'                | 'CHIPR0402'    | ''          | ''            | '20190718'
 '61.9K'      | '1%'      | '1/16W'  | '0402LF'  | 'EMPTY'  | 'CS36192FB04'(!)        = 'End of Design' | 'Comp-Approve'     | 'CS36192FB04'           | 'R0402'             | '(R0402-0201)'                 | '61.9K'   | '1%'    | '1/16W'  | 'IO'       | 'RES CHIP 61.9K 1/16W +-1%(0402)EF'                | 'CHIPR0402'    | ''          | ''            | '20190718'
 '82K'        | '1%'      | '1/16W'  | '0402LF'  | 'CHIP'   | 'CS38202FB01'(!)        = 'End of Design' | 'Comp-Approve'     | 'CS38202FB01'           | 'R0402'             | '(R0402-0201)'                 | '82K'     | '1%'    | '1/16W'  | 'DISCRETE' | 'RES CHIP 82K  1/16W +-1% (0402)EF'                | 'CHIPR0402'    | ''          | ''            | '20190718'
 '82K'        | '1%'      | '1/16W'  | '0402LF'  | 'EMPTY'  | 'CS38202FB01'(!)        = 'End of Design' | 'Comp-Approve'     | 'CS38202FB01'           | 'R0402'             | '(R0402-0201)'                 | '82K'     | '1%'    | '1/16W'  | 'IO'       | 'RES CHIP 82K  1/16W +-1% (0402)EF'                | 'CHIPR0402'    | ''          | ''            | '20190718'
 '140K'       | '1%'      | '1/16W'  | '0402LF'  | 'CHIP'   | 'CS41402FB01'(!)        = 'End of Design' | 'Comp-Approve'     | 'CS41402FB01'           | 'R0402'             | '(R0402-0201)'                 | '140K'    | '1%'    | '1/16W'  | 'DISCRETE' | 'RES CHIP 140K 1/16W +-1%(0402)EF'                 | 'CHIPR0402'    | ''          | ''            | '20190718'
 '140K'       | '1%'      | '1/16W'  | '0402LF'  | 'EMPTY'  | 'CS41402FB01'(!)        = 'End of Design' | 'Comp-Approve'     | 'CS41402FB01'           | 'R0402'             | '(R0402-0201)'                 | '140K'    | '1%'    | '1/16W'  | 'IO'       | 'RES CHIP 140K 1/16W +-1%(0402)EF'                 | 'CHIPR0402'    | ''          | ''            | '20190718'
 '200K'       | '5%'      | '1/16W'  | '0402LF'  | 'CHIP'   | 'CS42002JB02'(!)        = 'End of Design' | 'Comp-Approve'     | 'CS42002JB02'           | 'R0402'             | '(R0402-0201)'                 | '200K'    | '5%'    | '1/16W'  | 'DISCRETE' | 'RES CHIP 200K 1/16W +-5%(0402)EF'                 | 'CHIPR0402'    | ''          | ''            | '20190718'
 '200K'       | '5%'      | '1/16W'  | '0402LF'  | 'EMPTY'  | 'CS42002JB02'(!)        = 'End of Design' | 'Comp-Approve'     | 'CS42002JB02'           | 'R0402'             | '(R0402-0201)'                 | '200K'    | '5%'    | '1/16W'  | 'IO'       | 'RES CHIP 200K 1/16W +-5%(0402)EF'                 | 'CHIPR0402'    | ''          | ''            | '20190718'
 '22.6K'      | '1%'      | '1/16W'  | '0402LF'  | 'CHIP'   | 'CS32262FB02'(!)        = 'End of Design' | 'Comp-Approve'     | 'CS32262FB02'           | 'R0402'             | '(R0402-0201)'                 | '22.6K'   | '1%'    | '1/16W'  | 'DISCRETE' | 'RES CHIP 22.6K 1/16W +-1%(0402)EF'                | 'CHIPR0402'    | ''          | ''            | '20190718'
 '22.6K'      | '1%'      | '1/16W'  | '0402LF'  | 'EMPTY'  | 'CS32262FB02'(!)        = 'End of Design' | 'Comp-Approve'     | 'CS32262FB02'           | 'R0402'             | '(R0402-0201)'                 | '22.6K'   | '1%'    | '1/16W'  | 'IO'       | 'RES CHIP 22.6K 1/16W +-1%(0402)EF'                | 'CHIPR0402'    | ''          | ''            | '20190718'
 '36.5K'      | '1%'      | '1/16W'  | '0402LF'  | 'CHIP'   | 'CS33652FB03'(!)        = 'End of Design' | 'Comp-Approve'     | 'CS33652FB03'           | 'R0402'             | '(R0402-0201)'                 | '36.5K'   | '1%'    | '1/16W'  | 'DISCRETE' | 'RES CHIP 36.5K 1/16W +-1%(0402)EF'                | 'CHIPR0402'    | ''          | ''            | '20190718'
 '36.5K'      | '1%'      | '1/16W'  | '0402LF'  | 'EMPTY'  | 'CS33652FB03'(!)        = 'End of Design' | 'Comp-Approve'     | 'CS33652FB03'           | 'R0402'             | '(R0402-0201)'                 | '36.5K'   | '1%'    | '1/16W'  | 'IO'       | 'RES CHIP 36.5K 1/16W +-1%(0402)EF'                | 'CHIPR0402'    | ''          | ''            | '20190718'
 '1'          | '1%'      | '1/2W'   | '1206LF'  | 'CHIP'   | 'CS-1007F201'(!)        = 'End of Design' | 'Comp-Approve'     | 'CS-1007F201'           | 'R1206XI'           | '(SMR1206AW)'                  | '1'       | '1%'    | '1/2W'   | 'DISCRETE' | 'RES CHIP 1 1/2W +-1%(1206)EF'                     | 'CHIPR1206'    | ''          | ''            | '20190722'
 '1'          | '1%'      | '1/2W'   | '1206LF'  | 'EMPTY'  | 'CS-1007F201'(!)        = 'End of Design' | 'Comp-Approve'     | 'CS-1007F201'           | 'R1206XI'           | '(SMR1206AW)'                  | '1'       | '1%'    | '1/2W'   | 'IO'       | 'RES CHIP 1 1/2W +-1%(1206)EF'                     | 'CHIPR1206'    | ''          | ''            | '20190722'
 '1'          | '1%'      | '1/4W'   | '1206LF'  | 'CHIP'   | 'CS-1006F203'(!)        = ''              | ''                 | 'CS-1006F203'           | 'R1206XF'           | '(SMR1206AW)'                  | '1'       | '1%'    | '1/4W'   | 'DISCRETE' | 'RES CHIP 1 1/4W +-1%(1206)EF'                     | 'CHIPR1206'    | ''          | ''            | '20190722'
 '1'          | '1%'      | '1/4W'   | '1206LF'  | 'EMPTY'  | 'CS-1006F203'(!)        = ''              | ''                 | 'CS-1006F203'           | 'R1206XF'           | '(SMR1206AW)'                  | '1'       | '1%'    | '1/4W'   | 'IO'       | 'RES CHIP 1 1/4W +-1%(1206)EF'                     | 'CHIPR1206'    | ''          | ''            | '20190722'
 '576'        | '1%'      | '1/16W'  | '0402LF'  | 'CHIP'   | 'CS15762FB03'(!)        = 'End of Design' | 'Comp-Approve'     | 'CS15762FB03'           | 'R0402'             | '(R0402-0201)'                 | '576'     | '1%'    | '1/16W'  | 'DISCRETE' | 'RES CHIP 576 1/16W +-1%(0402)EF'                  | 'CHIPR0402'    | ''          | ''            | '20190729'
 '576'        | '1%'      | '1/16W'  | '0402LF'  | 'EMPTY'  | 'CS15762FB03'(!)        = 'End of Design' | 'Comp-Approve'     | 'CS15762FB03'           | 'R0402'             | '(R0402-0201)'                 | '576'     | '1%'    | '1/16W'  | 'IO'       | 'RES CHIP 576 1/16W +-1%(0402)EF'                  | 'CHIPR0402'    | ''          | ''            | '20190729'
 '1.37K'      | '1%'      | '1/16W'  | '0402LF'  | 'CHIP'   | 'CS21372FB03'(!)        = 'End of Design' | 'Comp-Approve'     | 'CS21372FB03'           | 'R0402'             | '(R0402-0201)'                 | '1.37K'   | '1%'    | '1/16W'  | 'DISCRETE' | 'RES CHIP 1.37K 1/16W +-1%(0402)EF'                | 'CHIPR0402'    | ''          | ''            | '20190729'
 '1.37K'      | '1%'      | '1/16W'  | '0402LF'  | 'EMPTY'  | 'CS21372FB03'(!)        = 'End of Design' | 'Comp-Approve'     | 'CS21372FB03'           | 'R0402'             | '(R0402-0201)'                 | '1.37K'   | '1%'    | '1/16W'  | 'IO'       | 'RES CHIP 1.37K 1/16W +-1%(0402)EF'                | 'CHIPR0402'    | ''          | ''            | '20190729'
 '27'         | '5%'      | '1/16W'  | '0402LF'  | 'CHIP'   | 'CS02702JB02'(!)        = 'End of Design' | 'Comp-Approve'     | 'CS02702JB02'           | 'R0402'             | '(R0402-0201)'                 | '27'      | '5%'    | '1/16W'  | 'DISCRETE' | 'RES CHIP 27 1/16W +-5%(0402)EF'                   | 'CHIPR0402'    | ''          | ''            | '20190729'
 '27'         | '5%'      | '1/16W'  | '0402LF'  | 'EMPTY'  | 'CS02702JB02'(!)        = 'End of Design' | 'Comp-Approve'     | 'CS02702JB02'           | 'R0402'             | '(R0402-0201)'                 | '27'      | '5%'    | '1/16W'  | 'IO'       | 'RES CHIP 27 1/16W +-5%(0402)EF'                   | 'CHIPR0402'    | ''          | ''            | '20190729'
 '43.2'       | '1%'      | '1/16W'  | '0402LF'  | 'CHIP'   | 'CS04322FB01'(!)        = 'End of Design' | 'Comp-Approve'     | 'CS04322FB01'           | 'R0402'             | '(R0402-0201)'                 | '43.2'    | '1%'    | '1/16W'  | 'DISCRETE' | 'RES CHIP 43.2 1/16W +-1%(0402)EF'                 | 'CHIPR0402'    | ''          | ''            | '20190729'
 '43.2'       | '1%'      | '1/16W'  | '0402LF'  | 'EMPTY'  | 'CS04322FB01'(!)        = 'End of Design' | 'Comp-Approve'     | 'CS04322FB01'           | 'R0402'             | '(R0402-0201)'                 | '43.2'    | '1%'    | '1/16W'  | 'IO'       | 'RES CHIP 43.2 1/16W +-1%(0402)EF'                 | 'CHIPR0402'    | ''          | ''            | '20190729'
 '100'        | '5%'      | '1/16W'  | '0402LF'  | 'CHIP'   | 'CS11002JB06'(!)        = 'End of Design' | 'Comp-Approve'     | 'CS11002JB06'           | 'R0402'             | '(R0402-0201)'                 | '100'     | '5%'    | '1/16W'  | 'DISCRETE' | 'RES CHIP 100 1/16W +-5%(0402)EF'                  | 'CHIPR0402'    | ''          | ''            | '20190729'
 '100'        | '5%'      | '1/16W'  | '0402LF'  | 'EMPTY'  | 'CS11002JB06'(!)        = 'End of Design' | 'Comp-Approve'     | 'CS11002JB06'           | 'R0402'             | '(R0402-0201)'                 | '100'     | '5%'    | '1/16W'  | 'IO'       | 'RES CHIP 100 1/16W +-5%(0402)EF'                  | 'CHIPR0402'    | ''          | ''            | '20190729'
 '4.7K'       | '5%'      | '1/16W'  | '0402LF'  | 'CHIP'   | 'CS24702JB10'(!)        = 'End of Design' | 'Comp-Approve'     | 'CS24702JB10'           | 'R0402'             | '(R0402-0201)'                 | '4.7K'    | '5%'    | '1/16W'  | 'DISCRETE' | 'RES CHIP 4.7K 1/16W +-5%(0402)EF'                 | 'CHIPR0402'    | ''          | ''            | '20190729'
 '4.7K'       | '5%'      | '1/16W'  | '0402LF'  | 'EMPTY'  | 'CS24702JB10'(!)        = 'End of Design' | 'Comp-Approve'     | 'CS24702JB10'           | 'R0402'             | '(R0402-0201)'                 | '4.7K'    | '5%'    | '1/16W'  | 'IO'       | 'RES CHIP 4.7K 1/16W +-5%(0402)EF'                 | 'CHIPR0402'    | ''          | ''            | '20190729'
 '5.11K'      | '1%'      | '1/16W'  | '0402LF'  | 'CHIP'   | 'CS25112FB04'(!)        = 'End of Design' | 'Comp-Approve'     | 'CS25112FB04'           | 'R0402'             | '(R0402-0201)'                 | '5.11K'   | '1%'    | '1/16W'  | 'DISCRETE' | 'RES CHIP 5.11K 1/16W +-1%(0402)EF'                | 'CHIPR0402'    | ''          | ''            | '20190726'
 '5.11K'      | '1%'      | '1/16W'  | '0402LF'  | 'EMPTY'  | 'CS25112FB04'(!)        = 'End of Design' | 'Comp-Approve'     | 'CS25112FB04'           | 'R0402'             | '(R0402-0201)'                 | '5.11K'   | '1%'    | '1/16W'  | 'IO'       | 'RES CHIP 5.11K 1/16W +-1%(0402)EF'                | 'CHIPR0402'    | ''          | ''            | '20190726'
 '82.5K'      | '1%'      | '1/16W'  | '0402LF'  | 'CHIP'   | 'CS38252FB01'(!)        = ''              | ''                 | 'CS38252FB01'           | 'R0402'             | '(R0402-0201)'                 | '82.5K'   | '1%'    | '1/16W'  | 'DISCRETE' | 'RES CHIP 82.5K 1/16W +-1%(0402)EF'                | 'CHIPR0402'    | ''          | ''            | '20190730'
 '82.5K'      | '1%'      | '1/16W'  | '0402LF'  | 'EMPTY'  | 'CS38252FB01'(!)        = ''              | ''                 | 'CS38252FB01'           | 'R0402'             | '(R0402-0201)'                 | '82.5K'   | '1%'    | '1/16W'  | 'IO'       | 'RES CHIP 82.5K 1/16W +-1%(0402)EF'                | 'CHIPR0402'    | ''          | ''            | '20190730'
 '17.8K'      | '1%'      | '1/16W'  | '0402LF'  | 'CHIP'   | 'CS31782FB04'(!)        = 'End of Design' | 'Comp-Approve'     | 'CS31782FB04'           | 'R0402'             | '(R0402-0201)'                 | '17.8K'   | '1%'    | '1/16W'  | 'DISCRETE' | 'RES CHIP 17.8K 1/16W +- 1% (0402)EF'              | 'CHIPR0402'    | ''          | ''            | '20190730'
 '17.8K'      | '1%'      | '1/16W'  | '0402LF'  | 'EMPTY'  | 'CS31782FB04'(!)        = 'End of Design' | 'Comp-Approve'     | 'CS31782FB04'           | 'R0402'             | '(R0402-0201)'                 | '17.8K'   | '1%'    | '1/16W'  | 'IO'       | 'RES CHIP 17.8K 1/16W +- 1% (0402)EF'              | 'CHIPR0402'    | ''          | ''            | '20190730'
 '953'        | '1%'      | '1/10W'  | '0603LF'  | 'CHIP'   | 'CS19533F901'(!)        = 'End of Design' | 'Comp-Approve'     | 'CS19533F901'           | 'R0603_H24'         | '(SMR0603AW)'                  | '953'     | '1%'    | '1/10W'  | 'DISCRETE' | 'RES CHIP 953 1/10W +-1%(0603)EF'                  | 'CHIPR0603'    | ''          | ''            | '20190730'
 '953'        | '1%'      | '1/10W'  | '0603LF'  | 'EMPTY'  | 'CS19533F901'(!)        = 'End of Design' | 'Comp-Approve'     | 'CS19533F901'           | 'R0603_H24'         | '(SMR0603AW)'                  | '953'     | '1%'    | '1/10W'  | 'IO'       | 'RES CHIP 953 1/10W +-1%(0603)EF'                  | 'CHIPR0603'    | ''          | ''            | '20190730'
 '1.6K'       | '1%'      | '1/10W'  | '0603LF'  | 'CHIP'   | 'CS21603F900'(!)        = 'End of Design' | 'Comp-Approve'     | 'CS21603F900'           | 'R0603_H24'         | '(SMR0603AW)'                  | '1.6K'    | '1%'    | '1/10W'  | 'DISCRETE' | 'RES CHIP 1.6K 1/10W +-1% (0603)EF'                | 'CHIPR0603'    | ''          | ''            | '20190731'
 '1.6K'       | '1%'      | '1/10W'  | '0603LF'  | 'EMPTY'  | 'CS21603F900'(!)        = 'End of Design' | 'Comp-Approve'     | 'CS21603F900'           | 'R0603_H24'         | '(SMR0603AW)'                  | '1.6K'    | '1%'    | '1/10W'  | 'IO'       | 'RES CHIP 1.6K 1/10W +-1% (0603)EF'                | 'CHIPR0603'    | ''          | ''            | '20190731'
 '681K'       | '1%'      | '1/16W'  | '0402LF'  | 'CHIP'   | 'CS46812FB06'(!)        = ''              | ''                 | 'CS46812FB06'           | 'R0402'             | '(R0402-0201)'                 | '681K'    | '1%'    | '1/16W'  | 'DISCRETE' | 'RES CHIP 681K 1/16W +-1%(0402)EF'                 | 'CHIPR0402'    | ''          | ''            | '20190731'
 '681K'       | '1%'      | '1/16W'  | '0402LF'  | 'EMPTY'  | 'CS46812FB06'(!)        = ''              | ''                 | 'CS46812FB06'           | 'R0402'             | '(R0402-0201)'                 | '681K'    | '1%'    | '1/16W'  | 'IO'       | 'RES CHIP 681K 1/16W +-1%(0402)EF'                 | 'CHIPR0402'    | ''          | ''            | '20190731'
 '0.004'      | '1%'      | '1W'     | '1206LF'  | 'CHIP'   | 'CS+0048F201'(!)        = 'End of Design' | 'Comp-Release Qty' | 'CS+0048F201'           | 'R1206XD_H36'       | '(SMR1206AW)'                  | '0.004'   | '1%'    | '1W'     | 'DISCRETE' | 'RES CHIP 0.004 1W +-1%(1206)EF'                   | 'CHIPR1206'    | ''          | ''            | '20190731'
 '0.004'      | '1%'      | '1W'     | '1206LF'  | 'EMPTY'  | 'CS+0048F201'(!)        = 'End of Design' | 'Comp-Release Qty' | 'CS+0048F201'           | 'R1206XD_H36'       | '(SMR1206AW)'                  | '0.004'   | '1%'    | '1W'     | 'IO'       | 'RES CHIP 0.004 1W +-1%(1206)EF'                   | 'CHIPR1206'    | ''          | ''            | '20190731'
 '1.5K'       | '0.1%'    | '1/16W'  | '0402LF'  | 'CHIP'   | 'CS21502BB00'(!)        = ''              | ''                 | 'CS21502BB00'           | 'R0402'             | '(R0402-0201)'                 | '1.5K'    | '0.1%'  | '1/16W'  | 'DISCRETE' | 'RES CHIP 1.5K 1/16W +-0.1% (0402)'                | 'CHIPR0402'    | ''          | ''            | '20190801'
 '1.5K'       | '0.1%'    | '1/16W'  | '0402LF'  | 'EMPTY'  | 'CS21502BB00'(!)        = ''              | ''                 | 'CS21502BB00'           | 'R0402'             | '(R0402-0201)'                 | '1.5K'    | '0.1%'  | '1/16W'  | 'IO'       | 'RES CHIP 1.5K 1/16W +-0.1% (0402)'                | 'CHIPR0402'    | ''          | ''            | '20190801'
 '56K'        | '0.1%'    | '1/16W'  | '0402LF'  | 'CHIP'   | 'CS35602BB00'(!)        = ''              | ''                 | 'CS35602BB00'           | 'R0402'             | '(R0402-0201)'                 | '56K'     | '0.1%'  | '1/16W'  | 'DISCRETE' | 'RES CHIP 56K 1/16W +-0.1%(0402)'                  | 'CHIPR0402'    | ''          | ''            | '20190821'
 '56K'        | '0.1%'    | '1/16W'  | '0402LF'  | 'EMPTY'  | 'CS35602BB00'(!)        = ''              | ''                 | 'CS35602BB00'           | 'R0402'             | '(R0402-0201)'                 | '56K'     | '0.1%'  | '1/16W'  | 'IO'       | 'RES CHIP 56K 1/16W +-0.1%(0402)'                  | 'CHIPR0402'    | ''          | ''            | '20190821'
 '7.87K'      | '1%'      | '1/16W'  | '0402LF'  | 'CHIP'   | 'CS27872FB02'(!)        = 'End of Design' | 'Comp-Approve'     | 'CS27872FB02'           | 'R0402'             | '(R0402-0201)'                 | '7.87K'   | '1%'    | '1/16W'  | 'DISCRETE' | 'RES CHIP 7.87K 1/16W +-1%(0402)EF'                | 'CHIPR0402'    | ''          | ''            | '20190820'
 '7.87K'      | '1%'      | '1/16W'  | '0402LF'  | 'EMPTY'  | 'CS27872FB02'(!)        = 'End of Design' | 'Comp-Approve'     | 'CS27872FB02'           | 'R0402'             | '(R0402-0201)'                 | '7.87K'   | '1%'    | '1/16W'  | 'IO'       | 'RES CHIP 7.87K 1/16W +-1%(0402)EF'                | 'CHIPR0402'    | ''          | ''            | '20190820'
 '13.3K'      | '1%'      | '1/16W'  | '0402LF'  | 'CHIP'   | 'CS31332FB02'(!)        = 'End of Design' | 'Comp-Approve'     | 'CS31332FB02'           | 'R0402'             | '(R0402-0201)'                 | '13.3K'   | '1%'    | '1/16W'  | 'DISCRETE' | 'RES CHIP 13.3K 1/16W +-1%(0402)EF'                | 'CHIPR0402'    | ''          | ''            | '20190820'
 '13.3K'      | '1%'      | '1/16W'  | '0402LF'  | 'EMPTY'  | 'CS31332FB02'(!)        = 'End of Design' | 'Comp-Approve'     | 'CS31332FB02'           | 'R0402'             | '(R0402-0201)'                 | '13.3K'   | '1%'    | '1/16W'  | 'IO'       | 'RES CHIP 13.3K 1/16W +-1%(0402)EF'                | 'CHIPR0402'    | ''          | ''            | '20190820'
 '1.47K'      | '1%'      | '1/16W'  | '0402LF'  | 'CHIP'   | 'CS21472FB02'(!)        = 'End of Design' | 'Comp-Approve'     | 'CS21472FB02'           | 'R0402'             | '(R0402-0201)'                 | '1.47K'   | '1%'    | '1/16W'  | 'DISCRETE' | 'RES CHIP 1.47K 1/16W +-1%(0402)EF'                | 'CHIPR0402'    | ''          | ''            | '20190821'
 '1.47K'      | '1%'      | '1/16W'  | '0402LF'  | 'EMPTY'  | 'CS21472FB02'(!)        = 'End of Design' | 'Comp-Approve'     | 'CS21472FB02'           | 'R0402'             | '(R0402-0201)'                 | '1.47K'   | '1%'    | '1/16W'  | 'IO'       | 'RES CHIP 1.47K 1/16W +-1%(0402)EF'                | 'CHIPR0402'    | ''          | ''            | '20190821'
 '76.8K'      | '1%'      | '1/20W'  | '0201LF'  | 'CHIP'   | 'CS37681FE01'(!)        = ''              | ''                 | 'CS37681FE01'           | 'R0201'             | '(SMR0201AW)'                  | '76.8K'   | '1%'    | '1/20W'  | 'DISCRETE' | 'RES CHIP 76.8K 1/20W +-1%(0201)YGOSELASN'         | 'CHIPR0201'    | ''          | ''            | '20190821'
 '76.8K'      | '1%'      | '1/20W'  | '0201LF'  | 'EMPTY'  | 'CS37681FE01'(!)        = ''              | ''                 | 'CS37681FE01'           | 'R0201'             | '(SMR0201AW)'                  | '76.8K'   | '1%'    | '1/20W'  | 'IO'       | 'RES CHIP 76.8K 1/20W +-1%(0201)YGOSELASN'         | 'CHIPR0201'    | ''          | ''            | '20190821'
 '17.4K'      | '1%'      | '1/16W'  | '0402LF'  | 'CHIP'   | 'CS31742FB04'(!)        = 'End of Design' | 'Comp-Approve'     | 'CS31742FB04'           | 'R0402'             | '(R0402-0201)'                 | '17.4K'   | '1%'    | '1/16W'  | 'DISCRETE' | 'RES CHIP 17.4K 1/16W +-1%(0402)EF'                | 'CHIPR0402'    | ''          | ''            | '20190826'
 '17.4K'      | '1%'      | '1/16W'  | '0402LF'  | 'EMPTY'  | 'CS31742FB04'(!)        = 'End of Design' | 'Comp-Approve'     | 'CS31742FB04'           | 'R0402'             | '(R0402-0201)'                 | '17.4K'   | '1%'    | '1/16W'  | 'IO'       | 'RES CHIP 17.4K 1/16W +-1%(0402)EF'                | 'CHIPR0402'    | ''          | ''            | '20190826'
 '0.15'       | '1%'      | '1/2W'   | '1206LF'  | 'CHIP'   | 'CS+1507F200'(!)        = ''              | ''                 | 'CS+1507F200'           | 'R1206XF'           | '(SMR1206AW)'                  | '0.15'    | '1%'    | '1/2W'   | 'DISCRETE' | 'RES CHIP 0.15 1/2W +-1%(1206)'                    | 'CHIPR1206'    | ''          | ''            | '20190829'
 '0.15'       | '1%'      | '1/2W'   | '1206LF'  | 'EMPTY'  | 'CS+1507F200'(!)        = ''              | ''                 | 'CS+1507F200'           | 'R1206XF'           | '(SMR1206AW)'                  | '0.15'    | '1%'    | '1/2W'   | 'IO'       | 'RES CHIP 0.15 1/2W +-1%(1206)'                    | 'CHIPR1206'    | ''          | ''            | '20190829'
 '680'        | '1%'      | '1/16W'  | '0402LF'  | 'CHIP'   | 'CS16802FB03'(!)        = ''              | ''                 | 'CS16802FB03'           | 'R0402'             | '(R0402-0201)'                 | '680'     | '1%'    | '1/16W'  | 'DISCRETE' | 'RES CHIP 680 1/16W +-1%(0402)EF'                  | 'CHIPR0402'    | ''          | ''            | '20190829'
 '680'        | '1%'      | '1/16W'  | '0402LF'  | 'EMPTY'  | 'CS16802FB03'(!)        = ''              | ''                 | 'CS16802FB03'           | 'R0402'             | '(R0402-0201)'                 | '680'     | '1%'    | '1/16W'  | 'IO'       | 'RES CHIP 680 1/16W +-1%(0402)EF'                  | 'CHIPR0402'    | ''          | ''            | '20190829'
 '3.57K'      | '1%'      | '1/16W'  | '0402LF'  | 'CHIP'   | 'CS23572FB05'(!)        = 'End of Design' | 'Comp-Approve'     | 'CS23572FB05'           | 'R0402'             | '(R0402-0201)'                 | '3.57K'   | '1%'    | '1/16W'  | 'DISCRETE' | 'RES CHIP 3.57K 1/16W +-1%(0402)EF'                | 'CHIPR0402'    | ''          | ''            | '20190829'
 '3.57K'      | '1%'      | '1/16W'  | '0402LF'  | 'EMPTY'  | 'CS23572FB05'(!)        = 'End of Design' | 'Comp-Approve'     | 'CS23572FB05'           | 'R0402'             | '(R0402-0201)'                 | '3.57K'   | '1%'    | '1/16W'  | 'IO'       | 'RES CHIP 3.57K 1/16W +-1%(0402)EF'                | 'CHIPR0402'    | ''          | ''            | '20190829'
 '76.8K'      | '1%'      | '1/20W'  | '0201LF'  | 'CHIP'   | 'CS37681FE06'(!)        = ''              | ''                 | 'CS37681FE06'           | 'R0201'             | '(SMR0201AW)'                  | '76.8K'   | '1%'    | '1/20W'  | 'DISCRETE' | 'RES CHIP 76.8K 1/20W +-1%(0201)'                  | 'CHIPR0201'    | ''          | ''            | '20190829'
 '76.8K'      | '1%'      | '1/20W'  | '0201LF'  | 'EMPTY'  | 'CS37681FE06'(!)        = ''              | ''                 | 'CS37681FE06'           | 'R0201'             | '(SMR0201AW)'                  | '76.8K'   | '1%'    | '1/20W'  | 'IO'       | 'RES CHIP 76.8K 1/20W +-1%(0201)'                  | 'CHIPR0201'    | ''          | ''            | '20190829'
 '0.003'      | '1%'      | '1W'     | '1206LF'  | 'CHIP'   | 'CS+0038F203'(!)        = ''              | ''                 | 'CS+0038F203'           | 'R1206XK'           | '(SMR1206AW)'                  | '0.003'   | '1%'    | '1W'     | 'DISCRETE' | 'RES CHIP 0.003 1W +-1%(1206)'                     | 'CHIPR1206'    | ''          | ''            | '20190828'
 '0.003'      | '1%'      | '1W'     | '1206LF'  | 'EMPTY'  | 'CS+0038F203'(!)        = ''              | ''                 | 'CS+0038F203'           | 'R1206XK'           | '(SMR1206AW)'                  | '0.003'   | '1%'    | '1W'     | 'IO'       | 'RES CHIP 0.003 1W +-1%(1206)'                     | 'CHIPR1206'    | ''          | ''            | '20190828'
 '1.1M'       | '1%'      | '1/8W'   | '0805LF'  | 'CHIP'   | 'CS51104FA00'(!)        = ''              | ''                 | 'CS51104FA00'           | 'R0805'             | '(SMR0805AW)'                  | '1.1M'    | '1%'    | '1/8W'   | 'DISCRETE' | 'RES CHIP 1.1M 1/8W +-1%(0805)'                    | 'CHIPR0805'    | ''          | ''            | '20190826'
 '1.1M'       | '1%'      | '1/8W'   | '0805LF'  | 'EMPTY'  | 'CS51104FA00'(!)        = ''              | ''                 | 'CS51104FA00'           | 'R0805'             | '(SMR0805AW)'                  | '1.1M'    | '1%'    | '1/8W'   | 'IO'       | 'RES CHIP 1.1M 1/8W +-1%(0805)'                    | 'CHIPR0805'    | ''          | ''            | '20190826'
 '28.7K'      | '1%'      | '1/10W'  | '0603LF'  | 'CHIP'   | 'CS32873F918'(!)        = ''              | ''                 | 'CS32873F918'           | 'R0603'             | '(SMR0603AW)'                  | '28.7K'   | '1%'    | '1/10W'  | 'DISCRETE' | 'RESISTOR CHIP 28.7K 1/10W+-1%(0603)'              | 'CHIPR0603'    | ''          | ''            | '20190830'
 '28.7K'      | '1%'      | '1/10W'  | '0603LF'  | 'EMPTY'  | 'CS32873F918'(!)        = ''              | ''                 | 'CS32873F918'           | 'R0603'             | '(SMR0603AW)'                  | '28.7K'   | '1%'    | '1/10W'  | 'IO'       | 'RESISTOR CHIP 28.7K 1/10W+-1%(0603)'              | 'CHIPR0603'    | ''          | ''            | '20190830'
 '20'         | '5%'      | '1/16W'  | '0402LF'  | 'CHIP'   | 'CS02002JB02'(!)        = ''              | ''                 | 'CS02002JB02'           | 'R0402'             | '(R0402-0201)'                 | '20'      | '5%'    | '1/16W'  | 'DISCRETE' | 'RES CHIP 20 1/16W +-5%(0402)EF'                   | 'CHIPR0402'    | ''          | ''            | '20190904'
 '20'         | '5%'      | '1/16W'  | '0402LF'  | 'EMPTY'  | 'CS02002JB02'(!)        = ''              | ''                 | 'CS02002JB02'           | 'R0402'             | '(R0402-0201)'                 | '20'      | '5%'    | '1/16W'  | 'IO'       | 'RES CHIP 20 1/16W +-5%(0402)EF'                   | 'CHIPR0402'    | ''          | ''            | '20190904'
 '30.1'       | '1%'      | '1/10W'  | '0603LF'  | 'CHIP'   | 'CS03013F902'(!)        = 'End of Design' | 'Comp-Release Qty' | 'CS03013F902'           | 'R0603_H24'         | '(SMR0603AW)'                  | '30.1'    | '1%'    | '1/10W'  | 'DISCRETE' | 'RES CHIP 30.1 1/10W +-1%(0603)EF'                 | 'CHIPR0603'    | ''          | ''            | '20190904'
 '30.1'       | '1%'      | '1/10W'  | '0603LF'  | 'EMPTY'  | 'CS03013F902'(!)        = 'End of Design' | 'Comp-Release Qty' | 'CS03013F902'           | 'R0603_H24'         | '(SMR0603AW)'                  | '30.1'    | '1%'    | '1/10W'  | 'IO'       | 'RES CHIP 30.1 1/10W +-1%(0603)EF'                 | 'CHIPR0603'    | ''          | ''            | '20190904'
 '33'         | '5%'      | '1/16W'  | '0402LF'  | 'CHIP'   | 'CS03302JB10'(!)        = 'End of Design' | 'Comp-Approve'     | 'CS03302JB10'           | 'R0402'             | '(R0402-0201)'                 | '33'      | '5%'    | '1/16W'  | 'DISCRETE' | 'RES CHIP 33 1/16W +-5%(0402)EF'                   | 'CHIPR0402'    | ''          | ''            | '20190904'
 '33'         | '5%'      | '1/16W'  | '0402LF'  | 'EMPTY'  | 'CS03302JB10'(!)        = 'End of Design' | 'Comp-Approve'     | 'CS03302JB10'           | 'R0402'             | '(R0402-0201)'                 | '33'      | '5%'    | '1/16W'  | 'IO'       | 'RES CHIP 33 1/16W +-5%(0402)EF'                   | 'CHIPR0402'    | ''          | ''            | '20190904'
 '1'          | '1%'      | '1/10W'  | '0603LF'  | 'CHIP'   | 'CS-1003F900'(!)        = 'End of Design' | 'Comp-Approve'     | 'CS-1003F900'           | 'R0603_H24'         | '(SMR0603AW)'                  | '1'       | '1%'    | '1/10W'  | 'DISCRETE' | 'RES CHIP 1 1/10W +-1%(0603)EF'                    | 'CHIPR0603'    | ''          | ''            | '20190904'
 '1'          | '1%'      | '1/10W'  | '0603LF'  | 'EMPTY'  | 'CS-1003F900'(!)        = 'End of Design' | 'Comp-Approve'     | 'CS-1003F900'           | 'R0603_H24'         | '(SMR0603AW)'                  | '1'       | '1%'    | '1/10W'  | 'IO'       | 'RES CHIP 1 1/10W +-1%(0603)EF'                    | 'CHIPR0603'    | ''          | ''            | '20190904'
 '165'        | '1%'      | '1/16W'  | '0402LF'  | 'CHIP'   | 'CS11652FB03'(!)        = 'End of Design' | 'Comp-Approve'     | 'CS11652FB03'           | 'R0402'             | '(R0402-0201)'                 | '165'     | '1%'    | '1/16W'  | 'DISCRETE' | 'RES CHIP 165 1/16W +-1%(0402)EF'                  | 'CHIPR0402'    | ''          | ''            | '20190904'
 '165'        | '1%'      | '1/16W'  | '0402LF'  | 'EMPTY'  | 'CS11652FB03'(!)        = 'End of Design' | 'Comp-Approve'     | 'CS11652FB03'           | 'R0402'             | '(R0402-0201)'                 | '165'     | '1%'    | '1/16W'  | 'IO'       | 'RES CHIP 165 1/16W +-1%(0402)EF'                  | 'CHIPR0402'    | ''          | ''            | '20190904'
 '249'        | '1%'      | '1/16W'  | '0402LF'  | 'CHIP'   | 'CS12492FB02'(!)        = 'End of Design' | 'Comp-Approve'     | 'CS12492FB02'           | 'R0402'             | '(R0402-0201)'                 | '249'     | '1%'    | '1/16W'  | 'DISCRETE' | 'RES CHIP 249 1/16W +-1%(0402)EF'                  | 'CHIPR0402'    | ''          | ''            | '20190904'
 '249'        | '1%'      | '1/16W'  | '0402LF'  | 'EMPTY'  | 'CS12492FB02'(!)        = 'End of Design' | 'Comp-Approve'     | 'CS12492FB02'           | 'R0402'             | '(R0402-0201)'                 | '249'     | '1%'    | '1/16W'  | 'IO'       | 'RES CHIP 249 1/16W +-1%(0402)EF'                  | 'CHIPR0402'    | ''          | ''            | '20190904'
 '249'        | '0.1%'    | '1/10W'  | '0603LF'  | 'CHIP'   | 'CS12493B901'(!)        = ''              | ''                 | 'CS12493B901'           | 'R0603_H24'         | '(SMR0603AW)'                  | '249'     | '0.1%'  | '1/10W'  | 'DISCRETE' | 'RES CHIP 249 1/10W +-0.1%(0603)EF'                | 'CHIPR0603'    | ''          | ''            | '20190905'
 '249'        | '0.1%'    | '1/10W'  | '0603LF'  | 'EMPTY'  | 'CS12493B901'(!)        = ''              | ''                 | 'CS12493B901'           | 'R0603_H24'         | '(SMR0603AW)'                  | '249'     | '0.1%'  | '1/10W'  | 'IO'       | 'RES CHIP 249 1/10W +-0.1%(0603)EF'                | 'CHIPR0603'    | ''          | ''            | '20190905'
 '301'        | '1%'      | '1/16W'  | '0402LF'  | 'CHIP'   | 'CS13012FB02'(!)        = 'End of Design' | 'Comp-Approve'     | 'CS13012FB02'           | 'R0402'             | '(R0402-0201)'                 | '301'     | '1%'    | '1/16W'  | 'DISCRETE' | 'RES CHIP 301 1/16W +-1%(0402)EF'                  | 'CHIPR0402'    | ''          | ''            | '20190904'
 '301'        | '1%'      | '1/16W'  | '0402LF'  | 'EMPTY'  | 'CS13012FB02'(!)        = 'End of Design' | 'Comp-Approve'     | 'CS13012FB02'           | 'R0402'             | '(R0402-0201)'                 | '301'     | '1%'    | '1/16W'  | 'IO'       | 'RES CHIP 301 1/16W +-1%(0402)EF'                  | 'CHIPR0402'    | ''          | ''            | '20190904'
 '383'        | '1%'      | '1/16W'  | '0402LF'  | 'CHIP'   | 'CS13832FB03'(!)        = 'End of Design' | 'Comp-Approve'     | 'CS13832FB03'           | 'R0402'             | '(R0402-0201)'                 | '383'     | '1%'    | '1/16W'  | 'DISCRETE' | 'RES CHIP 383 1/16W +-1%(0402)EF'                  | 'CHIPR0402'    | ''          | ''            | '20190904'
 '383'        | '1%'      | '1/16W'  | '0402LF'  | 'EMPTY'  | 'CS13832FB03'(!)        = 'End of Design' | 'Comp-Approve'     | 'CS13832FB03'           | 'R0402'             | '(R0402-0201)'                 | '383'     | '1%'    | '1/16W'  | 'IO'       | 'RES CHIP 383 1/16W +-1%(0402)EF'                  | 'CHIPR0402'    | ''          | ''            | '20190904'
 '510'        | '5%'      | '1/16W'  | '0402LF'  | 'CHIP'   | 'CS15102JB04'(!)        = ''              | ''                 | 'CS15102JB04'           | 'R0402'             | '(R0402-0201)'                 | '510'     | '5%'    | '1/16W'  | 'DISCRETE' | 'RES CHIP 510 1/16W +-5%(0402)EF'                  | 'CHIPR0402'    | ''          | ''            | '20190904'
 '510'        | '5%'      | '1/16W'  | '0402LF'  | 'EMPTY'  | 'CS15102JB04'(!)        = ''              | ''                 | 'CS15102JB04'           | 'R0402'             | '(R0402-0201)'                 | '510'     | '5%'    | '1/16W'  | 'IO'       | 'RES CHIP 510 1/16W +-5%(0402)EF'                  | 'CHIPR0402'    | ''          | ''            | '20190904'
 '523'        | '1%'      | '1/16W'  | '0402LF'  | 'CHIP'   | 'CS15232FB03'(!)        = ''              | ''                 | 'CS15232FB03'           | 'R0402'             | '(R0402-0201)'                 | '523'     | '1%'    | '1/16W'  | 'DISCRETE' | 'RES CHIP 523 1/16W +-1%(0402)EF'                  | 'CHIPR0402'    | ''          | ''            | '20190904'
 '523'        | '1%'      | '1/16W'  | '0402LF'  | 'EMPTY'  | 'CS15232FB03'(!)        = ''              | ''                 | 'CS15232FB03'           | 'R0402'             | '(R0402-0201)'                 | '523'     | '1%'    | '1/16W'  | 'IO'       | 'RES CHIP 523 1/16W +-1%(0402)EF'                  | 'CHIPR0402'    | ''          | ''            | '20190904'
 '560'        | '1%'      | '1/16W'  | '0402LF'  | 'CHIP'   | 'CS15602FB03'(!)        = ''              | ''                 | 'CS15602FB03'           | 'R0402'             | '(R0402-0201)'                 | '560'     | '1%'    | '1/16W'  | 'DISCRETE' | 'RES CHIP 560 1/16W +-1%(0402)EF'                  | 'CHIPR0402'    | ''          | ''            | '20190904'
 '560'        | '1%'      | '1/16W'  | '0402LF'  | 'EMPTY'  | 'CS15602FB03'(!)        = ''              | ''                 | 'CS15602FB03'           | 'R0402'             | '(R0402-0201)'                 | '560'     | '1%'    | '1/16W'  | 'IO'       | 'RES CHIP 560 1/16W +-1%(0402)EF'                  | 'CHIPR0402'    | ''          | ''            | '20190904'
 '562'        | '1%'      | '1/16W'  | '0402LF'  | 'CHIP'   | 'CS15622FB01'(!)        = 'End of Design' | 'Comp-Approve'     | 'CS15622FB01'           | 'R0402'             | '(R0402-0201)'                 | '562'     | '1%'    | '1/16W'  | 'DISCRETE' | 'RES CHIP 562 1/16W +-1% (0402)EF'                 | 'CHIPR0402'    | ''          | ''            | '20190904'
 '562'        | '1%'      | '1/16W'  | '0402LF'  | 'EMPTY'  | 'CS15622FB01'(!)        = 'End of Design' | 'Comp-Approve'     | 'CS15622FB01'           | 'R0402'             | '(R0402-0201)'                 | '562'     | '1%'    | '1/16W'  | 'IO'       | 'RES CHIP 562 1/16W +-1% (0402)EF'                 | 'CHIPR0402'    | ''          | ''            | '20190904'
 '750'        | '1%'      | '1/20W'  | '0201LF'  | 'CHIP'   | 'CS17501FE11'(!)        = ''              | ''                 | 'CS17501FE11'           | 'R0201'             | '(SMR0201AW)'                  | '750'     | '1%'    | '1/20W'  | 'DISCRETE' | 'RES CHIP 750 1/20W +-1%(0201)EF'                  | 'CHIPR0201'    | ''          | ''            | '20190904'
 '750'        | '1%'      | '1/20W'  | '0201LF'  | 'EMPTY'  | 'CS17501FE11'(!)        = ''              | ''                 | 'CS17501FE11'           | 'R0201'             | '(SMR0201AW)'                  | '750'     | '1%'    | '1/20W'  | 'IO'       | 'RES CHIP 750 1/20W +-1%(0201)EF'                  | 'CHIPR0201'    | ''          | ''            | '20190904'
 '887'        | '1%'      | '1/16W'  | '0402LF'  | 'CHIP'   | 'CS18872FB02'(!)        = 'End of Design' | 'Comp-Approve'     | 'CS18872FB02'           | 'R0402'             | '(R0402-0201)'                 | '887'     | '1%'    | '1/16W'  | 'DISCRETE' | 'RES CHIP 887 1/16W +-1%(0402)EF'                  | 'CHIPR0402'    | ''          | ''            | '20190905'
 '887'        | '1%'      | '1/16W'  | '0402LF'  | 'EMPTY'  | 'CS18872FB02'(!)        = 'End of Design' | 'Comp-Approve'     | 'CS18872FB02'           | 'R0402'             | '(R0402-0201)'                 | '887'     | '1%'    | '1/16W'  | 'IO'       | 'RES CHIP 887 1/16W +-1%(0402)EF'                  | 'CHIPR0402'    | ''          | ''            | '20190905'
 '1.18K'      | '1%'      | '1/16W'  | '0402LF'  | 'CHIP'   | 'CS21182FB01'(!)        = 'End of Design' | 'Comp-Approve'     | 'CS21182FB01'           | 'R0402'             | '(R0402-0201)'                 | '1.18K'   | '1%'    | '1/16W'  | 'DISCRETE' | 'RES CHIP 1.18K 1/16W +-1%(0402)EF'                | 'CHIPR0402'    | ''          | ''            | '20190905'
 '1.18K'      | '1%'      | '1/16W'  | '0402LF'  | 'EMPTY'  | 'CS21182FB01'(!)        = 'End of Design' | 'Comp-Approve'     | 'CS21182FB01'           | 'R0402'             | '(R0402-0201)'                 | '1.18K'   | '1%'    | '1/16W'  | 'IO'       | 'RES CHIP 1.18K 1/16W +-1%(0402)EF'                | 'CHIPR0402'    | ''          | ''            | '20190905'
 '1.2K'       | '1%'      | '1/16W'  | '0402LF'  | 'CHIP'   | 'CS21202FB00'(!)        = 'End of Design' | 'Comp-Approve'     | 'CS21202FB00'           | 'R0402'             | '(R0402-0201)'                 | '1.2K'    | '1%'    | '1/16W'  | 'DISCRETE' | 'RES CHIP 1.2K 1/16W+-1%(0402)EF'                  | 'CHIPR0402'    | ''          | ''            | '20190905'
 '1.2K'       | '1%'      | '1/16W'  | '0402LF'  | 'EMPTY'  | 'CS21202FB00'(!)        = 'End of Design' | 'Comp-Approve'     | 'CS21202FB00'           | 'R0402'             | '(R0402-0201)'                 | '1.2K'    | '1%'    | '1/16W'  | 'IO'       | 'RES CHIP 1.2K 1/16W+-1%(0402)EF'                  | 'CHIPR0402'    | ''          | ''            | '20190905'
 '2.67K'      | '1%'      | '1/16W'  | '0402LF'  | 'CHIP'   | 'CS22672FB03'(!)        = 'End of Design' | 'Comp-Approve'     | 'CS22672FB03'           | 'R0402'             | '(R0402-0201)'                 | '2.67K'   | '1%'    | '1/16W'  | 'DISCRETE' | 'RES CHIP 2.67K 1/16W +-1%(0402)EF'                | 'CHIPR0402'    | ''          | ''            | '20190905'
 '2.67K'      | '1%'      | '1/16W'  | '0402LF'  | 'EMPTY'  | 'CS22672FB03'(!)        = 'End of Design' | 'Comp-Approve'     | 'CS22672FB03'           | 'R0402'             | '(R0402-0201)'                 | '2.67K'   | '1%'    | '1/16W'  | 'IO'       | 'RES CHIP 2.67K 1/16W +-1%(0402)EF'                | 'CHIPR0402'    | ''          | ''            | '20190905'
 '4.22K'      | '1%'      | '1/16W'  | '0402LF'  | 'CHIP'   | 'CS24222FB01'(!)        = 'End of Design' | 'Comp-Approve'     | 'CS24222FB01'           | 'R0402'             | '(R0402-0201)'                 | '4.22K'   | '1%'    | '1/16W'  | 'DISCRETE' | 'RES CHIP 4.22K 1/16W +-1%(0402)EF'                | 'CHIPR0402'    | ''          | ''            | '20190906'
 '4.22K'      | '1%'      | '1/16W'  | '0402LF'  | 'EMPTY'  | 'CS24222FB01'(!)        = 'End of Design' | 'Comp-Approve'     | 'CS24222FB01'           | 'R0402'             | '(R0402-0201)'                 | '4.22K'   | '1%'    | '1/16W'  | 'IO'       | 'RES CHIP 4.22K 1/16W +-1%(0402)EF'                | 'CHIPR0402'    | ''          | ''            | '20190906'
 '5.36K'      | '1%'      | '1/16W'  | '0402LF'  | 'CHIP'   | 'CS25362FB02'(!)        = 'End of Design' | 'Comp-Approve'     | 'CS25362FB02'           | 'R0402'             | '(R0402-0201)'                 | '5.36K'   | '1%'    | '1/16W'  | 'DISCRETE' | 'RES CHIP 5.36K 1/16W +-1%(0402)EF'                | 'CHIPR0402'    | ''          | ''            | '20190906'
 '5.36K'      | '1%'      | '1/16W'  | '0402LF'  | 'EMPTY'  | 'CS25362FB02'(!)        = 'End of Design' | 'Comp-Approve'     | 'CS25362FB02'           | 'R0402'             | '(R0402-0201)'                 | '5.36K'   | '1%'    | '1/16W'  | 'IO'       | 'RES CHIP 5.36K 1/16W +-1%(0402)EF'                | 'CHIPR0402'    | ''          | ''            | '20190906'
 '6.98K'      | '1%'      | '1/16W'  | '0402LF'  | 'CHIP'   | 'CS26982FB08'(!)        = ''              | ''                 | 'CS26982FB08'           | 'R0402'             | '(R0402-0201)'                 | '6.98K'   | '1%'    | '1/16W'  | 'DISCRETE' | 'RES CHIP 6.98K 1/16W +-1%(0402)EF'                | 'CHIPR0402'    | ''          | ''            | '20190906'
 '6.98K'      | '1%'      | '1/16W'  | '0402LF'  | 'EMPTY'  | 'CS26982FB08'(!)        = ''              | ''                 | 'CS26982FB08'           | 'R0402'             | '(R0402-0201)'                 | '6.98K'   | '1%'    | '1/16W'  | 'IO'       | 'RES CHIP 6.98K 1/16W +-1%(0402)EF'                | 'CHIPR0402'    | ''          | ''            | '20190906'
 '10.7K'      | '1%'      | '1/16W'  | '0402LF'  | 'CHIP'   | 'CS31072FB05'(!)        = 'End of Design' | 'Comp-Approve'     | 'CS31072FB05'           | 'R0402'             | '(R0402-0201)'                 | '10.7K'   | '1%'    | '1/16W'  | 'DISCRETE' | 'RES CHIP 10.7K 1/16W +-1%(0402)EF'                | 'CHIPR0402'    | ''          | ''            | '20190906'
 '10.7K'      | '1%'      | '1/16W'  | '0402LF'  | 'EMPTY'  | 'CS31072FB05'(!)        = 'End of Design' | 'Comp-Approve'     | 'CS31072FB05'           | 'R0402'             | '(R0402-0201)'                 | '10.7K'   | '1%'    | '1/16W'  | 'IO'       | 'RES CHIP 10.7K 1/16W +-1%(0402)EF'                | 'CHIPR0402'    | ''          | ''            | '20190906'
 '26.7K'      | '1%'      | '1/16W'  | '0402LF'  | 'CHIP'   | 'CS32672FB03'(!)        = 'End of Design' | 'Comp-Approve'     | 'CS32672FB03'           | 'R0402'             | '(R0402-0201)'                 | '26.7K'   | '1%'    | '1/16W'  | 'DISCRETE' | 'RES CHIP 26.7K 1/16W +-1%(0402)EF'                | 'CHIPR0402'    | ''          | ''            | '20190906'
 '26.7K'      | '1%'      | '1/16W'  | '0402LF'  | 'EMPTY'  | 'CS32672FB03'(!)        = 'End of Design' | 'Comp-Approve'     | 'CS32672FB03'           | 'R0402'             | '(R0402-0201)'                 | '26.7K'   | '1%'    | '1/16W'  | 'IO'       | 'RES CHIP 26.7K 1/16W +-1%(0402)EF'                | 'CHIPR0402'    | ''          | ''            | '20190906'
 '27K'        | '1%'      | '1/16W'  | '0402LF'  | 'CHIP'   | 'CS32702FB03'(!)        = 'End of Design' | 'Comp-Approve'     | 'CS32702FB03'           | 'R0402'             | '(R0402-0201)'                 | '27K'     | '1%'    | '1/16W'  | 'DISCRETE' | 'RES CHIP 27K 1/16W +-1%(0402)EF'                  | 'CHIPR0402'    | ''          | ''            | '20190906'
 '27K'        | '1%'      | '1/16W'  | '0402LF'  | 'EMPTY'  | 'CS32702FB03'(!)        = 'End of Design' | 'Comp-Approve'     | 'CS32702FB03'           | 'R0402'             | '(R0402-0201)'                 | '27K'     | '1%'    | '1/16W'  | 'IO'       | 'RES CHIP 27K 1/16W +-1%(0402)EF'                  | 'CHIPR0402'    | ''          | ''            | '20190906'
 '57.6K'      | '1%'      | '1/16W'  | '0402LF'  | 'CHIP'   | 'CS35762FB02'(!)        = ''              | ''                 | 'CS35762FB02'           | 'R0402'             | '(R0402-0201)'                 | '57.6K'   | '1%'    | '1/16W'  | 'DISCRETE' | 'RES CHIP 57.6K 1/16W +-1%(0402)EF'                | 'CHIPR0402'    | ''          | ''            | '20190906'
 '57.6K'      | '1%'      | '1/16W'  | '0402LF'  | 'EMPTY'  | 'CS35762FB02'(!)        = ''              | ''                 | 'CS35762FB02'           | 'R0402'             | '(R0402-0201)'                 | '57.6K'   | '1%'    | '1/16W'  | 'IO'       | 'RES CHIP 57.6K 1/16W +-1%(0402)EF'                | 'CHIPR0402'    | ''          | ''            | '20190906'
 '68K'        | '1%'      | '1/16W'  | '0402LF'  | 'CHIP'   | 'CS36802FB04'(!)        = 'End of Design' | 'Comp-Approve'     | 'CS36802FB04'           | 'R0402'             | '(R0402-0201)'                 | '68K'     | '1%'    | '1/16W'  | 'DISCRETE' | 'RES CHIP 68K 1/16W +-1%(0402)EF'                  | 'CHIPR0402'    | ''          | ''            | '20190906'
 '68K'        | '1%'      | '1/16W'  | '0402LF'  | 'EMPTY'  | 'CS36802FB04'(!)        = 'End of Design' | 'Comp-Approve'     | 'CS36802FB04'           | 'R0402'             | '(R0402-0201)'                 | '68K'     | '1%'    | '1/16W'  | 'IO'       | 'RES CHIP 68K 1/16W +-1%(0402)EF'                  | 'CHIPR0402'    | ''          | ''            | '20190906'
 '4.02'       | '1%'      | '1/16W'  | '0402LF'  | 'CHIP'   | 'CS-4022FB01'(!)        = 'End of Design' | 'Comp-Approve'     | 'CS-4022FB01'           | 'R0402'             | '(R0402-0201)'                 | '4.02'    | '1%'    | '1/16W'  | 'DISCRETE' | 'RES CHIP 4.02 1/16W +-1%(0402)EF'                 | 'CHIPR0402'    | ''          | ''            | '20190906'
 '4.02'       | '1%'      | '1/16W'  | '0402LF'  | 'EMPTY'  | 'CS-4022FB01'(!)        = 'End of Design' | 'Comp-Approve'     | 'CS-4022FB01'           | 'R0402'             | '(R0402-0201)'                 | '4.02'    | '1%'    | '1/16W'  | 'IO'       | 'RES CHIP 4.02 1/16W +-1%(0402)EF'                 | 'CHIPR0402'    | ''          | ''            | '20190906'
 '143K'       | '1%'      | '1/16W'  | '0402LF'  | 'CHIP'   | 'CS41432FB04'(!)        = ''              | ''                 | 'CS41432FB04'           | 'R0402'             | '(R0402-0201)'                 | '143K'    | '1%'    | '1/16W'  | 'DISCRETE' | 'RES CHIP 143K 1/16W +-1%(0402)EF'                 | 'CHIPR0402'    | ''          | ''            | '20190906'
 '143K'       | '1%'      | '1/16W'  | '0402LF'  | 'EMPTY'  | 'CS41432FB04'(!)        = ''              | ''                 | 'CS41432FB04'           | 'R0402'             | '(R0402-0201)'                 | '143K'    | '1%'    | '1/16W'  | 'IO'       | 'RES CHIP 143K 1/16W +-1%(0402)EF'                 | 'CHIPR0402'    | ''          | ''            | '20190906'
 '165K'       | '1%'      | '1/16W'  | '0402LF'  | 'CHIP'   | 'CS41652FB03'(!)        = 'End of Design' | 'Comp-Approve'     | 'CS41652FB03'           | 'R0402'             | '(R0402-0201)'                 | '165K'    | '1%'    | '1/16W'  | 'DISCRETE' | 'RES CHIP 165K 1/16W +-1%(0402)EF'                 | 'CHIPR0402'    | ''          | ''            | '20190906'
 '165K'       | '1%'      | '1/16W'  | '0402LF'  | 'EMPTY'  | 'CS41652FB03'(!)        = 'End of Design' | 'Comp-Approve'     | 'CS41652FB03'           | 'R0402'             | '(R0402-0201)'                 | '165K'    | '1%'    | '1/16W'  | 'IO'       | 'RES CHIP 165K 1/16W +-1%(0402)EF'                 | 'CHIPR0402'    | ''          | ''            | '20190906'
 '255K'       | '1%'      | '1/16W'  | '0402LF'  | 'CHIP'   | 'CS42552FB02'(!)        = 'End of Design' | 'Comp-Approve'     | 'CS42552FB02'           | 'R0402'             | '(R0402-0201)'                 | '255K'    | '1%'    | '1/16W'  | 'DISCRETE' | 'RES CHIP 255K 1/16W +-1%(0402)EF'                 | 'CHIPR0402'    | ''          | ''            | '20190906'
 '255K'       | '1%'      | '1/16W'  | '0402LF'  | 'EMPTY'  | 'CS42552FB02'(!)        = 'End of Design' | 'Comp-Approve'     | 'CS42552FB02'           | 'R0402'             | '(R0402-0201)'                 | '255K'    | '1%'    | '1/16W'  | 'IO'       | 'RES CHIP 255K 1/16W +-1%(0402)EF'                 | 'CHIPR0402'    | ''          | ''            | '20190906'
 '470K'       | '1%'      | '1/16W'  | '0402LF'  | 'CHIP'   | 'CS44702FB02'(!)        = 'End of Design' | 'Comp-Approve'     | 'CS44702FB02'           | 'R0402'             | '(R0402-0201)'                 | '470K'    | '1%'    | '1/16W'  | 'DISCRETE' | 'RES CHIP 470K 1/16W +-1%(0402)EF'                 | 'CHIPR0402'    | ''          | ''            | '20190906'
 '470K'       | '1%'      | '1/16W'  | '0402LF'  | 'EMPTY'  | 'CS44702FB02'(!)        = 'End of Design' | 'Comp-Approve'     | 'CS44702FB02'           | 'R0402'             | '(R0402-0201)'                 | '470K'    | '1%'    | '1/16W'  | 'IO'       | 'RES CHIP 470K 1/16W +-1%(0402)EF'                 | 'CHIPR0402'    | ''          | ''            | '20190906'
 '866K'       | '1%'      | '1/16W'  | '0402LF'  | 'CHIP'   | 'CS48662FB02'(!)        = ''              | ''                 | 'CS48662FB02'           | 'R0402'             | '(R0402-0201)'                 | '866K'    | '1%'    | '1/16W'  | 'DISCRETE' | 'RES CHIP 866K 1/16W +-1%(0402)EF'                 | 'CHIPR0402'    | ''          | ''            | '20190906'
 '866K'       | '1%'      | '1/16W'  | '0402LF'  | 'EMPTY'  | 'CS48662FB02'(!)        = ''              | ''                 | 'CS48662FB02'           | 'R0402'             | '(R0402-0201)'                 | '866K'    | '1%'    | '1/16W'  | 'IO'       | 'RES CHIP 866K 1/16W +-1%(0402)EF'                 | 'CHIPR0402'    | ''          | ''            | '20190906'
 '5.11'       | '1%'      | '1/16W'  | '0402LF'  | 'CHIP'   | 'CS-5112FB02'(!)        = 'End of Design' | 'Comp-Approve'     | 'CS-5112FB02'           | 'R0402'             | '(R0402-0201)'                 | '5.11'    | '1%'    | '1/16W'  | 'DISCRETE' | 'RES CHIP 5.11 1/16W +-1%(0402)EF'                 | 'CHIPR0402'    | ''          | ''            | '20190906'
 '5.11'       | '1%'      | '1/16W'  | '0402LF'  | 'EMPTY'  | 'CS-5112FB02'(!)        = 'End of Design' | 'Comp-Approve'     | 'CS-5112FB02'           | 'R0402'             | '(R0402-0201)'                 | '5.11'    | '1%'    | '1/16W'  | 'IO'       | 'RES CHIP 5.11 1/16W +-1%(0402)EF'                 | 'CHIPR0402'    | ''          | ''            | '20190906'
 '10M'        | '1%'      | '1/16W'  | '0402LF'  | 'CHIP'   | 'CS61002FB02'(!)        = ''              | ''                 | 'CS61002FB02'           | 'R0402'             | '(R0402-0201)'                 | '10M'     | '1%'    | '1/16W'  | 'DISCRETE' | 'RES CHIP 10M 1/16W +-1%(0402)EF'                  | 'CHIPR0402'    | ''          | ''            | '20190906'
 '10M'        | '1%'      | '1/16W'  | '0402LF'  | 'EMPTY'  | 'CS61002FB02'(!)        = ''              | ''                 | 'CS61002FB02'           | 'R0402'             | '(R0402-0201)'                 | '10M'     | '1%'    | '1/16W'  | 'IO'       | 'RES CHIP 10M 1/16W +-1%(0402)EF'                  | 'CHIPR0402'    | ''          | ''            | '20190906'
 '2.8M'       | '1%'      | '1/8W'   | '0805LF'  | 'CHIP'   | 'CS52804FA00'(!)        = ''              | ''                 | 'CS52804FA00'           | 'R0805'             | '(SMR0805AW)'                  | '2.8M'    | '1%'    | '1/8W'   | 'DISCRETE' | 'RES CHIP 2.8M 1/8W +-1%(0805)'                    | 'CHIPR0805'    | ''          | ''            | '20191001'
 '2.8M'       | '1%'      | '1/8W'   | '0805LF'  | 'EMPTY'  | 'CS52804FA00'(!)        = ''              | ''                 | 'CS52804FA00'           | 'R0805'             | '(SMR0805AW)'                  | '2.8M'    | '1%'    | '1/8W'   | 'IO'       | 'RES CHIP 2.8M 1/8W +-1%(0805)'                    | 'CHIPR0805'    | ''          | ''            | '20191001'
 '12K'        | '1%'      | '1/10W'  | '0603LF'  | 'CHIP'   | 'CS31203F911'(!)        = ''              | ''                 | 'CS31203F911'           | 'R0603'             | '(SMR0603AW)'                  | '12K'     | '1%'    | '1/10W'  | 'DISCRETE' | 'RESISTOR CHIP 12K 1/10W+-1%(0603)'                | 'CHIPR0603'    | ''          | ''            | '20190925'
 '12K'        | '1%'      | '1/10W'  | '0603LF'  | 'EMPTY'  | 'CS31203F911'(!)        = ''              | ''                 | 'CS31203F911'           | 'R0603'             | '(SMR0603AW)'                  | '12K'     | '1%'    | '1/10W'  | 'IO'       | 'RESISTOR CHIP 12K 1/10W+-1%(0603)'                | 'CHIPR0603'    | ''          | ''            | '20190925'
 '26.1K'      | '0.1%'    | '1/10W'  | '0603LF'  | 'CHIP'   | 'CS32613B900'(!)        = 'End of Design' | 'Comp-Approve'     | 'CS32613B900'           | 'R0603'             | '(SMR0603AW)'                  | '26.1K'   | '0.1%'  | '1/10W'  | 'DISCRETE' | 'RES CHIP 26.1K 1/10W +-0.1%(0603)'                | 'CHIPR0603'    | ''          | ''            | '20190927'
 '26.1K'      | '0.1%'    | '1/10W'  | '0603LF'  | 'EMPTY'  | 'CS32613B900'(!)        = 'End of Design' | 'Comp-Approve'     | 'CS32613B900'           | 'R0603'             | '(SMR0603AW)'                  | '26.1K'   | '0.1%'  | '1/10W'  | 'IO'       | 'RES CHIP 26.1K 1/10W +-0.1%(0603)'                | 'CHIPR0603'    | ''          | ''            | '20190927'
 '10.2K'      | '0.1%'    | '1/16W'  | '0402LF'  | 'CHIP'   | 'CS31022BB01'(!)        = ''              | ''                 | 'CS31022BB01'           | 'R0402'             | '(R0402-0201)'                 | '10.2K'   | '0.1%'  | '1/16W'  | 'DISCRETE' | 'RES CHIP 10.2K 1/16W +-0.1%(0402)'                | 'CHIPR0402'    | ''          | ''            | '20190927'
 '10.2K'      | '0.1%'    | '1/16W'  | '0402LF'  | 'EMPTY'  | 'CS31022BB01'(!)        = ''              | ''                 | 'CS31022BB01'           | 'R0402'             | '(R0402-0201)'                 | '10.2K'   | '0.1%'  | '1/16W'  | 'IO'       | 'RES CHIP 10.2K 1/16W +-0.1%(0402)'                | 'CHIPR0402'    | ''          | ''            | '20190927'
 '10K'        | '1%'      | '1/20W'  | '0201LF'  | 'CHIP'   | 'CS31001FE17'(!)        = ''              | ''                 | 'CS31001FE17'           | 'R0201'             | '(SMR0201AW)'                  | '10K'     | '1%'    | '1/20W'  | 'DISCRETE' | 'RES CHIP 10K 1/20W +-1%(0201)EF'                  | 'CHIPR0201'    | ''          | ''            | '20191004'
 '10K'        | '1%'      | '1/20W'  | '0201LF'  | 'EMPTY'  | 'CS31001FE17'(!)        = ''              | ''                 | 'CS31001FE17'           | 'R0201'             | '(SMR0201AW)'                  | '10K'     | '1%'    | '1/20W'  | 'IO'       | 'RES CHIP 10K 1/20W +-1%(0201)EF'                  | 'CHIPR0201'    | ''          | ''            | '20191004'
 '32.4'       | '1%'      | '1/16W'  | '0402LF'  | 'CHIP'   | 'CS03242FB00'(!)        = ''              | ''                 | 'CS03242FB00'           | 'R0402'             | '(R0402-0201)'                 | '32.4'    | '1%'    | '1/16W'  | 'DISCRETE' | 'RES CHIP 32.4 1/16W +-1%(0402)'                   | 'CHIPR0402'    | ''          | ''            | '20191004'
 '32.4'       | '1%'      | '1/16W'  | '0402LF'  | 'EMPTY'  | 'CS03242FB00'(!)        = ''              | ''                 | 'CS03242FB00'           | 'R0402'             | '(R0402-0201)'                 | '32.4'    | '1%'    | '1/16W'  | 'IO'       | 'RES CHIP 32.4 1/16W +-1%(0402)'                   | 'CHIPR0402'    | ''          | ''            | '20191004'
 '1.74M'      | '1%'      | '1/8W'   | '0805LF'  | 'CHIP'   | 'CS51744FA00'(!)        = ''              | ''                 | 'CS51744FA00'           | 'R0805'             | '(SMR0805AW)'                  | '1.74M'   | '1%'    | '1/8W'   | 'DISCRETE' | 'RES CHIP 1.74M 1/8W +-1%(0805)'                   | 'CHIPR0805'    | ''          | ''            | '20191008'
 '1.74M'      | '1%'      | '1/8W'   | '0805LF'  | 'EMPTY'  | 'CS51744FA00'(!)        = ''              | ''                 | 'CS51744FA00'           | 'R0805'             | '(SMR0805AW)'                  | '1.74M'   | '1%'    | '1/8W'   | 'IO'       | 'RES CHIP 1.74M 1/8W +-1%(0805)'                   | 'CHIPR0805'    | ''          | ''            | '20191008'
 '4.7K'       | '5%'      | '1/20W'  | '0201LF'  | 'CHIP'   | 'CS24701JE04'(!)        = 'End of Design' | 'Comp-Approve'     | 'CS24701JE04'           | 'R0201'             | '(SMR0201AW)'                  | '4.7K'    | '5%'    | '1/20W'  | 'DISCRETE' | 'RES CHIP 4.7K 1/20W +-5%(0201)EF'                 | 'CHIPR0201'    | ''          | ''            | '20191008'
 '4.7K'       | '5%'      | '1/20W'  | '0201LF'  | 'EMPTY'  | 'CS24701JE04'(!)        = 'End of Design' | 'Comp-Approve'     | 'CS24701JE04'           | 'R0201'             | '(SMR0201AW)'                  | '4.7K'    | '5%'    | '1/20W'  | 'IO'       | 'RES CHIP 4.7K 1/20W +-5%(0201)EF'                 | 'CHIPR0201'    | ''          | ''            | '20191008'
 '3.6K'       | '1%'      | '1/20W'  | '0201LF'  | 'CHIP'   | 'CS23601FE00'(!)        = ''              | ''                 | 'CS23601FE00'           | 'R0201'             | '(SMR0201AW)'                  | '3.6K'    | '1%'    | '1/20W'  | 'DISCRETE' | 'RES CHIP 3.6K 1/20W +-1% (0201)'                  | 'CHIPR0201'    | ''          | ''            | '20191008'
 '3.6K'       | '1%'      | '1/20W'  | '0201LF'  | 'EMPTY'  | 'CS23601FE00'(!)        = ''              | ''                 | 'CS23601FE00'           | 'R0201'             | '(SMR0201AW)'                  | '3.6K'    | '1%'    | '1/20W'  | 'IO'       | 'RES CHIP 3.6K 1/20W +-1% (0201)'                  | 'CHIPR0201'    | ''          | ''            | '20191008'
 '348'        | '1%'      | '1/10W'  | '0603LF'  | 'CHIP'   | 'CS13483F917'(!)        = ''              | ''                 | 'CS13483F917'           | 'R0603_H24'         | '(SMR0603AW)'                  | '348'     | '1%'    | '1/10W'  | 'DISCRETE' | 'RES CHIP 348 1/10W +-1%(0603)'                    | 'CHIPR0603'    | ''          | ''            | '20191008'
 '348'        | '1%'      | '1/10W'  | '0603LF'  | 'EMPTY'  | 'CS13483F917'(!)        = ''              | ''                 | 'CS13483F917'           | 'R0603_H24'         | '(SMR0603AW)'                  | '348'     | '1%'    | '1/10W'  | 'IO'       | 'RES CHIP 348 1/10W +-1%(0603)'                    | 'CHIPR0603'    | ''          | ''            | '20191008'
 '10.2'       | '0.1%'    | '1/16W'  | '0402LF'  | 'CHIP'   | 'CS01022BB00'(!)        = ''              | ''                 | 'CS01022BB00'           | 'R0402'             | '(R0402-0201)'                 | '10.2'    | '0.1%'  | '1/16W'  | 'DISCRETE' | 'RES CHIP 10.2 1/16W +-0.1%(0402)'                 | 'CHIPR0402'    | ''          | ''            | '20191021'
 '10.2'       | '0.1%'    | '1/16W'  | '0402LF'  | 'EMPTY'  | 'CS01022BB00'(!)        = ''              | ''                 | 'CS01022BB00'           | 'R0402'             | '(R0402-0201)'                 | '10.2'    | '0.1%'  | '1/16W'  | 'IO'       | 'RES CHIP 10.2 1/16W +-0.1%(0402)'                 | 'CHIPR0402'    | ''          | ''            | '20191021'
 '6.8K'       | '1%'      | '1/20W'  | '0201LF'  | 'CHIP'   | 'CS26801FE00'(!)        = ''              | ''                 | 'CS26801FE00'           | 'R0201'             | '(SMR0201AW)'                  | '6.8K'    | '1%'    | '1/20W'  | 'DISCRETE' | 'RES CHIP 6.8K(1/20W,+-1%,0201)'                   | 'CHIPR0201'    | ''          | ''            | '20191022'
 '6.8K'       | '1%'      | '1/20W'  | '0201LF'  | 'EMPTY'  | 'CS26801FE00'(!)        = ''              | ''                 | 'CS26801FE00'           | 'R0201'             | '(SMR0201AW)'                  | '6.8K'    | '1%'    | '1/20W'  | 'IO'       | 'RES CHIP 6.8K(1/20W,+-1%,0201)'                   | 'CHIPR0201'    | ''          | ''            | '20191022'
 '4.7'        | '1%'      | '1/16W'  | '0402LF'  | 'CHIP'   | 'CS-4702FB19'(!)        = 'End of Design' | 'Comp-Approve'     | 'CS-4702FB19'           | 'R0402'             | '(R0402-0201)'                 | '4.7'     | '1%'    | '1/16W'  | 'DISCRETE' | 'RES CHIP 4.7 1/16W +-1%(0402)'                    | 'CHIPR0402'    | ''          | ''            | '20191025'
 '4.7'        | '1%'      | '1/16W'  | '0402LF'  | 'EMPTY'  | 'CS-4702FB19'(!)        = 'End of Design' | 'Comp-Approve'     | 'CS-4702FB19'           | 'R0402'             | '(R0402-0201)'                 | '4.7'     | '1%'    | '1/16W'  | 'IO'       | 'RES CHIP 4.7 1/16W +-1%(0402)'                    | 'CHIPR0402'    | ''          | ''            | '20191025'
 '10.2'       | '1%'      | '1/16W'  | '0402LF'  | 'CHIP'   | 'CS01022FB00'(!)        = ''              | ''                 | 'CS01022FB00'           | 'R0402'             | '(R0402-0201)'                 | '10.2'    | '1%'    | '1/16W'  | 'DISCRETE' | 'RES CHIP 10.2 1/16W +-1%(0402)HF'                 | 'CHIPR0402'    | ''          | ''            | '20191029'
 '10.2'       | '1%'      | '1/16W'  | '0402LF'  | 'EMPTY'  | 'CS01022FB00'(!)        = ''              | ''                 | 'CS01022FB00'           | 'R0402'             | '(R0402-0201)'                 | '10.2'    | '1%'    | '1/16W'  | 'IO'       | 'RES CHIP 10.2 1/16W +-1%(0402)HF'                 | 'CHIPR0402'    | ''          | ''            | '20191029'
 '0.03'       | '1%'      | '1/2W'   | '1206LF'  | 'CHIP'   | 'CS+0307F200'(!)        = ''              | ''                 | 'CS+0307F200'           | 'R1206'             | '(SMR1206AW)'                  | '0.03'    | '1%'    | '1/2W'   | 'DISCRETE' | 'RES CHIP 0.03 1/2W +-1%(1206)'                    | 'CHIPR1206'    | ''          | ''            | '20191030'
 '0.03'       | '1%'      | '1/2W'   | '1206LF'  | 'EMPTY'  | 'CS+0307F200'(!)        = ''              | ''                 | 'CS+0307F200'           | 'R1206'             | '(SMR1206AW)'                  | '0.03'    | '1%'    | '1/2W'   | 'IO'       | 'RES CHIP 0.03 1/2W +-1%(1206)'                    | 'CHIPR1206'    | ''          | ''            | '20191030'
 '332K'       | '1%'      | '1/16W'  | '0402LF'  | 'CHIP'   | 'CS43322FB03'(!)        = 'End of Design' | 'Comp-Approve'     | 'CS43322FB03'           | 'R0402'             | '(R0402-0201)'                 | '332K'    | '1%'    | '1/16W'  | 'DISCRETE' | 'RES CHIP 332K 1/16W +-1%(0402)EF'                 | 'CHIPR0402'    | ''          | ''            | '20191101'
 '332K'       | '1%'      | '1/16W'  | '0402LF'  | 'EMPTY'  | 'CS43322FB03'(!)        = 'End of Design' | 'Comp-Approve'     | 'CS43322FB03'           | 'R0402'             | '(R0402-0201)'                 | '332K'    | '1%'    | '1/16W'  | 'IO'       | 'RES CHIP 332K 1/16W +-1%(0402)EF'                 | 'CHIPR0402'    | ''          | ''            | '20191101'
 '40.2K'      | '1%'      | '1/16W'  | '0402LF'  | 'CHIP'   | 'CS34022FB04'(!)        = 'End of Design' | 'Comp-Approve'     | 'CS34022FB04'           | 'R0402'             | '(R0402-0201)'                 | '40.2K'   | '1%'    | '1/16W'  | 'DISCRETE' | 'RES CHIP 40.2K 1/16W +-1%(0402)EF'                | 'CHIPR0402'    | ''          | ''            | '20191101'
 '40.2K'      | '1%'      | '1/16W'  | '0402LF'  | 'EMPTY'  | 'CS34022FB04'(!)        = 'End of Design' | 'Comp-Approve'     | 'CS34022FB04'           | 'R0402'             | '(R0402-0201)'                 | '40.2K'   | '1%'    | '1/16W'  | 'IO'       | 'RES CHIP 40.2K 1/16W +-1%(0402)EF'                | 'CHIPR0402'    | ''          | ''            | '20191101'
 '118K'       | '1%'      | '1/16W'  | '0402LF'  | 'CHIP'   | 'CS41182FB05'(!)        = ''              | ''                 | 'CS41182FB05'           | 'R0402'             | '(R0402-0201)'                 | '118K'    | '1%'    | '1/16W'  | 'DISCRETE' | 'RES CHIP 118K 1/16W +-1%(0402)EF'                 | 'CHIPR0402'    | ''          | ''            | '20191101'
 '118K'       | '1%'      | '1/16W'  | '0402LF'  | 'EMPTY'  | 'CS41182FB05'(!)        = ''              | ''                 | 'CS41182FB05'           | 'R0402'             | '(R0402-0201)'                 | '118K'    | '1%'    | '1/16W'  | 'IO'       | 'RES CHIP 118K 1/16W +-1%(0402)EF'                 | 'CHIPR0402'    | ''          | ''            | '20191101'
 '160K'       | '1%'      | '1/16W'  | '0402LF'  | 'CHIP'   | 'CS41602FB05'(!)        = ''              | ''                 | 'CS41602FB05'           | 'R0402'             | '(R0402-0201)'                 | '160K'    | '1%'    | '1/16W'  | 'DISCRETE' | 'RES CHIP 160K 1/16W+-1%(0402)EF'                  | 'CHIPR0402'    | ''          | ''            | '20191113'
 '160K'       | '1%'      | '1/16W'  | '0402LF'  | 'EMPTY'  | 'CS41602FB05'(!)        = ''              | ''                 | 'CS41602FB05'           | 'R0402'             | '(R0402-0201)'                 | '160K'    | '1%'    | '1/16W'  | 'IO'       | 'RES CHIP 160K 1/16W+-1%(0402)EF'                  | 'CHIPR0402'    | ''          | ''            | '20191113'
 '33.2K'      | '1%'      | '1/20W'  | '0201LF'  | 'CHIP'   | 'CS33321FE00'(!)        = ''              | ''                 | 'CS33321FE00'           | 'R0201'             | '(SMR0201AW)'                  | '33.2K'   | '1%'    | '1/20W'  | 'DISCRETE' | 'RES CHIP 33.2K 1/20W +-1%(0201)'                  | 'CHIPR0201'    | ''          | ''            | '20191122'
 '33.2K'      | '1%'      | '1/20W'  | '0201LF'  | 'EMPTY'  | 'CS33321FE00'(!)        = ''              | ''                 | 'CS33321FE00'           | 'R0201'             | '(SMR0201AW)'                  | '33.2K'   | '1%'    | '1/20W'  | 'IO'       | 'RES CHIP 33.2K 1/20W +-1%(0201)'                  | 'CHIPR0201'    | ''          | ''            | '20191122'
 '115K'       | '1%'      | '1/20W'  | '0201LF'  | 'CHIP'   | 'CS41151FE00'(!)        = ''              | ''                 | 'CS41151FE00'           | 'R0201'             | '(SMR0201AW)'                  | '115K'    | '1%'    | '1/20W'  | 'DISCRETE' | 'RES CHIP 115K 1/20W +-1% (0201)'                  | 'CHIPR0201'    | ''          | ''            | '20191122'
 '115K'       | '1%'      | '1/20W'  | '0201LF'  | 'EMPTY'  | 'CS41151FE00'(!)        = ''              | ''                 | 'CS41151FE00'           | 'R0201'             | '(SMR0201AW)'                  | '115K'    | '1%'    | '1/20W'  | 'IO'       | 'RES CHIP 115K 1/20W +-1% (0201)'                  | 'CHIPR0201'    | ''          | ''            | '20191122'
 '806'        | '1%'      | '1/10W'  | '0603LF'  | 'CHIP'   | 'CS18063F901'(!)        = ''              | ''                 | 'CS18063F901'           | 'R0603_H24'         | '(SMR0603AW)'                  | '806'     | '1%'    | '1/10W'  | 'DISCRETE' | 'RES CHIP 806 1/10W +-1%(0603)EF'                  | 'CHIPR0603'    | ''          | ''            | '20191203'
 '806'        | '1%'      | '1/10W'  | '0603LF'  | 'EMPTY'  | 'CS18063F901'(!)        = ''              | ''                 | 'CS18063F901'           | 'R0603_H24'         | '(SMR0603AW)'                  | '806'     | '1%'    | '1/10W'  | 'IO'       | 'RES CHIP 806 1/10W +-1%(0603)EF'                  | 'CHIPR0603'    | ''          | ''            | '20191203'
 '0.0006'     | '1%'      | '4W'     | '2725LF'  | 'CHIP'   | 'CS0000FFT03'(!)        = 'End of Design' | 'Comp-Approve'     | 'CS0000FFT03'           | 'R2725'             | '(SMR2725AW)'                  | '0.0006'  | '1%'    | '4W'     | 'DISCRETE' | 'RES CHIP 0.0006 4W +-1%(2725)H0.991'              | 'CHIPR2725'    | ''          | ''            | '20191204'
 '0.0006'     | '1%'      | '4W'     | '2725LF'  | 'EMPTY'  | 'CS0000FFT03'(!)        = 'End of Design' | 'Comp-Approve'     | 'CS0000FFT03'           | 'R2725'             | '(SMR2725AW)'                  | '0.0006'  | '1%'    | '4W'     | 'IO'       | 'RES CHIP 0.0006 4W +-1%(2725)H0.991'              | 'CHIPR2725'    | ''          | ''            | '20191204'
 '2.61K'      | '0.1%'    | '1/16W'  | '0402LF'  | 'CHIP'   | 'CS22612BB00'(!)        = ''              | ''                 | 'CS22612BB00'           | 'R0402'             | '(R0402-0201)'                 | '2.61K'   | '0.1%'  | '1/16W'  | 'DISCRETE' | 'RES CHIP 2.61K 1/16W +-0.1%(0402)'                | 'CHIPR0402'    | ''          | ''            | '20191204'
 '2.61K'      | '0.1%'    | '1/16W'  | '0402LF'  | 'EMPTY'  | 'CS22612BB00'(!)        = ''              | ''                 | 'CS22612BB00'           | 'R0402'             | '(R0402-0201)'                 | '2.61K'   | '0.1%'  | '1/16W'  | 'IO'       | 'RES CHIP 2.61K 1/16W +-0.1%(0402)'                | 'CHIPR0402'    | ''          | ''            | '20191204'
 '76.8K'      | '0.1%'    | '1/20W'  | '0201LF'  | 'CHIP'   | 'CS37681BE01'(!)        = ''              | ''                 | 'CS37681BE01'           | 'R0201'             | '(SMR0201AW)'                  | '76.8K'   | '0.1%'  | '1/20W'  | 'DISCRETE' | 'RES CHIP 76.8K 1/20W +-0.1%(0201)'                | 'CHIPR0201'    | ''          | ''            | '20191204'
 '76.8K'      | '0.1%'    | '1/20W'  | '0201LF'  | 'EMPTY'  | 'CS37681BE01'(!)        = ''              | ''                 | 'CS37681BE01'           | 'R0201'             | '(SMR0201AW)'                  | '76.8K'   | '0.1%'  | '1/20W'  | 'IO'       | 'RES CHIP 76.8K 1/20W +-0.1%(0201)'                | 'CHIPR0201'    | ''          | ''            | '20191204'
 '8.06K'      | '1%'      | '1/20W'  | '0201LF'  | 'CHIP'   | 'CS28061FE00'(!)        = ''              | ''                 | 'CS28061FE00'           | 'R0201'             | '(SMR0201AW)'                  | '8.06K'   | '1%'    | '1/20W'  | 'DISCRETE' | 'RES CHIP 8.06K 1/20W +-1%(0201)'                  | 'CHIPR0201'    | ''          | ''            | '20191204'
 '8.06K'      | '1%'      | '1/20W'  | '0201LF'  | 'EMPTY'  | 'CS28061FE00'(!)        = ''              | ''                 | 'CS28061FE00'           | 'R0201'             | '(SMR0201AW)'                  | '8.06K'   | '1%'    | '1/20W'  | 'IO'       | 'RES CHIP 8.06K 1/20W +-1%(0201)'                  | 'CHIPR0201'    | ''          | ''            | '20191204'
 '931K'       | '1%'      | '1/16W'  | '0402LF'  | 'CHIP'   | 'CS49312FB00'(!)        = ''              | ''                 | 'CS49312FB00'           | 'R0402'             | '(R0402-0201)'                 | '931K'    | '1%'    | '1/16W'  | 'DISCRETE' | 'RES CHIP 931K 1/16W +-1%(0402)'                   | 'CHIPR0402'    | ''          | ''            | '20191216'
 '931K'       | '1%'      | '1/16W'  | '0402LF'  | 'EMPTY'  | 'CS49312FB00'(!)        = ''              | ''                 | 'CS49312FB00'           | 'R0402'             | '(R0402-0201)'                 | '931K'    | '1%'    | '1/16W'  | 'IO'       | 'RES CHIP 931K 1/16W +-1%(0402)'                   | 'CHIPR0402'    | ''          | ''            | '20191216'
 '0'          | '5%'      | '1/8W'   | '0805LF'  | 'CHIP'   | 'CS00004JA05'(!)        = 'End of Design' | 'Comp-Approve'     | 'CS00004JA05'           | 'R0805'             | '(SMR0805AW)'                  | '0'       | '5%'    | '1/8W'   | 'DISCRETE' | 'RES CHIP 0 1/8W +-5% (0805)EF'                    | 'CHIPR0805'    | ''          | ''            | '20191218'
 '0'          | '5%'      | '1/8W'   | '0805LF'  | 'EMPTY'  | 'CS00004JA05'(!)        = 'End of Design' | 'Comp-Approve'     | 'CS00004JA05'           | 'R0805'             | '(SMR0805AW)'                  | '0'       | '5%'    | '1/8W'   | 'IO'       | 'RES CHIP 0 1/8W +-5% (0805)EF'                    | 'CHIPR0805'    | ''          | ''            | '20191218'
 '0.0004'     | '1%'      | '4W'     | '2725LF'  | 'CHIP'   | 'CS0000FFT08'(!)        = 'End of Design' | 'Comp-Release Qty' | 'CS0000FFT08'           | 'R2725'             | '(SMR2725AW)'                  | '0.0004'  | '1%'    | '4W'     | 'DISCRETE' | 'RES CHIP 0.0004 4W +-1%(2725)'                    | 'CHIPR2725'    | ''          | ''            | '20191227'
 '0.0004'     | '1%'      | '4W'     | '2725LF'  | 'EMPTY'  | 'CS0000FFT08'(!)        = 'End of Design' | 'Comp-Release Qty' | 'CS0000FFT08'           | 'R2725'             | '(SMR2725AW)'                  | '0.0004'  | '1%'    | '4W'     | 'IO'       | 'RES CHIP 0.0004 4W +-1%(2725)'                    | 'CHIPR2725'    | ''          | ''            | '20191227'
 '0'          | ''        | '1W'     | '2512LF'  | 'CHIP'   | 'CS00008TR01'(!)        = ''              | ''                 | 'CS00008TR01'           | 'R2512XU'           | '(SMR2512AW)'                  | '0'       | ''      | '1W'     | 'DISCRETE' | 'RES CHIP 0 1W(2512)EF'                            | 'CHIPR2512'    | ''          | ''            | '20191227'
 '0'          | ''        | '1W'     | '2512LF'  | 'EMPTY'  | 'CS00008TR01'(!)        = ''              | ''                 | 'CS00008TR01'           | 'R2512XU'           | '(SMR2512AW)'                  | '0'       | ''      | '1W'     | 'IO'       | 'RES CHIP 0 1W(2512)EF'                            | 'CHIPR2512'    | ''          | ''            | '20191227'
 '750'        | '1%'      | '1/16W'  | '0402LF'  | 'CHIP'   | 'CS17502FB03'(!)        = 'End of Design' | 'Comp-Approve'     | 'CS17502FB03'           | 'R0402'             | '(R0402-0201)'                 | '750'     | '1%'    | '1/16W'  | 'DISCRETE' | 'RES CHIP 750 1/16W +-1%(0402)EF'                  | 'CHIPR0402'    | ''          | ''            | '20191227'
 '750'        | '1%'      | '1/16W'  | '0402LF'  | 'EMPTY'  | 'CS17502FB03'(!)        = 'End of Design' | 'Comp-Approve'     | 'CS17502FB03'           | 'R0402'             | '(R0402-0201)'                 | '750'     | '1%'    | '1/16W'  | 'IO'       | 'RES CHIP 750 1/16W +-1%(0402)EF'                  | 'CHIPR0402'    | ''          | ''            | '20191227'
 '2.32K'      | '1%'      | '1/16W'  | '0402LF'  | 'CHIP'   | 'CS22322FB03'(!)        = 'End of Design' | 'Comp-Approve'     | 'CS22322FB03'           | 'R0402'             | '(R0402-0201)'                 | '2.32K'   | '1%'    | '1/16W'  | 'DISCRETE' | 'RES CHIP 2.32K 1/16W +-1%(0402)EF'                | 'CHIPR0402'    | ''          | ''            | '20191227'
 '2.32K'      | '1%'      | '1/16W'  | '0402LF'  | 'EMPTY'  | 'CS22322FB03'(!)        = 'End of Design' | 'Comp-Approve'     | 'CS22322FB03'           | 'R0402'             | '(R0402-0201)'                 | '2.32K'   | '1%'    | '1/16W'  | 'IO'       | 'RES CHIP 2.32K 1/16W +-1%(0402)EF'                | 'CHIPR0402'    | ''          | ''            | '20191227'
 '7.32K'      | '1%'      | '1/16W'  | '0402LF'  | 'CHIP'   | 'CS27322FB02'(!)        = 'End of Design' | 'Comp-Approve'     | 'CS27322FB02'           | 'R0402'             | '(R0402-0201)'                 | '7.32K'   | '1%'    | '1/16W'  | 'DISCRETE' | 'RES CHIP 7.32K 1/16W +-1%(0402)EF'                | 'CHIPR0402'    | ''          | ''            | '20191227'
 '7.32K'      | '1%'      | '1/16W'  | '0402LF'  | 'EMPTY'  | 'CS27322FB02'(!)        = 'End of Design' | 'Comp-Approve'     | 'CS27322FB02'           | 'R0402'             | '(R0402-0201)'                 | '7.32K'   | '1%'    | '1/16W'  | 'IO'       | 'RES CHIP 7.32K 1/16W +-1%(0402)EF'                | 'CHIPR0402'    | ''          | ''            | '20191227'
 '7.68K'      | '1%'      | '1/16W'  | '0402LF'  | 'CHIP'   | 'CS27682FB04'(!)        = 'End of Design' | 'Comp-Approve'     | 'CS27682FB04'           | 'R0402'             | '(R0402-0201)'                 | '7.68K'   | '1%'    | '1/16W'  | 'DISCRETE' | 'RES CHIP 7.68K 1/16W +-1%(0402)EF'                | 'CHIPR0402'    | ''          | ''            | '20191227'
 '7.68K'      | '1%'      | '1/16W'  | '0402LF'  | 'EMPTY'  | 'CS27682FB04'(!)        = 'End of Design' | 'Comp-Approve'     | 'CS27682FB04'           | 'R0402'             | '(R0402-0201)'                 | '7.68K'   | '1%'    | '1/16W'  | 'IO'       | 'RES CHIP 7.68K 1/16W +-1%(0402)EF'                | 'CHIPR0402'    | ''          | ''            | '20191227'
 '15K'        | '1%'      | '1/16W'  | '0402LF'  | 'CHIP'   | 'CS31502FB05'(!)        = 'End of Design' | 'Comp-Approve'     | 'CS31502FB05'           | 'R0402'             | '(R0402-0201)'                 | '15K'     | '1%'    | '1/16W'  | 'DISCRETE' | 'RES CHIP 15K 1/16W +-1%(0402)EF'                  | 'CHIPR0402'    | ''          | ''            | '20191227'
 '15K'        | '1%'      | '1/16W'  | '0402LF'  | 'EMPTY'  | 'CS31502FB05'(!)        = 'End of Design' | 'Comp-Approve'     | 'CS31502FB05'           | 'R0402'             | '(R0402-0201)'                 | '15K'     | '1%'    | '1/16W'  | 'IO'       | 'RES CHIP 15K 1/16W +-1%(0402)EF'                  | 'CHIPR0402'    | ''          | ''            | '20191227'
 '634K'       | '1%'      | '1/16W'  | '0402LF'  | 'CHIP'   | 'CS46342FB04'(!)        = 'End of Design' | 'Comp-Approve'     | 'CS46342FB04'           | 'R0402'             | '(R0402-0201)'                 | '634K'    | '1%'    | '1/16W'  | 'DISCRETE' | 'RES CHIP 634K 1/16W +-1%(0402)'                   | 'CHIPR0402'    | ''          | ''            | '20200108'
 '634K'       | '1%'      | '1/16W'  | '0402LF'  | 'EMPTY'  | 'CS46342FB04'(!)        = 'End of Design' | 'Comp-Approve'     | 'CS46342FB04'           | 'R0402'             | '(R0402-0201)'                 | '634K'    | '1%'    | '1/16W'  | 'IO'       | 'RES CHIP 634K 1/16W +-1%(0402)'                   | 'CHIPR0402'    | ''          | ''            | '20200108'
 '825K'       | '1%'      | '1/16W'  | '0402LF'  | 'CHIP'   | 'CS48252FB01'(!)        = ''              | ''                 | 'CS48252FB01'           | 'R0402'             | '(R0402-0201)'                 | '825K'    | '1%'    | '1/16W'  | 'DISCRETE' | 'RES CHIP 825K 1/16W +-1%(0402)'                   | 'CHIPR0402'    | ''          | ''            | '20200108'
 '825K'       | '1%'      | '1/16W'  | '0402LF'  | 'EMPTY'  | 'CS48252FB01'(!)        = ''              | ''                 | 'CS48252FB01'           | 'R0402'             | '(R0402-0201)'                 | '825K'    | '1%'    | '1/16W'  | 'IO'       | 'RES CHIP 825K 1/16W +-1%(0402)'                   | 'CHIPR0402'    | ''          | ''            | '20200108'
 '715K'       | '1%'      | '1/16W'  | '0402LF'  | 'CHIP'   | 'CS47152FB00'(!)        = ''              | ''                 | 'CS47152FB00'           | 'R0402'             | '(R0402-0201)'                 | '715K'    | '1%'    | '1/16W'  | 'DISCRETE' | 'RES CHIP 715K 1/16W +-1% (0402)'                  | 'CHIPR0402'    | ''          | ''            | '20200114'
 '715K'       | '1%'      | '1/16W'  | '0402LF'  | 'EMPTY'  | 'CS47152FB00'(!)        = ''              | ''                 | 'CS47152FB00'           | 'R0402'             | '(R0402-0201)'                 | '715K'    | '1%'    | '1/16W'  | 'IO'       | 'RES CHIP 715K 1/16W +-1% (0402)'                  | 'CHIPR0402'    | ''          | ''            | '20200114'
 '2.7K'       | '5%'      | '1/8W'   | '0805LF'  | 'CHIP'   | 'CS22704JA36'(!)        = ''              | ''                 | 'CS22704JA36'           | 'R0805'             | '(SMR0805AW)'                  | '2.7K'    | '5%'    | '1/8W'   | 'DISCRETE' | 'RESISTOR CHIP 2.7K  1/8W  +-5%(0805)'             | 'CHIPR0805'    | ''          | ''            | '20200113'
 '2.7K'       | '5%'      | '1/8W'   | '0805LF'  | 'EMPTY'  | 'CS22704JA36'(!)        = ''              | ''                 | 'CS22704JA36'           | 'R0805'             | '(SMR0805AW)'                  | '2.7K'    | '5%'    | '1/8W'   | 'IO'       | 'RESISTOR CHIP 2.7K  1/8W  +-5%(0805)'             | 'CHIPR0805'    | ''          | ''            | '20200113'
 '19.6K'      | '1%'      | '1/16W'  | '0402LF'  | 'CHIP'   | 'CS31962FB07'(!)        = ''              | ''                 | 'CS31962FB07'           | 'R0402'             | '(R0402-0201)'                 | '19.6K'   | '1%'    | '1/16W'  | 'DISCRETE' | 'RES CHIP 19.6K 1/16W +-1%(0402)EF'                | 'CHIPR0402'    | ''          | ''            | '20200114'
 '19.6K'      | '1%'      | '1/16W'  | '0402LF'  | 'EMPTY'  | 'CS31962FB07'(!)        = ''              | ''                 | 'CS31962FB07'           | 'R0402'             | '(R0402-0201)'                 | '19.6K'   | '1%'    | '1/16W'  | 'IO'       | 'RES CHIP 19.6K 1/16W +-1%(0402)EF'                | 'CHIPR0402'    | ''          | ''            | '20200114'
 '255'        | '1%'      | '1/10W'  | '0603LF'  | 'CHIP'   | 'CS12553F914'(!)        = ''              | ''                 | 'CS12553F914'           | 'R0603'             | '(SMR0603AW)'                  | '255'     | '1%'    | '1/10W'  | 'DISCRETE' | 'RESISTOR CHIP 255,1/10W,+-1%(0603)'               | 'CHIPR0603'    | ''          | ''            | '20200122'
 '255'        | '1%'      | '1/10W'  | '0603LF'  | 'EMPTY'  | 'CS12553F914'(!)        = ''              | ''                 | 'CS12553F914'           | 'R0603'             | '(SMR0603AW)'                  | '255'     | '1%'    | '1/10W'  | 'IO'       | 'RESISTOR CHIP 255,1/10W,+-1%(0603)'               | 'CHIPR0603'    | ''          | ''            | '20200122'
 '33'         | '5%'      | '1/8W'   | '0805LF'  | 'CHIP'   | 'CS03304JA14'(!)        = ''              | ''                 | 'CS03304JA14'           | 'R0805'             | '(SMR0805AW)'                  | '33'      | '5%'    | '1/8W'   | 'DISCRETE' | 'RES CHIP 33 1/8W +-5% (0805)'                     | 'CHIPR0805'    | ''          | ''            | '20200203'
 '33'         | '5%'      | '1/8W'   | '0805LF'  | 'EMPTY'  | 'CS03304JA14'(!)        = ''              | ''                 | 'CS03304JA14'           | 'R0805'             | '(SMR0805AW)'                  | '33'      | '5%'    | '1/8W'   | 'IO'       | 'RES CHIP 33 1/8W +-5% (0805)'                     | 'CHIPR0805'    | ''          | ''            | '20200203'
 '120K'       | '1%'      | '1/16W'  | '0402LF'  | 'CHIP'   | 'CS41202FB05'(!)        = ''              | ''                 | 'CS41202FB05'           | 'R0402'             | '(R0402-0201)'                 | '120K'    | '1%'    | '1/16W'  | 'DISCRETE' | 'RES CHIP 120K 1/16W +-1%(0402)EF'                 | 'CHIPR0402'    | ''          | ''            | '20200225'
 '120K'       | '1%'      | '1/16W'  | '0402LF'  | 'EMPTY'  | 'CS41202FB05'(!)        = ''              | ''                 | 'CS41202FB05'           | 'R0402'             | '(R0402-0201)'                 | '120K'    | '1%'    | '1/16W'  | 'IO'       | 'RES CHIP 120K 1/16W +-1%(0402)EF'                 | 'CHIPR0402'    | ''          | ''            | '20200225'
 '0.0003'     | '1%'      | '8W'     | '2512LF'  | 'CHIP'   | 'CS0000LFR00'(!)        = ''              | ''                 | 'CS0000LFR00'           | 'R2512XV'           | '(SMR2512AW)'                  | '0.0003'  | '1%'    | '8W'     | 'DISCRETE' | 'RES CHIP 0.0003 8W +-1% (2512)KOA'                | 'CHIPR2512'    | ''          | ''            | '20200227'
 '0.0003'     | '1%'      | '8W'     | '2512LF'  | 'EMPTY'  | 'CS0000LFR00'(!)        = ''              | ''                 | 'CS0000LFR00'           | 'R2512XV'           | '(SMR2512AW)'                  | '0.0003'  | '1%'    | '8W'     | 'IO'       | 'RES CHIP 0.0003 8W +-1% (2512)KOA'                | 'CHIPR2512'    | ''          | ''            | '20200227'
 '56.2K'      | '1%'      | '1/16W'  | '0402LF'  | 'CHIP'   | 'CS35622FB07'(!)        = 'End of Design' | 'Comp-Approve'     | 'CS35622FB07'           | 'R0402'             | '(R0402-0201)'                 | '56.2K'   | '1%'    | '1/16W'  | 'DISCRETE' | 'RES CHIP 56.2K 1/16W +-1%(0402)EF'                | 'CHIPR0402'    | ''          | ''            | '20200227'
 '56.2K'      | '1%'      | '1/16W'  | '0402LF'  | 'EMPTY'  | 'CS35622FB07'(!)        = 'End of Design' | 'Comp-Approve'     | 'CS35622FB07'           | 'R0402'             | '(R0402-0201)'                 | '56.2K'   | '1%'    | '1/16W'  | 'IO'       | 'RES CHIP 56.2K 1/16W +-1%(0402)EF'                | 'CHIPR0402'    | ''          | ''            | '20200227'
 '46.4K'      | '1%'      | '1/16W'  | '0402LF'  | 'CHIP'   | 'CS34642FB02'(!)        = ''              | ''                 | 'CS34642FB02'           | 'R0402'             | '(R0402-0201)'                 | '46.4K'   | '1%'    | '1/16W'  | 'DISCRETE' | 'RES CHIP 46.4K 1/16W +-1%(0402)EF'                | 'CHIPR0402'    | ''          | ''            | '20200227'
 '46.4K'      | '1%'      | '1/16W'  | '0402LF'  | 'EMPTY'  | 'CS34642FB02'(!)        = ''              | ''                 | 'CS34642FB02'           | 'R0402'             | '(R0402-0201)'                 | '46.4K'   | '1%'    | '1/16W'  | 'IO'       | 'RES CHIP 46.4K 1/16W +-1%(0402)EF'                | 'CHIPR0402'    | ''          | ''            | '20200227'
 '21.5K'      | '1%'      | '1/16W'  | '0402LF'  | 'CHIP'   | 'CS32152FB04'(!)        = ''              | ''                 | 'CS32152FB04'           | 'R0402'             | '(R0402-0201)'                 | '21.5K'   | '1%'    | '1/16W'  | 'DISCRETE' | 'RES CHIP 21.5K 1/16W +-1%(0402)EF'                | 'CHIPR0402'    | ''          | ''            | '20200302'
 '21.5K'      | '1%'      | '1/16W'  | '0402LF'  | 'EMPTY'  | 'CS32152FB04'(!)        = ''              | ''                 | 'CS32152FB04'           | 'R0402'             | '(R0402-0201)'                 | '21.5K'   | '1%'    | '1/16W'  | 'IO'       | 'RES CHIP 21.5K 1/16W +-1%(0402)EF'                | 'CHIPR0402'    | ''          | ''            | '20200302'
 '270K'       | '1%'      | '1/16W'  | '0402LF'  | 'CHIP'   | 'CS42702FB01'(!)        = ''              | ''                 | 'CS42702FB01'           | 'R0402'             | '(R0402-0201)'                 | '270K'    | '1%'    | '1/16W'  | 'DISCRETE' | 'RES CHIP 270K 1/16W +-1%(0402)EF'                 | 'CHIPR0402'    | ''          | ''            | '20200304'
 '270K'       | '1%'      | '1/16W'  | '0402LF'  | 'EMPTY'  | 'CS42702FB01'(!)        = ''              | ''                 | 'CS42702FB01'           | 'R0402'             | '(R0402-0201)'                 | '270K'    | '1%'    | '1/16W'  | 'IO'       | 'RES CHIP 270K 1/16W +-1%(0402)EF'                 | 'CHIPR0402'    | ''          | ''            | '20200304'
 '0.22'       | '1%'      | '1/2W'   | '1206LF'  | 'CHIP'   | 'CS+2207F202'(!)        = ''              | ''                 | 'CS+2207F202'           | 'R1206XJ'           | '(SMR1206AW)'                  | '0.22'    | '1%'    | '1/2W'   | 'DISCRETE' | 'RES CHIP 0.22 1/2W +-1%(1206)'                    | 'CHIPR1206'    | ''          | ''            | '20200304'
 '0.22'       | '1%'      | '1/2W'   | '1206LF'  | 'EMPTY'  | 'CS+2207F202'(!)        = ''              | ''                 | 'CS+2207F202'           | 'R1206XJ'           | '(SMR1206AW)'                  | '0.22'    | '1%'    | '1/2W'   | 'IO'       | 'RES CHIP 0.22 1/2W +-1%(1206)'                    | 'CHIPR1206'    | ''          | ''            | '20200304'
 '4.75'       | '1%'      | '1/16W'  | '0402LF'  | 'CHIP'   | 'CS-4752FB01'(!)        = 'End of Design' | 'Comp-Approve'     | 'CS-4752FB01'           | 'R0402'             | '(R0402-0201)'                 | '4.75'    | '1%'    | '1/16W'  | 'DISCRETE' | 'RES CHIP 4.75 1/16W +-1%(0402)EF'                 | 'CHIPR0402'    | ''          | ''            | '20200312'
 '4.75'       | '1%'      | '1/16W'  | '0402LF'  | 'EMPTY'  | 'CS-4752FB01'(!)        = 'End of Design' | 'Comp-Approve'     | 'CS-4752FB01'           | 'R0402'             | '(R0402-0201)'                 | '4.75'    | '1%'    | '1/16W'  | 'IO'       | 'RES CHIP 4.75 1/16W +-1%(0402)EF'                 | 'CHIPR0402'    | ''          | ''            | '20200312'
 '1.3M'       | '1%'      | '1/16W'  | '0402LF'  | 'CHIP'   | 'CS51302FB00'(!)        = ''              | ''                 | 'CS51302FB00'           | 'R0402'             | '(R0402-0201)'                 | '1.3M'    | '1%'    | '1/16W'  | 'DISCRETE' | 'RES CHIP 1.3M 1/16W +-1%(0402)'                   | 'CHIPR0402'    | ''          | ''            | '20200313'
 '1.3M'       | '1%'      | '1/16W'  | '0402LF'  | 'EMPTY'  | 'CS51302FB00'(!)        = ''              | ''                 | 'CS51302FB00'           | 'R0402'             | '(R0402-0201)'                 | '1.3M'    | '1%'    | '1/16W'  | 'IO'       | 'RES CHIP 1.3M 1/16W +-1%(0402)'                   | 'CHIPR0402'    | ''          | ''            | '20200313'
 '1.43M'      | '1%'      | '1/16W'  | '0402LF'  | 'CHIP'   | 'CS51432FB10'(!)        = ''              | ''                 | 'CS51432FB10'           | 'R0402'             | '(R0402-0201)'                 | '1.43M'   | '1%'    | '1/16W'  | 'DISCRETE' | 'RES CHIP 1.43M 1/16W+-1%(0402)'                   | 'CHIPR0402'    | ''          | ''            | '20200313'
 '1.43M'      | '1%'      | '1/16W'  | '0402LF'  | 'EMPTY'  | 'CS51432FB10'(!)        = ''              | ''                 | 'CS51432FB10'           | 'R0402'             | '(R0402-0201)'                 | '1.43M'   | '1%'    | '1/16W'  | 'IO'       | 'RES CHIP 1.43M 1/16W+-1%(0402)'                   | 'CHIPR0402'    | ''          | ''            | '20200313'
 '976'        | '0.1%'    | '1/16W'  | '0402LF'  | 'CHIP'   | 'CS19762BB00'(!)        = ''              | ''                 | 'CS19762BB00'           | 'R0402'             | '(R0402-0201)'                 | '976'     | '0.1%'  | '1/16W'  | 'DISCRETE' | 'RES CHIP 976 1/16W  +-0.1%(0402)'                 | 'CHIPR0402'    | ''          | ''            | '20170829'
 '976'        | '0.1%'    | '1/16W'  | '0402LF'  | 'EMPTY'  | 'CS19762BB00'(!)        = ''              | ''                 | 'CS19762BB00'           | 'R0402'             | '(R0402-0201)'                 | '976'     | '0.1%'  | '1/16W'  | 'IO'       | 'RES CHIP 976 1/16W  +-0.1%(0402)'                 | 'CHIPR0402'    | ''          | ''            | '20170829'
 '3.3'        | '1%'      | '1/16W'  | '0402LF'  | 'CHIP'   | 'CS-3302FB00'(!)        = 'End of Design' | 'Comp-Approve'     | 'CS-3302FB00'           | 'R0402'             | '(R0402-0201)'                 | '3.3'     | '1%'    | '1/16W'  | 'DISCRETE' | 'RES CHIP 3.3 1/16W +-1% (0402)'                   | 'CHIPR0402'    | ''          | ''            | '20200319'
 '3.3'        | '1%'      | '1/16W'  | '0402LF'  | 'EMPTY'  | 'CS-3302FB00'(!)        = 'End of Design' | 'Comp-Approve'     | 'CS-3302FB00'           | 'R0402'             | '(R0402-0201)'                 | '3.3'     | '1%'    | '1/16W'  | 'IO'       | 'RES CHIP 3.3 1/16W +-1% (0402)'                   | 'CHIPR0402'    | ''          | ''            | '20200319'
 '100'        | '1%'      | '1/4W'   | '1206LF'  | 'CHIP'   | 'CS11006F216'(!)        = ''              | ''                 | 'CS11006F216'           | 'R1206XM'           | '(SMR1206AW)'                  | '100'     | '1%'    | '1/4W'   | 'DISCRETE' | 'RES CHIP 100 1/4W +-1%(1206)'                     | 'CHIPR1206'    | ''          | ''            | '20200323'
 '100'        | '1%'      | '1/4W'   | '1206LF'  | 'EMPTY'  | 'CS11006F216'(!)        = ''              | ''                 | 'CS11006F216'           | 'R1206XM'           | '(SMR1206AW)'                  | '100'     | '1%'    | '1/4W'   | 'IO'       | 'RES CHIP 100 1/4W +-1%(1206)'                     | 'CHIPR1206'    | ''          | ''            | '20200323'
 '5.76K'      | '1%'      | '1/16W'  | '0402LF'  | 'CHIP'   | 'CS25762FB04'(!)        = 'End of Design' | 'Comp-Approve'     | 'CS25762FB04'           | 'R0402'             | '(R0402-0201)'                 | '5.76K'   | '1%'    | '1/16W'  | 'DISCRETE' | 'RES CHIP 5.76K 1/16W +-1%(0402)EF'                | 'CHIPR0402'    | ''          | ''            | '20200320'
 '5.76K'      | '1%'      | '1/16W'  | '0402LF'  | 'EMPTY'  | 'CS25762FB04'(!)        = 'End of Design' | 'Comp-Approve'     | 'CS25762FB04'           | 'R0402'             | '(R0402-0201)'                 | '5.76K'   | '1%'    | '1/16W'  | 'IO'       | 'RES CHIP 5.76K 1/16W +-1%(0402)EF'                | 'CHIPR0402'    | ''          | ''            | '20200320'
 '4.7K'       | '1%'      | '1/20W'  | '0201LF'  | 'CHIP'   | 'CS24701FE00'(!)        = ''              | ''                 | 'CS24701FE00'           | 'R0201'             | '(SMR0201AW)'                  | '4.7K'    | '1%'    | '1/20W'  | 'DISCRETE' | 'RES CHIP 4.7K 1/20W +-1%(0201)'                   | 'CHIPR0201'    | ''          | ''            | '20200326'
 '4.7K'       | '1%'      | '1/20W'  | '0201LF'  | 'EMPTY'  | 'CS24701FE00'(!)        = ''              | ''                 | 'CS24701FE00'           | 'R0201'             | '(SMR0201AW)'                  | '4.7K'    | '1%'    | '1/20W'  | 'IO'       | 'RES CHIP 4.7K 1/20W +-1%(0201)'                   | 'CHIPR0201'    | ''          | ''            | '20200326'
 '30K'        | '1%'      | '1/20W'  | '0201LF'  | 'CHIP'   | 'CS33001FE00'(!)        = 'End of Design' | 'Comp-Approve'     | 'CS33001FE00'           | 'R0201'             | '(SMR0201AW)'                  | '30K'     | '1%'    | '1/20W'  | 'DISCRETE' | 'RES CHIP 30K 1/20W +-1% (0201)'                   | 'CHIPR0201'    | ''          | ''            | '20200326'
 '30K'        | '1%'      | '1/20W'  | '0201LF'  | 'EMPTY'  | 'CS33001FE00'(!)        = 'End of Design' | 'Comp-Approve'     | 'CS33001FE00'           | 'R0201'             | '(SMR0201AW)'                  | '30K'     | '1%'    | '1/20W'  | 'IO'       | 'RES CHIP 30K 1/20W +-1% (0201)'                   | 'CHIPR0201'    | ''          | ''            | '20200326'
 '162'        | '1%'      | '1/16W'  | '0402LF'  | 'CHIP'   | 'CS11622FB09'(!)        = ''              | ''                 | 'CS11622FB09'           | 'R0402'             | '(R0402-0201)'                 | '162'     | '1%'    | '1/16W'  | 'DISCRETE' | 'RES CHIP 162 1/16W +-1% (0402)YGO'                | 'CHIPR0402'    | ''          | ''            | '20200324'
 '162'        | '1%'      | '1/16W'  | '0402LF'  | 'EMPTY'  | 'CS11622FB09'(!)        = ''              | ''                 | 'CS11622FB09'           | 'R0402'             | '(R0402-0201)'                 | '162'     | '1%'    | '1/16W'  | 'IO'       | 'RES CHIP 162 1/16W +-1% (0402)YGO'                | 'CHIPR0402'    | ''          | ''            | '20200324'
 '681'        | '1%'      | '1/16W'  | '0402LF'  | 'CHIP'   | 'CS16812FB07'(!)        = ''              | ''                 | 'CS16812FB07'           | 'R0402'             | '(R0402-0201)'                 | '681'     | '1%'    | '1/16W'  | 'DISCRETE' | 'RES CHIP 681 1/16W +-1% (0402)YGO'                | 'CHIPR0402'    | ''          | ''            | '20200325'
 '681'        | '1%'      | '1/16W'  | '0402LF'  | 'EMPTY'  | 'CS16812FB07'(!)        = ''              | ''                 | 'CS16812FB07'           | 'R0402'             | '(R0402-0201)'                 | '681'     | '1%'    | '1/16W'  | 'IO'       | 'RES CHIP 681 1/16W +-1% (0402)YGO'                | 'CHIPR0402'    | ''          | ''            | '20200325'
 '2.8K'       | '1%'      | '1/16W'  | '0402LF'  | 'CHIP'   | 'CS22802FB07'(!)        = ''              | ''                 | 'CS22802FB07'           | 'R0402'             | '(R0402-0201)'                 | '2.8K'    | '1%'    | '1/16W'  | 'DISCRETE' | 'RES CHIP 2.8K 1/16W +-1%(0402)YGO'                | 'CHIPR0402'    | ''          | ''            | '20200325'
 '2.8K'       | '1%'      | '1/16W'  | '0402LF'  | 'EMPTY'  | 'CS22802FB07'(!)        = ''              | ''                 | 'CS22802FB07'           | 'R0402'             | '(R0402-0201)'                 | '2.8K'    | '1%'    | '1/16W'  | 'IO'       | 'RES CHIP 2.8K 1/16W +-1%(0402)YGO'                | 'CHIPR0402'    | ''          | ''            | '20200325'
 '3.3'        | '1%'      | '1/2W'   | '1206LF'  | 'CHIP'   | 'CS-3307F200'(!)        = ''              | ''                 | 'CS-3307F200'           | 'R1206XN'           | '(SMR1206AW)'                  | '3.3'     | '1%'    | '1/2W'   | 'DISCRETE' | 'RES CHIP 3.3 1/2W+-1%(1206)SR'                    | 'CHIPR1206'    | ''          | ''            | '20200330'
 '3.3'        | '1%'      | '1/2W'   | '1206LF'  | 'EMPTY'  | 'CS-3307F200'(!)        = ''              | ''                 | 'CS-3307F200'           | 'R1206XN'           | '(SMR1206AW)'                  | '3.3'     | '1%'    | '1/2W'   | 'IO'       | 'RES CHIP 3.3 1/2W+-1%(1206)SR'                    | 'CHIPR1206'    | ''          | ''            | '20200330'
 '475K'       | '1%'      | '1/10W'  | '0603LF'  | 'CHIP'   | 'CS44753F912'(!)        = ''              | ''                 | 'CS44753F912'           | 'R0603'             | '(SMR0603AW)'                  | '475K'    | '1%'    | '1/10W'  | 'DISCRETE' | 'RES CHIP 475K 1/10W +-1%(0603)'                   | 'CHIPR0603'    | ''          | ''            | '20200401'
 '475K'       | '1%'      | '1/10W'  | '0603LF'  | 'EMPTY'  | 'CS44753F912'(!)        = ''              | ''                 | 'CS44753F912'           | 'R0603'             | '(SMR0603AW)'                  | '475K'    | '1%'    | '1/10W'  | 'IO'       | 'RES CHIP 475K 1/10W +-1%(0603)'                   | 'CHIPR0603'    | ''          | ''            | '20200401'
 '124'        | '1%'      | '1/16W'  | '0402LF'  | 'CHIP'   | 'CS11242FB10'(!)        = 'End of Design' | 'Comp-Approve'     | 'CS11242FB10'           | 'R0402'             | '(R0402-0201)'                 | '124'     | '1%'    | '1/16W'  | 'DISCRETE' | 'RES CHIP 124 1/16W +-1%(0402)'                    | 'CHIPR0402'    | ''          | ''            | '20200409'
 '124'        | '1%'      | '1/16W'  | '0402LF'  | 'EMPTY'  | 'CS11242FB10'(!)        = 'End of Design' | 'Comp-Approve'     | 'CS11242FB10'           | 'R0402'             | '(R0402-0201)'                 | '124'     | '1%'    | '1/16W'  | 'IO'       | 'RES CHIP 124 1/16W +-1%(0402)'                    | 'CHIPR0402'    | ''          | ''            | '20200409'
 '3.3'        | '1%'      | '1/4W'   | '0603LF'  | 'CHIP'   | 'CS-3306F900'(!)        = ''              | ''                 | 'CS-3306F900'           | 'R0603'             | '(SMR0603AW)'                  | '3.3'     | '1%'    | '1/4W'   | 'DISCRETE' | 'RES CHIP 3.3 1/4W+-1%(0603)SR'                    | 'CHIPR0603'    | ''          | ''            | '20200414'
 '3.3'        | '1%'      | '1/4W'   | '0603LF'  | 'EMPTY'  | 'CS-3306F900'(!)        = ''              | ''                 | 'CS-3306F900'           | 'R0603'             | '(SMR0603AW)'                  | '3.3'     | '1%'    | '1/4W'   | 'IO'       | 'RES CHIP 3.3 1/4W+-1%(0603)SR'                    | 'CHIPR0603'    | ''          | ''            | '20200414'
 '330'        | '5%'      | '1/2W'   | '1206LF'  | 'CHIP'   | 'CS13307J200'(!)        = ''              | ''                 | 'CS13307J200'           | 'R1206XN'           | '(SMR1206AW)'                  | '330'     | '5%'    | '1/2W'   | 'DISCRETE' | 'RES CHIP 330 1/2W+-5%(1206)SR'                    | 'CHIPR1206'    | ''          | ''            | '20200424'
 '330'        | '5%'      | '1/2W'   | '1206LF'  | 'EMPTY'  | 'CS13307J200'(!)        = ''              | ''                 | 'CS13307J200'           | 'R1206XN'           | '(SMR1206AW)'                  | '330'     | '5%'    | '1/2W'   | 'IO'       | 'RES CHIP 330 1/2W+-5%(1206)SR'                    | 'CHIPR1206'    | ''          | ''            | '20200424'
 '3.3'        | '5%'      | '1/5W'   | '0603LF'  | 'CHIP'   | 'CS-330GJ900'(!)        = ''              | ''                 | 'CS-330GJ900'           | 'R0603'             | '(SMR0603AW)'                  | '3.3'     | '5%'    | '1/5W'   | 'DISCRETE' | 'RES CHIP 3.3 1/5W+-5%(0603)SR'                    | 'CHIPR0603'    | ''          | ''            | '20200429'
 '3.3'        | '5%'      | '1/5W'   | '0603LF'  | 'EMPTY'  | 'CS-330GJ900'(!)        = ''              | ''                 | 'CS-330GJ900'           | 'R0603'             | '(SMR0603AW)'                  | '3.3'     | '5%'    | '1/5W'   | 'IO'       | 'RES CHIP 3.3 1/5W+-5%(0603)SR'                    | 'CHIPR0603'    | ''          | ''            | '20200429'
 '1.5'        | '5%'      | '1/4W'   | '0603LF'  | 'CHIP'   | 'CS-1506J900'(!)        = ''              | ''                 | 'CS-1506J900'           | 'R0603'             | '(SMR0603AW)'                  | '1.5'     | '5%'    | '1/4W'   | 'DISCRETE' | 'RES CHIP 1.5 1/4W+-5%(0603)SR'                    | 'CHIPR0603'    | ''          | ''            | '20200505'
 '1.5'        | '5%'      | '1/4W'   | '0603LF'  | 'EMPTY'  | 'CS-1506J900'(!)        = ''              | ''                 | 'CS-1506J900'           | 'R0603'             | '(SMR0603AW)'                  | '1.5'     | '5%'    | '1/4W'   | 'IO'       | 'RES CHIP 1.5 1/4W+-5%(0603)SR'                    | 'CHIPR0603'    | ''          | ''            | '20200505'
 '3.65K'      | '1%'      | '1/16W'  | '0402LF'  | 'CHIP'   | 'CS23652FB03'(!)        = ''              | ''                 | 'CS23652FB03'           | 'R0402'             | '(R0402-0201)'                 | '3.65K'   | '1%'    | '1/16W'  | 'DISCRETE' | 'RES CHIP 3.65K 1/16W +-1%(0402)EF'                | 'CHIPR0402'    | ''          | ''            | '20200508'
 '3.65K'      | '1%'      | '1/16W'  | '0402LF'  | 'EMPTY'  | 'CS23652FB03'(!)        = ''              | ''                 | 'CS23652FB03'           | 'R0402'             | '(R0402-0201)'                 | '3.65K'   | '1%'    | '1/16W'  | 'IO'       | 'RES CHIP 3.65K 1/16W +-1%(0402)EF'                | 'CHIPR0402'    | ''          | ''            | '20200508'
 '0.01'       | '1%'      | '1W'     | '1206LF'  | 'CHIP'   | 'CS+0108F207'(!)        = ''              | ''                 | 'CS+0108F207'           | 'R1206XO'           | '(SMR1206AW)'                  | '0.01'    | '1%'    | '1W'     | 'DISCRETE' | 'RES CHIP 0.01 1W +-1%(1206)EF'                    | 'CHIPR1206'    | ''          | ''            | '20191224'
 '0.01'       | '1%'      | '1W'     | '1206LF'  | 'EMPTY'  | 'CS+0108F207'(!)        = ''              | ''                 | 'CS+0108F207'           | 'R1206XO'           | '(SMR1206AW)'                  | '0.01'    | '1%'    | '1W'     | 'IO'       | 'RES CHIP 0.01 1W +-1%(1206)EF'                    | 'CHIPR1206'    | ''          | ''            | '20191224'
 '1.58M'      | '1%'      | '1/8W'   | '0805LF'  | 'CHIP'   | 'CS51584FA00'(!)        = ''              | ''                 | 'CS51584FA00'           | 'R0805'             | '(SMR0805AW)'                  | '1.58M'   | '1%'    | '1/8W'   | 'DISCRETE' | 'RES CHIP 1.58M 1/8W +-1%(0805)'                   | 'CHIPR0805'    | ''          | ''            | '20200514'
 '1.58M'      | '1%'      | '1/8W'   | '0805LF'  | 'EMPTY'  | 'CS51584FA00'(!)        = ''              | ''                 | 'CS51584FA00'           | 'R0805'             | '(SMR0805AW)'                  | '1.58M'   | '1%'    | '1/8W'   | 'IO'       | 'RES CHIP 1.58M 1/8W +-1%(0805)'                   | 'CHIPR0805'    | ''          | ''            | '20200514'
 '1.5K'       | '1%'      | '1/4W'   | '1206LF'  | 'CHIP'   | 'CS21506F200'(!)        = ''              | ''                 | 'CS21506F200'           | 'R1206XM'           | '(SMR1206AW)'                  | '1.5K'    | '1%'    | '1/4W'   | 'DISCRETE' | 'RES CHIP 1.5K 1/4W +-1%(1206)'                    | 'CHIPR1206'    | ''          | ''            | '20200518'
 '1.5K'       | '1%'      | '1/4W'   | '1206LF'  | 'EMPTY'  | 'CS21506F200'(!)        = ''              | ''                 | 'CS21506F200'           | 'R1206XM'           | '(SMR1206AW)'                  | '1.5K'    | '1%'    | '1/4W'   | 'IO'       | 'RES CHIP 1.5K 1/4W +-1%(1206)'                    | 'CHIPR1206'    | ''          | ''            | '20200518'
 '0.001'      | '1%'      | '3W'     | '2512LF'  | 'CHIP'   | 'CS+001DFR07'(!)        = ''              | ''                 | 'CS+001DFR07'           | 'R2512XW'           | '(SMR2512AW)'                  | '0.001'   | '1%'    | '3W'     | 'DISCRETE' | 'RES CHIP 0.001 3W +-1%(2512)YGO AEC'              | 'CHIPR2512'    | ''          | ''            | '20200527'
 '0.001'      | '1%'      | '3W'     | '2512LF'  | 'EMPTY'  | 'CS+001DFR07'(!)        = ''              | ''                 | 'CS+001DFR07'           | 'R2512XW'           | '(SMR2512AW)'                  | '0.001'   | '1%'    | '3W'     | 'IO'       | 'RES CHIP 0.001 3W +-1%(2512)YGO AEC'              | 'CHIPR2512'    | ''          | ''            | '20200527'
 '45.3K'      | '1%'      | '1/16W'  | '0402LF'  | 'CHIP'   | 'CS34532FB08'(!)        = ''              | ''                 | 'CS34532FB08'           | 'R0402'             | '(R0402-0201)'                 | '45.3K'   | '1%'    | '1/16W'  | 'DISCRETE' | 'RES CHIP 45.3K 1/16W +-1%(0402)EF'                | 'CHIPR0402'    | ''          | ''            | '20200602'
 '45.3K'      | '1%'      | '1/16W'  | '0402LF'  | 'EMPTY'  | 'CS34532FB08'(!)        = ''              | ''                 | 'CS34532FB08'           | 'R0402'             | '(R0402-0201)'                 | '45.3K'   | '1%'    | '1/16W'  | 'IO'       | 'RES CHIP 45.3K 1/16W +-1%(0402)EF'                | 'CHIPR0402'    | ''          | ''            | '20200602'
 '107K'       | '1%'      | '1/16W'  | '0402LF'  | 'CHIP'   | 'CS41072FB05'(!)        = ''              | ''                 | 'CS41072FB05'           | 'R0402'             | '(R0402-0201)'                 | '107K'    | '1%'    | '1/16W'  | 'DISCRETE' | 'RES CHIP 107K 1/16W +-1%(0402)EF'                 | 'CHIPR0402'    | ''          | ''            | '20200602'
 '107K'       | '1%'      | '1/16W'  | '0402LF'  | 'EMPTY'  | 'CS41072FB05'(!)        = ''              | ''                 | 'CS41072FB05'           | 'R0402'             | '(R0402-0201)'                 | '107K'    | '1%'    | '1/16W'  | 'IO'       | 'RES CHIP 107K 1/16W +-1%(0402)EF'                 | 'CHIPR0402'    | ''          | ''            | '20200602'
 '91K'        | '1%'      | '1/16W'  | '0402LF'  | 'CHIP'   | 'CS39102FB06'(!)        = ''              | ''                 | 'CS39102FB06'           | 'R0402'             | '(R0402-0201)'                 | '91K'     | '1%'    | '1/16W'  | 'DISCRETE' | 'RES CHIP 91K 1/16W +-1%(0402)EF'                  | 'CHIPR0402'    | ''          | ''            | '20200602'
 '91K'        | '1%'      | '1/16W'  | '0402LF'  | 'EMPTY'  | 'CS39102FB06'(!)        = ''              | ''                 | 'CS39102FB06'           | 'R0402'             | '(R0402-0201)'                 | '91K'     | '1%'    | '1/16W'  | 'IO'       | 'RES CHIP 91K 1/16W +-1%(0402)EF'                  | 'CHIPR0402'    | ''          | ''            | '20200602'
 '20.5K'      | '1%'      | '1/16W'  | '0402LF'  | 'CHIP'   | 'CS32052FB02'(!)        = 'End of Design' | 'Comp-Approve'     | 'CS32052FB02'           | 'R0402'             | '(R0402-0201)'                 | '20.5K'   | '1%'    | '1/16W'  | 'DISCRETE' | 'RES CHIP 20.5K 1/16W +-1%(0402)EF'                | 'CHIPR0402'    | ''          | ''            | '20200602'
 '20.5K'      | '1%'      | '1/16W'  | '0402LF'  | 'EMPTY'  | 'CS32052FB02'(!)        = 'End of Design' | 'Comp-Approve'     | 'CS32052FB02'           | 'R0402'             | '(R0402-0201)'                 | '20.5K'   | '1%'    | '1/16W'  | 'IO'       | 'RES CHIP 20.5K 1/16W +-1%(0402)EF'                | 'CHIPR0402'    | ''          | ''            | '20200602'
 '0.0003'     | '1%'      | '4W'     | '2725LF'  | 'CHIP'   | 'CS0000FFT10'(!)        = 'End of Design' | 'Comp-Approve'     | 'CS0000FFT10'           | 'R2725XA'           | '(SMR2725AW)'                  | '0.0003'  | '1%'    | '4W'     | 'DISCRETE' | 'RES CHIP 0.0003 4W +-1%(2725)ERO'                 | 'CHIPR2725'    | ''          | ''            | '20200609'
 '0.0003'     | '1%'      | '4W'     | '2725LF'  | 'EMPTY'  | 'CS0000FFT10'(!)        = 'End of Design' | 'Comp-Approve'     | 'CS0000FFT10'           | 'R2725XA'           | '(SMR2725AW)'                  | '0.0003'  | '1%'    | '4W'     | 'IO'       | 'RES CHIP 0.0003 4W +-1%(2725)ERO'                 | 'CHIPR2725'    | ''          | ''            | '20200609'
 '0.0003'     | '1%'      | '4W'     | '2725LF'  | 'CHIP'   | 'CS0000FFT09'(!)        = ''              | ''                 | 'CS0000FFT09'           | 'R2725'             | '(SMR2725AW)'                  | '0.0003'  | '1%'    | '4W'     | 'DISCRETE' | 'RES CHIP 0.0003 4W +-1%(2725)RLC'                 | 'CHIPR2725'    | ''          | ''            | '20200609'
 '0.0003'     | '1%'      | '4W'     | '2725LF'  | 'EMPTY'  | 'CS0000FFT09'(!)        = ''              | ''                 | 'CS0000FFT09'           | 'R2725'             | '(SMR2725AW)'                  | '0.0003'  | '1%'    | '4W'     | 'IO'       | 'RES CHIP 0.0003 4W +-1%(2725)RLC'                 | 'CHIPR2725'    | ''          | ''            | '20200609'
 '4.64K'      | '1%'      | '1/16W'  | '0402LF'  | 'CHIP'   | 'CS24642FB01'(!)        = 'End of Design' | 'Comp-Approve'     | 'CS24642FB01'           | 'R0402'             | '(R0402-0201)'                 | '4.64K'   | '1%'    | '1/16W'  | 'DISCRETE' | 'RES CHIP 4.64K 1/16W +-1%(0402)EF'                | 'CHIPR0402'    | ''          | ''            | '20200609'
 '4.64K'      | '1%'      | '1/16W'  | '0402LF'  | 'EMPTY'  | 'CS24642FB01'(!)        = 'End of Design' | 'Comp-Approve'     | 'CS24642FB01'           | 'R0402'             | '(R0402-0201)'                 | '4.64K'   | '1%'    | '1/16W'  | 'IO'       | 'RES CHIP 4.64K 1/16W +-1%(0402)EF'                | 'CHIPR0402'    | ''          | ''            | '20200609'
 '7.15K'      | '1%'      | '1/16W'  | '0402LF'  | 'CHIP'   | 'CS27152FB03'(!)        = 'End of Design' | 'Comp-Approve'     | 'CS27152FB03'           | 'R0402'             | '(R0402-0201)'                 | '7.15K'   | '1%'    | '1/16W'  | 'DISCRETE' | 'RES CHIP 7.15K 1/16W +-1%(0402)EF'                | 'CHIPR0402'    | ''          | ''            | '20200609'
 '7.15K'      | '1%'      | '1/16W'  | '0402LF'  | 'EMPTY'  | 'CS27152FB03'(!)        = 'End of Design' | 'Comp-Approve'     | 'CS27152FB03'           | 'R0402'             | '(R0402-0201)'                 | '7.15K'   | '1%'    | '1/16W'  | 'IO'       | 'RES CHIP 7.15K 1/16W +-1%(0402)EF'                | 'CHIPR0402'    | ''          | ''            | '20200609'
 '100'        | '5%'      | '1/10W'  | '0603LF'  | 'CHIP'   | 'CS11003J903'(!)        = ''              | ''                 | 'CS11003J903'           | 'R0603_H24'         | '(SMR0603AW)'                  | '100'     | '5%'    | '1/10W'  | 'DISCRETE' | 'RES CHIP 100 1/10W +-5%(0603)EF'                  | 'CHIPR0603'    | ''          | ''            | '20200609'
 '100'        | '5%'      | '1/10W'  | '0603LF'  | 'EMPTY'  | 'CS11003J903'(!)        = ''              | ''                 | 'CS11003J903'           | 'R0603_H24'         | '(SMR0603AW)'                  | '100'     | '5%'    | '1/10W'  | 'IO'       | 'RES CHIP 100 1/10W +-5%(0603)EF'                  | 'CHIPR0603'    | ''          | ''            | '20200609'
 '6.49K'      | '1%'      | '1/16W'  | '0402LF'  | 'CHIP'   | 'CS26492FB06'(!)        = 'End of Design' | 'Comp-Approve'     | 'CS26492FB06'           | 'R0402'             | '(R0402-0201)'                 | '6.49K'   | '1%'    | '1/16W'  | 'DISCRETE' | 'RES CHIP 6.49K 1/16W +-1%(0402)EF'                | 'CHIPR0402'    | ''          | ''            | '20200611'
 '6.49K'      | '1%'      | '1/16W'  | '0402LF'  | 'EMPTY'  | 'CS26492FB06'(!)        = 'End of Design' | 'Comp-Approve'     | 'CS26492FB06'           | 'R0402'             | '(R0402-0201)'                 | '6.49K'   | '1%'    | '1/16W'  | 'IO'       | 'RES CHIP 6.49K 1/16W +-1%(0402)EF'                | 'CHIPR0402'    | ''          | ''            | '20200611'
 '16.9K'      | '1%'      | '1/16W'  | '0402LF'  | 'CHIP'   | 'CS31692FB03'(!)        = 'End of Design' | 'Comp-Approve'     | 'CS31692FB03'           | 'R0402'             | '(R0402-0201)'                 | '16.9K'   | '1%'    | '1/16W'  | 'DISCRETE' | 'RES CHIP 16.9K 1/16W +-1%(0402)EF'                | 'CHIPR0402'    | ''          | ''            | '20200615'
 '16.9K'      | '1%'      | '1/16W'  | '0402LF'  | 'EMPTY'  | 'CS31692FB03'(!)        = 'End of Design' | 'Comp-Approve'     | 'CS31692FB03'           | 'R0402'             | '(R0402-0201)'                 | '16.9K'   | '1%'    | '1/16W'  | 'IO'       | 'RES CHIP 16.9K 1/16W +-1%(0402)EF'                | 'CHIPR0402'    | ''          | ''            | '20200615'
 '5.1'        | '1%'      | '1/16W'  | '0402LF'  | 'CHIP'   | 'CS-5102FB00'(!)        = 'End of Design' | 'Comp-Approve'     | 'CS-5102FB00'           | 'R0402'             | '(R0402-0201)'                 | '5.1'     | '1%'    | '1/16W'  | 'DISCRETE' | 'RES CHIP 5.1 1/16W +-1%(0402)'                    | 'CHIPR0402'    | ''          | ''            | '20200707'
 '5.1'        | '1%'      | '1/16W'  | '0402LF'  | 'EMPTY'  | 'CS-5102FB00'(!)        = 'End of Design' | 'Comp-Approve'     | 'CS-5102FB00'           | 'R0402'             | '(R0402-0201)'                 | '5.1'     | '1%'    | '1/16W'  | 'IO'       | 'RES CHIP 5.1 1/16W +-1%(0402)'                    | 'CHIPR0402'    | ''          | ''            | '20200707'
 '1'          | '1%'      | '1/4W'   | '0603LF'  | 'CHIP'   | 'CS-1006F900'(!)        = ''              | ''                 | 'CS-1006F900'           | 'R0603'             | '(SMR0603AW)'                  | '1'       | '1%'    | '1/4W'   | 'DISCRETE' | 'RES CHIP 1 1/4W+-1%(0603)SR'                      | 'CHIPR0603'    | ''          | ''            | '20200707'
 '1'          | '1%'      | '1/4W'   | '0603LF'  | 'EMPTY'  | 'CS-1006F900'(!)        = ''              | ''                 | 'CS-1006F900'           | 'R0603'             | '(SMR0603AW)'                  | '1'       | '1%'    | '1/4W'   | 'IO'       | 'RES CHIP 1 1/4W+-1%(0603)SR'                      | 'CHIPR0603'    | ''          | ''            | '20200707'
 '820'        | '1%'      | '1/16W'  | '0402LF'  | 'CHIP'   | 'CS18202FB00'(!)        = 'End of Design' | 'Comp-Approve'     | 'CS18202FB00'           | 'R0402'             | '(R0402-0201)'                 | '820'     | '1%'    | '1/16W'  | 'DISCRETE' | 'RES CHIP 820 1/16W +-1%(0402)'                    | 'CHIPR0402'    | ''          | ''            | '20200715'
 '820'        | '1%'      | '1/16W'  | '0402LF'  | 'EMPTY'  | 'CS18202FB00'(!)        = 'End of Design' | 'Comp-Approve'     | 'CS18202FB00'           | 'R0402'             | '(R0402-0201)'                 | '820'     | '1%'    | '1/16W'  | 'IO'       | 'RES CHIP 820 1/16W +-1%(0402)'                    | 'CHIPR0402'    | ''          | ''            | '20200715'
 '1'          | '5%'      | '1/2W'   | '1206LF'  | 'CHIP'   | 'CS-1007J200'(!)        = ''              | ''                 | 'CS-1007J200'           | 'R1206XN'           | '(SMR1206AW)'                  | '1'       | '5%'    | '1/2W'   | 'DISCRETE' | 'RES CHIP 1 1/2W+-5%(1206)SR'                      | 'CHIPR1206'    | ''          | ''            | '20200715'
 '1'          | '5%'      | '1/2W'   | '1206LF'  | 'EMPTY'  | 'CS-1007J200'(!)        = ''              | ''                 | 'CS-1007J200'           | 'R1206XN'           | '(SMR1206AW)'                  | '1'       | '5%'    | '1/2W'   | 'IO'       | 'RES CHIP 1 1/2W+-5%(1206)SR'                      | 'CHIPR1206'    | ''          | ''            | '20200715'
 '34.8K'      | '1%'      | '1/16W'  | '0402LF'  | 'CHIP'   | 'CS33482FB04'(!)        = ''              | ''                 | 'CS33482FB04'           | 'R0402'             | '(R0402-0201)'                 | '34.8K'   | '1%'    | '1/16W'  | 'DISCRETE' | 'RES CHIP 34.8K 1/16W +-1%(0402)EF'                | 'CHIPR0402'    | ''          | ''            | '20200728'
 '34.8K'      | '1%'      | '1/16W'  | '0402LF'  | 'EMPTY'  | 'CS33482FB04'(!)        = ''              | ''                 | 'CS33482FB04'           | 'R0402'             | '(R0402-0201)'                 | '34.8K'   | '1%'    | '1/16W'  | 'IO'       | 'RES CHIP 34.8K 1/16W +-1%(0402)EF'                | 'CHIPR0402'    | ''          | ''            | '20200728'
 '0.68'       | '1%'      | '1/10W'  | '0603LF'  | 'CHIP'   | 'CS+6803F900'(!)        = ''              | ''                 | 'CS+6803F900'           | 'R0603_H24'         | '(SMR0603AW)'                  | '0.68'    | '1%'    | '1/10W'  | 'DISCRETE' | 'RES CHIP 0.68 1/10W+-1%(0603)EF'                  | 'CHIPR0603'    | ''          | ''            | '20200803'
 '0.68'       | '1%'      | '1/10W'  | '0603LF'  | 'EMPTY'  | 'CS+6803F900'(!)        = ''              | ''                 | 'CS+6803F900'           | 'R0603_H24'         | '(SMR0603AW)'                  | '0.68'    | '1%'    | '1/10W'  | 'IO'       | 'RES CHIP 0.68 1/10W+-1%(0603)EF'                  | 'CHIPR0603'    | ''          | ''            | '20200803'
 '24K'        | '1%'      | '1/10W'  | '0603LF'  | 'CHIP'   | 'CS32403F911'(!)        = 'End of Design' | 'Comp-Approve'     | 'CS32403F911'           | 'R0603'             | '(SMR0603AW)'                  | '24K'     | '1%'    | '1/10W'  | 'DISCRETE' | 'RES CHIP 24K 1/10W +-1%(0603)'                    | 'CHIPR0603'    | ''          | ''            | '20200810'
 '24K'        | '1%'      | '1/10W'  | '0603LF'  | 'EMPTY'  | 'CS32403F911'(!)        = 'End of Design' | 'Comp-Approve'     | 'CS32403F911'           | 'R0603'             | '(SMR0603AW)'                  | '24K'     | '1%'    | '1/10W'  | 'IO'       | 'RES CHIP 24K 1/10W +-1%(0603)'                    | 'CHIPR0603'    | ''          | ''            | '20200810'
 '1.1K'       | '1%'      | '1/16W'  | '0402LF'  | 'CHIP'   | 'CS21102FB04'(!)        = 'End of Design' | 'Comp-Approve'     | 'CS21102FB04'           | 'R0402'             | '(R0402-0201)'                 | '1.1K'    | '1%'    | '1/16W'  | 'DISCRETE' | 'RES CHIP 1.1K 1/16W +-1% (0402)EF'                | 'CHIPR0402'    | ''          | ''            | '20200810'
 '1.1K'       | '1%'      | '1/16W'  | '0402LF'  | 'EMPTY'  | 'CS21102FB04'(!)        = 'End of Design' | 'Comp-Approve'     | 'CS21102FB04'           | 'R0402'             | '(R0402-0201)'                 | '1.1K'    | '1%'    | '1/16W'  | 'IO'       | 'RES CHIP 1.1K 1/16W +-1% (0402)EF'                | 'CHIPR0402'    | ''          | ''            | '20200810'
 '49.9'       | '1%'      | '1/4W'   | '1206LF'  | 'CHIP'   | 'CS04996F200'(!)        = ''              | ''                 | 'CS04996F200'           | 'R1206XJ'           | '(SMR1206AW)'                  | '49.9'    | '1%'    | '1/4W'   | 'DISCRETE' | 'RES CHIP 49.9 1/4W+-1%(1206)'                     | 'CHIPR1206'    | ''          | ''            | '20200811'
 '49.9'       | '1%'      | '1/4W'   | '1206LF'  | 'EMPTY'  | 'CS04996F200'(!)        = ''              | ''                 | 'CS04996F200'           | 'R1206XJ'           | '(SMR1206AW)'                  | '49.9'    | '1%'    | '1/4W'   | 'IO'       | 'RES CHIP 49.9 1/4W+-1%(1206)'                     | 'CHIPR1206'    | ''          | ''            | '20200811'
 '330'        | '1%'      | '1/8W'   | '0805LF'  | 'CHIP'   | 'CS13304FA00'(!)        = ''              | ''                 | 'CS13304FA00'           | 'R0805_H26'         | '(SMR0805AW)'                  | '330'     | '1%'    | '1/8W'   | 'DISCRETE' | 'RES CHIP 330 1/8W +-1%(0805)'                     | 'CHIPR0805'    | ''          | ''            | '20200811'
 '330'        | '1%'      | '1/8W'   | '0805LF'  | 'EMPTY'  | 'CS13304FA00'(!)        = ''              | ''                 | 'CS13304FA00'           | 'R0805_H26'         | '(SMR0805AW)'                  | '330'     | '1%'    | '1/8W'   | 'IO'       | 'RES CHIP 330 1/8W +-1%(0805)'                     | 'CHIPR0805'    | ''          | ''            | '20200811'
 '68K'        | '1%'      | '1/10W'  | '0603LF'  | 'CHIP'   | 'CS36803F917'(!)        = 'End of Design' | 'Comp-Approve'     | 'CS36803F917'           | 'R0603'             | '(SMR0603AW)'                  | '68K'     | '1%'    | '1/10W'  | 'DISCRETE' | 'RES CHIP 68K 1/10W +-1%(0603)'                    | 'CHIPR0603'    | ''          | ''            | '20200811'
 '68K'        | '1%'      | '1/10W'  | '0603LF'  | 'EMPTY'  | 'CS36803F917'(!)        = 'End of Design' | 'Comp-Approve'     | 'CS36803F917'           | 'R0603'             | '(SMR0603AW)'                  | '68K'     | '1%'    | '1/10W'  | 'IO'       | 'RES CHIP 68K 1/10W +-1%(0603)'                    | 'CHIPR0603'    | ''          | ''            | '20200811'
 '240K'       | '1%'      | '1/10W'  | '0603LF'  | 'CHIP'   | 'CS42403F913'(!)        = 'End of Design' | 'Comp-Approve'     | 'CS42403F913'           | 'R0603'             | '(SMR0603AW)'                  | '240K'    | '1%'    | '1/10W'  | 'DISCRETE' | 'RESISTOR CHIP 240K 1/10W,+-1%(0603)'              | 'CHIPR0603'    | ''          | ''            | '20200811'
 '240K'       | '1%'      | '1/10W'  | '0603LF'  | 'EMPTY'  | 'CS42403F913'(!)        = 'End of Design' | 'Comp-Approve'     | 'CS42403F913'           | 'R0603'             | '(SMR0603AW)'                  | '240K'    | '1%'    | '1/10W'  | 'IO'       | 'RESISTOR CHIP 240K 1/10W,+-1%(0603)'              | 'CHIPR0603'    | ''          | ''            | '20200811'
 '604'        | '1%'      | '1/4W'   | '1206LF'  | 'CHIP'   | 'CS16046F200'(!)        = ''              | ''                 | 'CS16046F200'           | 'R1206XF'           | '(SMR1206AW)'                  | '604'     | '1%'    | '1/4W'   | 'DISCRETE' | 'RES CHIP 604 1/4W +-1%(1206)'                     | 'CHIPR1206'    | ''          | ''            | '20200812'
 '604'        | '1%'      | '1/4W'   | '1206LF'  | 'EMPTY'  | 'CS16046F200'(!)        = ''              | ''                 | 'CS16046F200'           | 'R1206XF'           | '(SMR1206AW)'                  | '604'     | '1%'    | '1/4W'   | 'IO'       | 'RES CHIP 604 1/4W +-1%(1206)'                     | 'CHIPR1206'    | ''          | ''            | '20200812'
 '0.0005'     | '1%'      | '3W'     | '2512LF'  | 'CHIP'   | 'CS0000DFR02'(!)        = 'End of Design' | 'Comp-Approve'     | 'CS0000DFR02'           | 'R2512XG'           | '(SMR2512AW)'                  | '0.0005'  | '1%'    | '3W'     | 'DISCRETE' | 'RES CHIP 0.0005 3W +-1%(2512)EF'                  | 'CHIPR2512'    | ''          | ''            | '20200826'
 '0.0005'     | '1%'      | '3W'     | '2512LF'  | 'EMPTY'  | 'CS0000DFR02'(!)        = 'End of Design' | 'Comp-Approve'     | 'CS0000DFR02'           | 'R2512XG'           | '(SMR2512AW)'                  | '0.0005'  | '1%'    | '3W'     | 'IO'       | 'RES CHIP 0.0005 3W +-1%(2512)EF'                  | 'CHIPR2512'    | ''          | ''            | '20200826'
 '0.1'        | '1%'      | '1/8W'   | '0805LF'  | 'CHIP'   | 'CS+1004FA01'(!)        = ''              | ''                 | 'CS+1004FA01'           | 'R0805'             | '(SMR0805AW)'                  | '0.1'     | '1%'    | '1/8W'   | 'DISCRETE' | 'RES CHIP 0.1 1/8W +-1%(0805)'                     | 'CHIPR0805'    | ''          | ''            | '20200909'
 '0.1'        | '1%'      | '1/8W'   | '0805LF'  | 'EMPTY'  | 'CS+1004FA01'(!)        = ''              | ''                 | 'CS+1004FA01'           | 'R0805'             | '(SMR0805AW)'                  | '0.1'     | '1%'    | '1/8W'   | 'IO'       | 'RES CHIP 0.1 1/8W +-1%(0805)'                     | 'CHIPR0805'    | ''          | ''            | '20200909'
 '100'        | '5%'      | '1/2W'   | '1206LF'  | 'CHIP'   | 'CS11007J200'(!)        = ''              | ''                 | 'CS11007J200'           | 'R1206XN'           | '(SMR1206AW)'                  | '100'     | '5%'    | '1/2W'   | 'DISCRETE' | 'RES CHIP 100 1/2W+-5%(1206)SR'                    | 'CHIPR1206'    | ''          | ''            | '20200909'
 '100'        | '5%'      | '1/2W'   | '1206LF'  | 'EMPTY'  | 'CS11007J200'(!)        = ''              | ''                 | 'CS11007J200'           | 'R1206XN'           | '(SMR1206AW)'                  | '100'     | '5%'    | '1/2W'   | 'IO'       | 'RES CHIP 100 1/2W+-5%(1206)SR'                    | 'CHIPR1206'    | ''          | ''            | '20200909'
 '10'         | '0.1%'    | '1/16W'  | '0402LF'  | 'CHIP'   | 'CS01002BB00'(!)        = ''              | ''                 | 'CS01002BB00'           | 'R0402'             | '(R0402-0201)'                 | '10'      | '0.1%'  | '1/16W'  | 'DISCRETE' | 'RES CHIP 10 1/16W +-0.1%(0402)'                   | 'CHIPR0402'    | ''          | ''            | '20200915'
 '10'         | '0.1%'    | '1/16W'  | '0402LF'  | 'EMPTY'  | 'CS01002BB00'(!)        = ''              | ''                 | 'CS01002BB00'           | 'R0402'             | '(R0402-0201)'                 | '10'      | '0.1%'  | '1/16W'  | 'IO'       | 'RES CHIP 10 1/16W +-0.1%(0402)'                   | 'CHIPR0402'    | ''          | ''            | '20200915'
 '56K'        | '0.5%'    | '1/16W'  | '0402LF'  | 'CHIP'   | 'CS35602DB00'(!)        = ''              | ''                 | 'CS35602DB00'           | 'R0402'             | '(R0402-0201)'                 | '56K'     | '0.5%'  | '1/16W'  | 'DISCRETE' | 'RES CHIP 56K 1/16W +-0.5%(0402)'                  | 'CHIPR0402'    | ''          | ''            | '20200915'
 '56K'        | '0.5%'    | '1/16W'  | '0402LF'  | 'EMPTY'  | 'CS35602DB00'(!)        = ''              | ''                 | 'CS35602DB00'           | 'R0402'             | '(R0402-0201)'                 | '56K'     | '0.5%'  | '1/16W'  | 'IO'       | 'RES CHIP 56K 1/16W +-0.5%(0402)'                  | 'CHIPR0402'    | ''          | ''            | '20200915'
 '2.4K'       | '5%'      | '1/16W'  | '0402LF'  | 'CHIP'   | 'CS22402JB15'(!)        = 'End of Design' | 'Comp-Approve'     | 'CS22402JB15'           | 'R0402'             | '(R0402-0201)'                 | '2.4K'    | '5%'    | '1/16W'  | 'DISCRETE' | 'RES CHIP 2.4K 1/16W+-5%(0402)'                    | 'CHIPR0402'    | ''          | ''            | '20200917'
 '2.4K'       | '5%'      | '1/16W'  | '0402LF'  | 'EMPTY'  | 'CS22402JB15'(!)        = 'End of Design' | 'Comp-Approve'     | 'CS22402JB15'           | 'R0402'             | '(R0402-0201)'                 | '2.4K'    | '5%'    | '1/16W'  | 'IO'       | 'RES CHIP 2.4K 1/16W+-5%(0402)'                    | 'CHIPR0402'    | ''          | ''            | '20200917'
 '0.0005'     | '1%'      | '3W'     | '2512LF'  | 'CHIP'   | 'CS0000DFR17'(!)        = ''              | ''                 | 'CS0000DFR17'           | 'R2512XX'           | '(SMR2512AW)'                  | '0.0005'  | '1%'    | '3W'     | 'DISCRETE' | 'RES CHIP 0.0005 3W +-1%(2512)ERO'                 | 'CHIPR2512'    | ''          | ''            | '20200917'
 '0.0005'     | '1%'      | '3W'     | '2512LF'  | 'EMPTY'  | 'CS0000DFR17'(!)        = ''              | ''                 | 'CS0000DFR17'           | 'R2512XX'           | '(SMR2512AW)'                  | '0.0005'  | '1%'    | '3W'     | 'IO'       | 'RES CHIP 0.0005 3W +-1%(2512)ERO'                 | 'CHIPR2512'    | ''          | ''            | '20200917'
 '100'        | '5%'      | '1/4W'   | '0805LF'  | 'CHIP'   | 'CS11006JA00'(!)        = ''              | ''                 | 'CS11006JA00'           | 'R0805_H26'         | '(SMR0805AW)'                  | '100'     | '5%'    | '1/4W'   | 'DISCRETE' | 'RES CHIP 100 1/4W+-5%(0805)SR'                    | 'CHIPR0805'    | ''          | ''            | '20200921'
 '100'        | '5%'      | '1/4W'   | '0805LF'  | 'EMPTY'  | 'CS11006JA00'(!)        = ''              | ''                 | 'CS11006JA00'           | 'R0805_H26'         | '(SMR0805AW)'                  | '100'     | '5%'    | '1/4W'   | 'IO'       | 'RES CHIP 100 1/4W+-5%(0805)SR'                    | 'CHIPR0805'    | ''          | ''            | '20200921'
 '14.3K'      | '0.1%'    | '1/16W'  | '0402LF'  | 'CHIP'   | 'CS31432BB00'(!)        = ''              | ''                 | 'CS31432BB00'           | 'R0402'             | '(R0402-0201)'                 | '14.3K'   | '0.1%'  | '1/16W'  | 'DISCRETE' | 'RES CHIP 14.3K 1/16W +-0.1%(0402)'                | 'CHIPR0402'    | ''          | ''            | '20200930'
 '14.3K'      | '0.1%'    | '1/16W'  | '0402LF'  | 'EMPTY'  | 'CS31432BB00'(!)        = ''              | ''                 | 'CS31432BB00'           | 'R0402'             | '(R0402-0201)'                 | '14.3K'   | '0.1%'  | '1/16W'  | 'IO'       | 'RES CHIP 14.3K 1/16W +-0.1%(0402)'                | 'CHIPR0402'    | ''          | ''            | '20200930'
 '35.7K'      | '0.1%'    | '1/16W'  | '0402LF'  | 'CHIP'   | 'CS33572BB00'(!)        = ''              | ''                 | 'CS33572BB00'           | 'R0402'             | '(R0402-0201)'                 | '35.7K'   | '0.1%'  | '1/16W'  | 'DISCRETE' | 'RES CHIP 35.7K 1/16W  +-0.1%(0402)'               | 'CHIPR0402'    | ''          | ''            | '20201005'
 '35.7K'      | '0.1%'    | '1/16W'  | '0402LF'  | 'EMPTY'  | 'CS33572BB00'(!)        = ''              | ''                 | 'CS33572BB00'           | 'R0402'             | '(R0402-0201)'                 | '35.7K'   | '0.1%'  | '1/16W'  | 'IO'       | 'RES CHIP 35.7K 1/16W  +-0.1%(0402)'               | 'CHIPR0402'    | ''          | ''            | '20201005'
 '332K'       | '1%'      | '1/4W'   | '1206LF'  | 'CHIP'   | 'CS43326F200'(!)        = ''              | ''                 | 'CS43326F200'           | 'R1206XI'           | '(SMR1206AW)'                  | '332K'    | '1%'    | '1/4W'   | 'DISCRETE' | 'RES CHIP 332K 1/4W +-1%(1206)'                    | 'CHIPR1206'    | ''          | ''            | '20201006'
 '332K'       | '1%'      | '1/4W'   | '1206LF'  | 'EMPTY'  | 'CS43326F200'(!)        = ''              | ''                 | 'CS43326F200'           | 'R1206XI'           | '(SMR1206AW)'                  | '332K'    | '1%'    | '1/4W'   | 'IO'       | 'RES CHIP 332K 1/4W +-1%(1206)'                    | 'CHIPR1206'    | ''          | ''            | '20201006'
 '30.1K'      | '0.1%'    | '1/16W'  | '0402LF'  | 'CHIP'   | 'CS33012BB00'(!)        = 'End of Design' | 'Comp-Approve'     | 'CS33012BB00'           | 'R0402'             | '(R0402-0201)'                 | '30.1K'   | '0.1%'  | '1/16W'  | 'DISCRETE' | 'RES CHIP 30.1K 1/16W +-0.1% (0402)'               | 'CHIPR0402'    | ''          | ''            | '20201008'
 '30.1K'      | '0.1%'    | '1/16W'  | '0402LF'  | 'EMPTY'  | 'CS33012BB00'(!)        = 'End of Design' | 'Comp-Approve'     | 'CS33012BB00'           | 'R0402'             | '(R0402-0201)'                 | '30.1K'   | '0.1%'  | '1/16W'  | 'IO'       | 'RES CHIP 30.1K 1/16W +-0.1% (0402)'               | 'CHIPR0402'    | ''          | ''            | '20201008'
 '3.32K'      | '0.1%'    | '1/16W'  | '0402LF'  | 'CHIP'   | 'CS23322BB08'(!)        = 'End of Design' | 'Comp-Approve'     | 'CS23322BB08'           | 'R0402'             | '(R0402-0201)'                 | '3.32K'   | '0.1%'  | '1/16W'  | 'DISCRETE' | 'RES CHIP 3.32K 1/16W +-0.1% (0402)'               | 'CHIPR0402'    | ''          | ''            | '20201008'
 '3.32K'      | '0.1%'    | '1/16W'  | '0402LF'  | 'EMPTY'  | 'CS23322BB08'(!)        = 'End of Design' | 'Comp-Approve'     | 'CS23322BB08'           | 'R0402'             | '(R0402-0201)'                 | '3.32K'   | '0.1%'  | '1/16W'  | 'IO'       | 'RES CHIP 3.32K 1/16W +-0.1% (0402)'               | 'CHIPR0402'    | ''          | ''            | '20201008'
 '34.8K'      | '0.1%'    | '1/16W'  | '0402LF'  | 'CHIP'   | 'CS33482BB01'(!)        = ''              | ''                 | 'CS33482BB01'           | 'R0402'             | '(R0402-0201)'                 | '34.8K'   | '0.1%'  | '1/16W'  | 'DISCRETE' | 'RES CHIP 34.8K 1/16W +-0.1%(0402)'                | 'CHIPR0402'    | ''          | ''            | '20201110'
 '34.8K'      | '0.1%'    | '1/16W'  | '0402LF'  | 'EMPTY'  | 'CS33482BB01'(!)        = ''              | ''                 | 'CS33482BB01'           | 'R0402'             | '(R0402-0201)'                 | '34.8K'   | '0.1%'  | '1/16W'  | 'IO'       | 'RES CHIP 34.8K 1/16W +-0.1%(0402)'                | 'CHIPR0402'    | ''          | ''            | '20201110'
 '3.57K'      | '0.1%'    | '1/16W'  | '0402LF'  | 'CHIP'   | 'CS23572BB05'(!)        = ''              | ''                 | 'CS23572BB05'           | 'R0402'             | '(R0402-0201)'                 | '3.57K'   | '0.1%'  | '1/16W'  | 'DISCRETE' | 'RES CHIP 3.57K 1/16W +-0.1%(0402)'                | 'CHIPR0402'    | ''          | ''            | '20201110'
 '3.57K'      | '0.1%'    | '1/16W'  | '0402LF'  | 'EMPTY'  | 'CS23572BB05'(!)        = ''              | ''                 | 'CS23572BB05'           | 'R0402'             | '(R0402-0201)'                 | '3.57K'   | '0.1%'  | '1/16W'  | 'IO'       | 'RES CHIP 3.57K 1/16W +-0.1%(0402)'                | 'CHIPR0402'    | ''          | ''            | '20201110'
 '182'        | '1%'      | '1/16W'  | '0402LF'  | 'CHIP'   | 'CS11822FB02'(!)        = ''              | ''                 | 'CS11822FB02'           | 'R0402'             | '(R0402-0201)'                 | '182'     | '1%'    | '1/16W'  | 'DISCRETE' | 'RES CHIP 182 1/16W +-1%(0402)EF'                  | 'CHIPR0402'    | ''          | ''            | '20201112'
 '182'        | '1%'      | '1/16W'  | '0402LF'  | 'EMPTY'  | 'CS11822FB02'(!)        = ''              | ''                 | 'CS11822FB02'           | 'R0402'             | '(R0402-0201)'                 | '182'     | '1%'    | '1/16W'  | 'IO'       | 'RES CHIP 182 1/16W +-1%(0402)EF'                  | 'CHIPR0402'    | ''          | ''            | '20201112'
 '8.06K'      | '1%'      | '1/16W'  | '0402LF'  | 'CHIP'   | 'CS28062FB03'(!)        = 'End of Design' | 'Comp-Approve'     | 'CS28062FB03'           | 'R0402'             | '(R0402-0201)'                 | '8.06K'   | '1%'    | '1/16W'  | 'DISCRETE' | 'RES CHIP 8.06K 1/16W +-1%(0402)EF'                | 'CHIPR0402'    | ''          | ''            | '20201118'
 '8.06K'      | '1%'      | '1/16W'  | '0402LF'  | 'EMPTY'  | 'CS28062FB03'(!)        = 'End of Design' | 'Comp-Approve'     | 'CS28062FB03'           | 'R0402'             | '(R0402-0201)'                 | '8.06K'   | '1%'    | '1/16W'  | 'IO'       | 'RES CHIP 8.06K 1/16W +-1%(0402)EF'                | 'CHIPR0402'    | ''          | ''            | '20201118'
 '162'        | '1%'      | '1/16W'  | '0402LF'  | 'CHIP'   | 'CS11622FB15'(!)        = 'End of Design' | 'Comp-Approve'     | 'CS11622FB15'           | 'R0402'             | '(R0402-0201)'                 | '162'     | '1%'    | '1/16W'  | 'DISCRETE' | 'RES CHIP 162 1/16W +-1%(0402)'                    | 'CHIPR0402'    | ''          | ''            | '20201120'
 '162'        | '1%'      | '1/16W'  | '0402LF'  | 'EMPTY'  | 'CS11622FB15'(!)        = 'End of Design' | 'Comp-Approve'     | 'CS11622FB15'           | 'R0402'             | '(R0402-0201)'                 | '162'     | '1%'    | '1/16W'  | 'IO'       | 'RES CHIP 162 1/16W +-1%(0402)'                    | 'CHIPR0402'    | ''          | ''            | '20201120'
 '8.2'        | '1%'      | '1/16W'  | '0402LF'  | 'CHIP'   | 'CS-8202FB00'(!)        = ''              | ''                 | 'CS-8202FB00'           | 'R0402'             | '(R0402-0201)'                 | '8.2'     | '1%'    | '1/16W'  | 'DISCRETE' | 'RES CHIP 8.2 1/16W +-1%(0402)'                    | 'CHIPR0402'    | ''          | ''            | '20201123'
 '8.2'        | '1%'      | '1/16W'  | '0402LF'  | 'EMPTY'  | 'CS-8202FB00'(!)        = ''              | ''                 | 'CS-8202FB00'           | 'R0402'             | '(R0402-0201)'                 | '8.2'     | '1%'    | '1/16W'  | 'IO'       | 'RES CHIP 8.2 1/16W +-1%(0402)'                    | 'CHIPR0402'    | ''          | ''            | '20201123'
 '0.2'        | '1%'      | '1/10W'  | '0603LF'  | 'CHIP'   | 'CS+2003F900'(!)        = ''              | ''                 | 'CS+2003F900'           | 'R0603_H24'         | '(SMR0603AW)'                  | '0.2'     | '1%'    | '1/10W'  | 'DISCRETE' | 'RES CHIP 0.2 1/10W +-1%(0603)EF'                  | 'CHIPR0603'    | ''          | ''            | '20201201'
 '0.2'        | '1%'      | '1/10W'  | '0603LF'  | 'EMPTY'  | 'CS+2003F900'(!)        = ''              | ''                 | 'CS+2003F900'           | 'R0603_H24'         | '(SMR0603AW)'                  | '0.2'     | '1%'    | '1/10W'  | 'IO'       | 'RES CHIP 0.2 1/10W +-1%(0603)EF'                  | 'CHIPR0603'    | ''          | ''            | '20201201'
 '9.1K'       | '1%'      | '1/16W'  | '0402LF'  | 'CHIP'   | 'CS29102FB00'(!)        = ''              | ''                 | 'CS29102FB00'           | 'R0402'             | '(R0402-0201)'                 | '9.1K'    | '1%'    | '1/16W'  | 'DISCRETE' | 'RES CHIP 9.1K 1/16W +-1%(0402)EF'                 | 'CHIPR0402'    | ''          | ''            | '20201207'
 '9.1K'       | '1%'      | '1/16W'  | '0402LF'  | 'EMPTY'  | 'CS29102FB00'(!)        = ''              | ''                 | 'CS29102FB00'           | 'R0402'             | '(R0402-0201)'                 | '9.1K'    | '1%'    | '1/16W'  | 'IO'       | 'RES CHIP 9.1K 1/16W +-1%(0402)EF'                 | 'CHIPR0402'    | ''          | ''            | '20201207'
 '3.3K'       | '5%'      | '1/16W'  | '0402LF'  | 'CHIP'   | 'CS23302JB04'(!)        = 'End of Design' | 'Comp-Approve'     | 'CS23302JB04'           | 'R0402'             | '(R0402-0201)'                 | '3.3K'    | '5%'    | '1/16W'  | 'DISCRETE' | 'RES CHIP 3.3K 1/16W +-5%(0402)EF'                 | 'CHIPR0402'    | ''          | ''            | '20201208'
 '3.3K'       | '5%'      | '1/16W'  | '0402LF'  | 'EMPTY'  | 'CS23302JB04'(!)        = 'End of Design' | 'Comp-Approve'     | 'CS23302JB04'           | 'R0402'             | '(R0402-0201)'                 | '3.3K'    | '5%'    | '1/16W'  | 'IO'       | 'RES CHIP 3.3K 1/16W +-5%(0402)EF'                 | 'CHIPR0402'    | ''          | ''            | '20201208'
 '0.15'       | '1%'      | '1W'     | '1206LF'  | 'CHIP'   | 'CS+1508F201'(!)        = ''              | ''                 | 'CS+1508F201'           | 'R1206XP'           | '(SMR1206AW)'                  | '0.15'    | '1%'    | '1W'     | 'DISCRETE' | 'RES CHIP 0.15 1W +-1%(1206)'                      | 'CHIPR1206'    | ''          | ''            | '20201209'
 '0.15'       | '1%'      | '1W'     | '1206LF'  | 'EMPTY'  | 'CS+1508F201'(!)        = ''              | ''                 | 'CS+1508F201'           | 'R1206XP'           | '(SMR1206AW)'                  | '0.15'    | '1%'    | '1W'     | 'IO'       | 'RES CHIP 0.15 1W +-1%(1206)'                      | 'CHIPR1206'    | ''          | ''            | '20201209'
 '6.34K'      | '0.1%'    | '1/16W'  | '0402LF'  | 'CHIP'   | 'CS26342BB00'(!)        = ''              | ''                 | 'CS26342BB00'           | 'R0402'             | '(R0402-0201)'                 | '6.34K'   | '0.1%'  | '1/16W'  | 'DISCRETE' | 'RES CHIP 6.34K 1/16W +-0.1%(0402)'                | 'CHIPR0402'    | ''          | ''            | '20201224'
 '6.34K'      | '0.1%'    | '1/16W'  | '0402LF'  | 'EMPTY'  | 'CS26342BB00'(!)        = ''              | ''                 | 'CS26342BB00'           | 'R0402'             | '(R0402-0201)'                 | '6.34K'   | '0.1%'  | '1/16W'  | 'IO'       | 'RES CHIP 6.34K 1/16W +-0.1%(0402)'                | 'CHIPR0402'    | ''          | ''            | '20201224'
 '9.09K'      | '0.1%'    | '1/16W'  | '0402LF'  | 'CHIP'   | 'CS29092BB01'(!)        = ''              | ''                 | 'CS29092BB01'           | 'R0402'             | '(R0402-0201)'                 | '9.09K'   | '0.1%'  | '1/16W'  | 'DISCRETE' | 'RES CHIP 9.09K 1/16W +-0.1%(0402)'                | 'CHIPR0402'    | ''          | ''            | '20201224'
 '9.09K'      | '0.1%'    | '1/16W'  | '0402LF'  | 'EMPTY'  | 'CS29092BB01'(!)        = ''              | ''                 | 'CS29092BB01'           | 'R0402'             | '(R0402-0201)'                 | '9.09K'   | '0.1%'  | '1/16W'  | 'IO'       | 'RES CHIP 9.09K 1/16W +-0.1%(0402)'                | 'CHIPR0402'    | ''          | ''            | '20201224'
 '2.21K'      | '0.1%'    | '1/16W'  | '0402LF'  | 'CHIP'   | 'CS22212BB01'(!)        = 'End of Design' | 'Comp-Approve'     | 'CS22212BB01'           | 'R0402'             | '(R0402-0201)'                 | '2.21K'   | '0.1%'  | '1/16W'  | 'DISCRETE' | 'RES CHIP 2.21K 1/16W +-0.1%(0402)'                | 'CHIPR0402'    | ''          | ''            | '20201225'
 '2.21K'      | '0.1%'    | '1/16W'  | '0402LF'  | 'EMPTY'  | 'CS22212BB01'(!)        = 'End of Design' | 'Comp-Approve'     | 'CS22212BB01'           | 'R0402'             | '(R0402-0201)'                 | '2.21K'   | '0.1%'  | '1/16W'  | 'IO'       | 'RES CHIP 2.21K 1/16W +-0.1%(0402)'                | 'CHIPR0402'    | ''          | ''            | '20201225'
 '4.32K'      | '0.1%'    | '1/16W'  | '0402LF'  | 'CHIP'   | 'CS24322BB01'(!)        = ''              | ''                 | 'CS24322BB01'           | 'R0402'             | '(R0402-0201)'                 | '4.32K'   | '0.1%'  | '1/16W'  | 'DISCRETE' | 'RES CHIP 4.32K 1/16W +-0.1%(0402)'                | 'CHIPR0402'    | ''          | ''            | '20201225'
 '4.32K'      | '0.1%'    | '1/16W'  | '0402LF'  | 'EMPTY'  | 'CS24322BB01'(!)        = ''              | ''                 | 'CS24322BB01'           | 'R0402'             | '(R0402-0201)'                 | '4.32K'   | '0.1%'  | '1/16W'  | 'IO'       | 'RES CHIP 4.32K 1/16W +-0.1%(0402)'                | 'CHIPR0402'    | ''          | ''            | '20201225'
 '16.5K'      | '0.1%'    | '1/16W'  | '0402LF'  | 'CHIP'   | 'CS31652BB00'(!)        = ''              | ''                 | 'CS31652BB00'           | 'R0402'             | '(R0402-0201)'                 | '16.5K'   | '0.1%'  | '1/16W'  | 'DISCRETE' | 'RES CHIP 16.5K 1/16W +-0.1%(0402)'                | 'CHIPR0402'    | ''          | ''            | '20201225'
 '16.5K'      | '0.1%'    | '1/16W'  | '0402LF'  | 'EMPTY'  | 'CS31652BB00'(!)        = ''              | ''                 | 'CS31652BB00'           | 'R0402'             | '(R0402-0201)'                 | '16.5K'   | '0.1%'  | '1/16W'  | 'IO'       | 'RES CHIP 16.5K 1/16W +-0.1%(0402)'                | 'CHIPR0402'    | ''          | ''            | '20201225'
 '4.12K'      | '0.1%'    | '1/16W'  | '0402LF'  | 'CHIP'   | 'CS24122BB01'(!)        = ''              | ''                 | 'CS24122BB01'           | 'R0402'             | '(R0402-0201)'                 | '4.12K'   | '0.1%'  | '1/16W'  | 'DISCRETE' | 'RES CHIP 4.12K 1/16W  +-0.1%(0402)'               | 'CHIPR0402'    | ''          | ''            | '20201225'
 '4.12K'      | '0.1%'    | '1/16W'  | '0402LF'  | 'EMPTY'  | 'CS24122BB01'(!)        = ''              | ''                 | 'CS24122BB01'           | 'R0402'             | '(R0402-0201)'                 | '4.12K'   | '0.1%'  | '1/16W'  | 'IO'       | 'RES CHIP 4.12K 1/16W  +-0.1%(0402)'               | 'CHIPR0402'    | ''          | ''            | '20201225'
 '2.2'        | '1%'      | '1/2W'   | '1206LF'  | 'CHIP'   | 'CS-2207F200'(!)        = ''              | ''                 | 'CS-2207F200'           | 'R1206XF'           | '(SMR1206AW)'                  | '2.2'     | '1%'    | '1/2W'   | 'DISCRETE' | 'RES CHIP 2.2 1/2W +-1%(1206)'                     | 'CHIPR1206'    | ''          | ''            | '20210105'
 '2.2'        | '1%'      | '1/2W'   | '1206LF'  | 'EMPTY'  | 'CS-2207F200'(!)        = ''              | ''                 | 'CS-2207F200'           | 'R1206XF'           | '(SMR1206AW)'                  | '2.2'     | '1%'    | '1/2W'   | 'IO'       | 'RES CHIP 2.2 1/2W +-1%(1206)'                     | 'CHIPR1206'    | ''          | ''            | '20210105'
 '200'        | '1%'      | '1/8W'   | '0402LF'  | 'CHIP'   | 'CS12004FB00'(!)        = ''              | ''                 | 'CS12004FB00'           | 'R0402'             | '(R0402-0201)'                 | '200'     | '1%'    | '1/8W'   | 'DISCRETE' | 'RES CHIP 200 1/8W +-1%(0402)SR'                   | 'CHIPR0402'    | ''          | ''            | '20210112'
 '200'        | '1%'      | '1/8W'   | '0402LF'  | 'EMPTY'  | 'CS12004FB00'(!)        = ''              | ''                 | 'CS12004FB00'           | 'R0402'             | '(R0402-0201)'                 | '200'     | '1%'    | '1/8W'   | 'IO'       | 'RES CHIP 200 1/8W +-1%(0402)SR'                   | 'CHIPR0402'    | ''          | ''            | '20210112'
 '47K'        | '0.1%'    | '1/16W'  | '0402LF'  | 'CHIP'   | 'CS34702BB03'(!)        = ''              | ''                 | 'CS34702BB03'           | 'R0402'             | '(R0402-0201)'                 | '47K'     | '0.1%'  | '1/16W'  | 'DISCRETE' | 'RES CHIP 47K 1/16W +-0.1%(0402)YGO'               | 'CHIPR0402'    | ''          | ''            | '20210120'
 '47K'        | '0.1%'    | '1/16W'  | '0402LF'  | 'EMPTY'  | 'CS34702BB03'(!)        = ''              | ''                 | 'CS34702BB03'           | 'R0402'             | '(R0402-0201)'                 | '47K'     | '0.1%'  | '1/16W'  | 'IO'       | 'RES CHIP 47K 1/16W +-0.1%(0402)YGO'               | 'CHIPR0402'    | ''          | ''            | '20210120'
 '15K'        | '0.1%'    | '1/16W'  | '0402LF'  | 'CHIP'   | 'CS31502BB01'(!)        = ''              | ''                 | 'CS31502BB01'           | 'R0402'             | '(R0402-0201)'                 | '15K'     | '0.1%'  | '1/16W'  | 'DISCRETE' | 'RES CHIP 15K 1/16W +-0.1%(0402)'                  | 'CHIPR0402'    | ''          | ''            | '20210120'
 '15K'        | '0.1%'    | '1/16W'  | '0402LF'  | 'EMPTY'  | 'CS31502BB01'(!)        = ''              | ''                 | 'CS31502BB01'           | 'R0402'             | '(R0402-0201)'                 | '15K'     | '0.1%'  | '1/16W'  | 'IO'       | 'RES CHIP 15K 1/16W +-0.1%(0402)'                  | 'CHIPR0402'    | ''          | ''            | '20210120'
 '26.1K'      | '0.1%'    | '1/16W'  | '0402LF'  | 'CHIP'   | 'CS32612BB01'(!)        = ''              | ''                 | 'CS32612BB01'           | 'R0402'             | '(R0402-0201)'                 | '26.1K'   | '0.1%'  | '1/16W'  | 'DISCRETE' | 'RES CHIP 26.1K 1/16W +-0.1%(0402)'                | 'CHIPR0402'    | ''          | ''            | '20210121'
 '26.1K'      | '0.1%'    | '1/16W'  | '0402LF'  | 'EMPTY'  | 'CS32612BB01'(!)        = ''              | ''                 | 'CS32612BB01'           | 'R0402'             | '(R0402-0201)'                 | '26.1K'   | '0.1%'  | '1/16W'  | 'IO'       | 'RES CHIP 26.1K 1/16W +-0.1%(0402)'                | 'CHIPR0402'    | ''          | ''            | '20210121'
 '86.6K'      | '0.1%'    | '1/16W'  | '0402LF'  | 'CHIP'   | 'CS38662BB00'(!)        = ''              | ''                 | 'CS38662BB00'           | 'R0402'             | '(R0402-0201)'                 | '86.6K'   | '0.1%'  | '1/16W'  | 'DISCRETE' | 'RES CHIP 86.6K 1/16W +-0.1%(0402)'                | 'CHIPR0402'    | ''          | ''            | '20210121'
 '86.6K'      | '0.1%'    | '1/16W'  | '0402LF'  | 'EMPTY'  | 'CS38662BB00'(!)        = ''              | ''                 | 'CS38662BB00'           | 'R0402'             | '(R0402-0201)'                 | '86.6K'   | '0.1%'  | '1/16W'  | 'IO'       | 'RES CHIP 86.6K 1/16W +-0.1%(0402)'                | 'CHIPR0402'    | ''          | ''            | '20210121'
 '7.32K'      | '0.1%'    | '1/16W'  | '0402LF'  | 'CHIP'   | 'CS27322BB08'(!)        = ''              | ''                 | 'CS27322BB08'           | 'R0402'             | '(R0402-0201)'                 | '7.32K'   | '0.1%'  | '1/16W'  | 'DISCRETE' | 'RES CHIP 7.32K 1/16W +-0.1% (0402)'               | 'CHIPR0402'    | ''          | ''            | '20210121'
 '7.32K'      | '0.1%'    | '1/16W'  | '0402LF'  | 'EMPTY'  | 'CS27322BB08'(!)        = ''              | ''                 | 'CS27322BB08'           | 'R0402'             | '(R0402-0201)'                 | '7.32K'   | '0.1%'  | '1/16W'  | 'IO'       | 'RES CHIP 7.32K 1/16W +-0.1% (0402)'               | 'CHIPR0402'    | ''          | ''            | '20210121'
 '31.6K'      | '0.1%'    | '1/16W'  | '0402LF'  | 'CHIP'   | 'CS33162BB03'(!)        = ''              | ''                 | 'CS33162BB03'           | 'R0402'             | '(R0402-0201)'                 | '31.6K'   | '0.1%'  | '1/16W'  | 'DISCRETE' | 'RES CHIP 31.6K 1/16W +-0.1%(0402)'                | 'CHIPR0402'    | ''          | ''            | '20210122'
 '31.6K'      | '0.1%'    | '1/16W'  | '0402LF'  | 'EMPTY'  | 'CS33162BB03'(!)        = ''              | ''                 | 'CS33162BB03'           | 'R0402'             | '(R0402-0201)'                 | '31.6K'   | '0.1%'  | '1/16W'  | 'IO'       | 'RES CHIP 31.6K 1/16W +-0.1%(0402)'                | 'CHIPR0402'    | ''          | ''            | '20210122'
 '36K'        | '0.1%'    | '1/16W'  | '0402LF'  | 'CHIP'   | 'CS33602BB00'(!)        = 'End of Design' | 'Comp-Approve'     | 'CS33602BB00'           | 'R0402'             | '(R0402-0201)'                 | '36K'     | '0.1%'  | '1/16W'  | 'DISCRETE' | 'RES CHIP 36K 1/16W +-0.1%(0402)'                  | 'CHIPR0402'    | ''          | ''            | '20210122'
 '36K'        | '0.1%'    | '1/16W'  | '0402LF'  | 'EMPTY'  | 'CS33602BB00'(!)        = 'End of Design' | 'Comp-Approve'     | 'CS33602BB00'           | 'R0402'             | '(R0402-0201)'                 | '36K'     | '0.1%'  | '1/16W'  | 'IO'       | 'RES CHIP 36K 1/16W +-0.1%(0402)'                  | 'CHIPR0402'    | ''          | ''            | '20210122'
 '1.15K'      | '0.1%'    | '1/16W'  | '0402LF'  | 'CHIP'   | 'CS21152BB00'(!)        = ''              | ''                 | 'CS21152BB00'           | 'R0402'             | '(R0402-0201)'                 | '1.15K'   | '0.1%'  | '1/16W'  | 'DISCRETE' | 'RES CHIP 1.15K 1/16W +-0.1%(0402)'                | 'CHIPR0402'    | ''          | ''            | '20210302'
 '1.15K'      | '0.1%'    | '1/16W'  | '0402LF'  | 'EMPTY'  | 'CS21152BB00'(!)        = ''              | ''                 | 'CS21152BB00'           | 'R0402'             | '(R0402-0201)'                 | '1.15K'   | '0.1%'  | '1/16W'  | 'IO'       | 'RES CHIP 1.15K 1/16W +-0.1%(0402)'                | 'CHIPR0402'    | ''          | ''            | '20210302'
 '1.02K'      | '0.1%'    | '1/16W'  | '0402LF'  | 'CHIP'   | 'CS21022BB00'(!)        = ''              | ''                 | 'CS21022BB00'           | 'R0402'             | '(R0402-0201)'                 | '1.02K'   | '0.1%'  | '1/16W'  | 'DISCRETE' | 'RES CHIP 1.02K 1/16W +-0.1%(0402)'                | 'CHIPR0402'    | ''          | ''            | '20210303'
 '1.02K'      | '0.1%'    | '1/16W'  | '0402LF'  | 'EMPTY'  | 'CS21022BB00'(!)        = ''              | ''                 | 'CS21022BB00'           | 'R0402'             | '(R0402-0201)'                 | '1.02K'   | '0.1%'  | '1/16W'  | 'IO'       | 'RES CHIP 1.02K 1/16W +-0.1%(0402)'                | 'CHIPR0402'    | ''          | ''            | '20210303'
 '16.2K'      | '0.1%'    | '1/16W'  | '0402LF'  | 'CHIP'   | 'CS31622BB00'(!)        = ''              | ''                 | 'CS31622BB00'           | 'R0402'             | '(R0402-0201)'                 | '16.2K'   | '0.1%'  | '1/16W'  | 'DISCRETE' | 'RES CHIP 16.2K 1/16W 0.1% (0402)'                 | 'CHIPR0402'    | ''          | ''            | '20210309'
 '16.2K'      | '0.1%'    | '1/16W'  | '0402LF'  | 'EMPTY'  | 'CS31622BB00'(!)        = ''              | ''                 | 'CS31622BB00'           | 'R0402'             | '(R0402-0201)'                 | '16.2K'   | '0.1%'  | '1/16W'  | 'IO'       | 'RES CHIP 16.2K 1/16W 0.1% (0402)'                 | 'CHIPR0402'    | ''          | ''            | '20210309'
 '5.76K'      | '0.1%'    | '1/16W'  | '0402LF'  | 'CHIP'   | 'CS25762BB00'(!)        = 'End of Design' | 'Comp-Approve'     | 'CS25762BB00'           | 'R0402'             | '(R0402-0201)'                 | '5.76K'   | '0.1%'  | '1/16W'  | 'DISCRETE' | 'RES CHIP 5.76K 1/16W +-0.1%(0402)'                | 'CHIPR0402'    | ''          | ''            | '20210310'
 '5.76K'      | '0.1%'    | '1/16W'  | '0402LF'  | 'EMPTY'  | 'CS25762BB00'(!)        = 'End of Design' | 'Comp-Approve'     | 'CS25762BB00'           | 'R0402'             | '(R0402-0201)'                 | '5.76K'   | '0.1%'  | '1/16W'  | 'IO'       | 'RES CHIP 5.76K 1/16W +-0.1%(0402)'                | 'CHIPR0402'    | ''          | ''            | '20210310'
 '1'          | '1%'      | '1/4W'   | '0603LF'  | 'CHIP'   | 'CS-1006F903'(!)        = ''              | ''                 | 'CS-1006F903'           | 'R0603'             | '(SMR0603AW)'                  | '1'       | '1%'    | '1/4W'   | 'DISCRETE' | 'RES CHIP 1 1/4W+-1%(0603)SR RLC'                  | 'CHIPR0603'    | ''          | ''            | '20210318'
 '1'          | '1%'      | '1/4W'   | '0603LF'  | 'EMPTY'  | 'CS-1006F903'(!)        = ''              | ''                 | 'CS-1006F903'           | 'R0603'             | '(SMR0603AW)'                  | '1'       | '1%'    | '1/4W'   | 'IO'       | 'RES CHIP 1 1/4W+-1%(0603)SR RLC'                  | 'CHIPR0603'    | ''          | ''            | '20210318'
 '3.3'        | '1%'      | '1/4W'   | '0603LF'  | 'CHIP'   | 'CS-3306F903'(!)        = ''              | ''                 | 'CS-3306F903'           | 'R0603'             | '(SMR0603AW)'                  | '3.3'     | '1%'    | '1/4W'   | 'DISCRETE' | 'RES CHIP 3.3 1/4W+-1%(0603)SR RLC'                | 'CHIPR0603'    | ''          | ''            | '20210318'
 '3.3'        | '1%'      | '1/4W'   | '0603LF'  | 'EMPTY'  | 'CS-3306F903'(!)        = ''              | ''                 | 'CS-3306F903'           | 'R0603'             | '(SMR0603AW)'                  | '3.3'     | '1%'    | '1/4W'   | 'IO'       | 'RES CHIP 3.3 1/4W+-1%(0603)SR RLC'                | 'CHIPR0603'    | ''          | ''            | '20210318'
 '75K'        | '1%'      | '1/10W'  | '0603LF'  | 'CHIP'   | 'CS37503F904'(!)        = ''              | ''                 | 'CS37503F904'           | 'R0603_H24'         | '(SMR0603AW)'                  | '75K'     | '1%'    | '1/10W'  | 'DISCRETE' | 'RES CHIP 75K 1/10W +-1%(0603)WTC'                 | 'CHIPR0603'    | ''          | ''            | '20210330'
 '75K'        | '1%'      | '1/10W'  | '0603LF'  | 'EMPTY'  | 'CS37503F904'(!)        = ''              | ''                 | 'CS37503F904'           | 'R0603_H24'         | '(SMR0603AW)'                  | '75K'     | '1%'    | '1/10W'  | 'IO'       | 'RES CHIP 75K 1/10W +-1%(0603)WTC'                 | 'CHIPR0603'    | ''          | ''            | '20210330'
 '174K'       | '1%'      | '1/10W'  | '0603LF'  | 'CHIP'   | 'CS41743F910'(!)        = ''              | ''                 | 'CS41743F910'           | 'R0603_H24'         | '(SMR0603AW)'                  | '174K'    | '1%'    | '1/10W'  | 'DISCRETE' | 'RESISTOR CHIP 174K 1/10W+-1%(0603)'               | 'CHIPR0603'    | ''          | ''            | '20210330'
 '174K'       | '1%'      | '1/10W'  | '0603LF'  | 'EMPTY'  | 'CS41743F910'(!)        = ''              | ''                 | 'CS41743F910'           | 'R0603_H24'         | '(SMR0603AW)'                  | '174K'    | '1%'    | '1/10W'  | 'IO'       | 'RESISTOR CHIP 174K 1/10W+-1%(0603)'               | 'CHIPR0603'    | ''          | ''            | '20210330'
 '174K'       | '0.5%'    | '1/10W'  | '0603LF'  | 'CHIP'   | 'CS41743D909'(!)        = ''              | ''                 | 'CS41743D909'           | 'R0603_H24'         | '(SMR0603AW)'                  | '174K'    | '0.5%'  | '1/10W'  | 'DISCRETE' | 'RES CHIP 174K 1/10W +-0.5%(0603)EP'               | 'CHIPR0603'    | ''          | ''            | '20210330'
 '174K'       | '0.5%'    | '1/10W'  | '0603LF'  | 'EMPTY'  | 'CS41743D909'(!)        = ''              | ''                 | 'CS41743D909'           | 'R0603_H24'         | '(SMR0603AW)'                  | '174K'    | '0.5%'  | '1/10W'  | 'IO'       | 'RES CHIP 174K 1/10W +-0.5%(0603)EP'               | 'CHIPR0603'    | ''          | ''            | '20210330'
 '75K'        | '0.5%'    | '1/10W'  | '0603LF'  | 'CHIP'   | 'CS37503D916'(!)        = ''              | ''                 | 'CS37503D916'           | 'R0603'             | '(SMR0603AW)'                  | '75K'     | '0.5%'  | '1/10W'  | 'DISCRETE' | 'RESISTOR CHIP 75K 1/10W+-0.5%(0603)'              | 'CHIPR0603'    | ''          | ''            | '20210330'
 '75K'        | '0.5%'    | '1/10W'  | '0603LF'  | 'EMPTY'  | 'CS37503D916'(!)        = ''              | ''                 | 'CS37503D916'           | 'R0603'             | '(SMR0603AW)'                  | '75K'     | '0.5%'  | '1/10W'  | 'IO'       | 'RESISTOR CHIP 75K 1/10W+-0.5%(0603)'              | 'CHIPR0603'    | ''          | ''            | '20210330'
 '681'        | '1%'      | '1/16W'  | '0402LF'  | 'CHIP'   | 'CS16812FB20'(!)        = 'End of Design' | 'Comp-Approve'     | 'CS16812FB20'           | 'R0402'             | '(R0402-0201)'                 | '681'     | '1%'    | '1/16W'  | 'DISCRETE' | 'RES CHIP 681 1/16W +-1%(0402)'                    | 'CHIPR0402'    | ''          | ''            | '20210330'
 '681'        | '1%'      | '1/16W'  | '0402LF'  | 'EMPTY'  | 'CS16812FB20'(!)        = 'End of Design' | 'Comp-Approve'     | 'CS16812FB20'           | 'R0402'             | '(R0402-0201)'                 | '681'     | '1%'    | '1/16W'  | 'IO'       | 'RES CHIP 681 1/16W +-1%(0402)'                    | 'CHIPR0402'    | ''          | ''            | '20210330'
 '0.47'       | '1%'      | '1/10W'  | '0603LF'  | 'CHIP'   | 'CS+4703F905'(!)        = ''              | ''                 | 'CS+4703F905'           | 'R0603'             | '(SMR0603AW)'                  | '0.47'    | '1%'    | '1/10W'  | 'DISCRETE' | 'RES CHIP 0.47 1/10W+-1%(0603)'                    | 'CHIPR0603'    | ''          | ''            | '20210330'
 '0.47'       | '1%'      | '1/10W'  | '0603LF'  | 'EMPTY'  | 'CS+4703F905'(!)        = ''              | ''                 | 'CS+4703F905'           | 'R0603'             | '(SMR0603AW)'                  | '0.47'    | '1%'    | '1/10W'  | 'IO'       | 'RES CHIP 0.47 1/10W+-1%(0603)'                    | 'CHIPR0603'    | ''          | ''            | '20210330'
 '750'        | '1%'      | '1/10W'  | '0603LF'  | 'CHIP'   | 'CS17503F902'(!)        = 'End of Design' | 'Comp-Approve'     | 'CS17503F902'           | 'R0603'             | '(SMR0603AW)'                  | '750'     | '1%'    | '1/10W'  | 'DISCRETE' | 'RES CHIP 750 1/10W +-1%(0603)EF'                  | 'CHIPR0603'    | ''          | ''            | '20210407'
 '750'        | '1%'      | '1/10W'  | '0603LF'  | 'EMPTY'  | 'CS17503F902'(!)        = 'End of Design' | 'Comp-Approve'     | 'CS17503F902'           | 'R0603'             | '(SMR0603AW)'                  | '750'     | '1%'    | '1/10W'  | 'IO'       | 'RES CHIP 750 1/10W +-1%(0603)EF'                  | 'CHIPR0603'    | ''          | ''            | '20210407'
 '0.003'      | '1%'      | '3W'     | '2512LF'  | 'CHIP'   | 'CS+003DFR03'(!)        = ''              | ''                 | 'CS+003DFR03'           | 'R2512XY'           | '(SMR2512AW)'                  | '0.003'   | '1%'    | '3W'     | 'DISCRETE' | 'RES CHIP 0.003 3W +-1%(2512)RLC'                  | 'CHIPR2512'    | ''          | ''            | '20210419'
 '0.003'      | '1%'      | '3W'     | '2512LF'  | 'EMPTY'  | 'CS+003DFR03'(!)        = ''              | ''                 | 'CS+003DFR03'           | 'R2512XY'           | '(SMR2512AW)'                  | '0.003'   | '1%'    | '3W'     | 'IO'       | 'RES CHIP 0.003 3W +-1%(2512)RLC'                  | 'CHIPR2512'    | ''          | ''            | '20210419'
 '0.0005'     | '1%'      | '3W'     | '2512LF'  | 'CHIP'   | 'CS0000DFR18'(!)        = ''              | ''                 | 'CS0000DFR18'           | 'R2512XG'           | '(SMR2512AW)'                  | '0.0005'  | '1%'    | '3W'     | 'DISCRETE' | 'RES CHIP 0.0005 3W +-1%(2512)RLC'                 | 'CHIPR2512'    | ''          | ''            | '20210428'
 '0.0005'     | '1%'      | '3W'     | '2512LF'  | 'EMPTY'  | 'CS0000DFR18'(!)        = ''              | ''                 | 'CS0000DFR18'           | 'R2512XG'           | '(SMR2512AW)'                  | '0.0005'  | '1%'    | '3W'     | 'IO'       | 'RES CHIP 0.0005 3W +-1%(2512)RLC'                 | 'CHIPR2512'    | ''          | ''            | '20210428'
 '0.001'      | '1%'      | '3W'     | '2512LF'  | 'CHIP'   | 'CS+001DFR10'(!)        = ''              | ''                 | 'CS+001DFR10'           | 'R2512XJ'           | '(SMR2512AW)'                  | '0.001'   | '1%'    | '3W'     | 'DISCRETE' | 'RES CHIP 0.001 3W +-1%(2512)RLC'                  | 'CHIPR2512'    | ''          | ''            | '20210428'
 '0.001'      | '1%'      | '3W'     | '2512LF'  | 'EMPTY'  | 'CS+001DFR10'(!)        = ''              | ''                 | 'CS+001DFR10'           | 'R2512XJ'           | '(SMR2512AW)'                  | '0.001'   | '1%'    | '3W'     | 'IO'       | 'RES CHIP 0.001 3W +-1%(2512)RLC'                  | 'CHIPR2512'    | ''          | ''            | '20210428'
 '0.68'       | '1%'      | '1/6W'   | '0402LF'  | 'CHIP'   | 'CS+6802FB00'(!)        = ''              | ''                 | 'CS+6802FB00'           | 'R0402_H20'         | '(R0402-0201_H20)'             | '0.68'    | '1%'    | '1/6W'   | 'DISCRETE' | 'RES CHIP 0.68 OHM 1/6W +-1%(0402)'                | 'CHIPR0402'    | ''          | ''            | '20210507'
 '0.68'       | '1%'      | '1/6W'   | '0402LF'  | 'EMPTY'  | 'CS+6802FB00'(!)        = ''              | ''                 | 'CS+6802FB00'           | 'R0402_H20'         | '(R0402-0201_H20)'             | '0.68'    | '1%'    | '1/6W'   | 'IO'       | 'RES CHIP 0.68 OHM 1/6W +-1%(0402)'                | 'CHIPR0402'    | ''          | ''            | '20210507'
 '374'        | '1%'      | '1/16W'  | '0402LF'  | 'CHIP'   | 'CS13742FB13'(!)        = 'End of Design' | 'Comp-Approve'     | 'CS13742FB13'           | 'R0402'             | '(R0402-0201)'                 | '374'     | '1%'    | '1/16W'  | 'DISCRETE' | 'RES CHIP 374 1/16W +-1%(0402)'                    | 'CHIPR0402'    | ''          | ''            | '20210514'
 '374'        | '1%'      | '1/16W'  | '0402LF'  | 'EMPTY'  | 'CS13742FB13'(!)        = 'End of Design' | 'Comp-Approve'     | 'CS13742FB13'           | 'R0402'             | '(R0402-0201)'                 | '374'     | '1%'    | '1/16W'  | 'IO'       | 'RES CHIP 374 1/16W +-1%(0402)'                    | 'CHIPR0402'    | ''          | ''            | '20210514'
 '3.74K'      | '0.1%'    | '1/16W'  | '0402LF'  | 'CHIP'   | 'CS23742BB01'(!)        = ''              | 'End of Life'      | 'CS23742BB01'           | 'R0402_EOL'         | '(R0402-0201)'                 | '3.74K'   | '0.1%'  | '1/16W'  | 'DISCRETE' | 'RES CHIP 3.74K 1/16W +-0.1%(0402)'                | 'CHIPR0402'    | ''          | ''            | '20210514'
 '3.74K'      | '0.1%'    | '1/16W'  | '0402LF'  | 'EMPTY'  | 'CS23742BB01'(!)        = ''              | 'End of Life'      | 'CS23742BB01'           | 'R0402_EOL'         | '(R0402-0201)'                 | '3.74K'   | '0.1%'  | '1/16W'  | 'IO'       | 'RES CHIP 3.74K 1/16W +-0.1%(0402)'                | 'CHIPR0402'    | ''          | ''            | '20210514'
 '13.3K'      | '0.1%'    | '1/16W'  | '0402LF'  | 'CHIP'   | 'CS31332BB01'(!)        = ''              | ''                 | 'CS31332BB01'           | 'R0402'             | '(R0402-0201)'                 | '13.3K'   | '0.1%'  | '1/16W'  | 'DISCRETE' | 'RES CHIP 13.3K 1/16W +-0.1%(0402)'                | 'CHIPR0402'    | ''          | ''            | '20210514'
 '13.3K'      | '0.1%'    | '1/16W'  | '0402LF'  | 'EMPTY'  | 'CS31332BB01'(!)        = ''              | ''                 | 'CS31332BB01'           | 'R0402'             | '(R0402-0201)'                 | '13.3K'   | '0.1%'  | '1/16W'  | 'IO'       | 'RES CHIP 13.3K 1/16W +-0.1%(0402)'                | 'CHIPR0402'    | ''          | ''            | '20210514'
 '90.9'       | '1%'      | '1/20W'  | '0201LF'  | 'CHIP'   | 'CS09091FE00'(!)        = ''              | ''                 | 'CS09091FE00'           | 'R0201'             | '(SMR0201AW)'                  | '90.9'    | '1%'    | '1/20W'  | 'DISCRETE' | 'RES CHIP 90.9 1/20W +-1%(0201)'                   | 'CHIPR0201'    | ''          | ''            | '20210520'
 '90.9'       | '1%'      | '1/20W'  | '0201LF'  | 'EMPTY'  | 'CS09091FE00'(!)        = ''              | ''                 | 'CS09091FE00'           | 'R0201'             | '(SMR0201AW)'                  | '90.9'    | '1%'    | '1/20W'  | 'IO'       | 'RES CHIP 90.9 1/20W +-1%(0201)'                   | 'CHIPR0201'    | ''          | ''            | '20210520'
 '280K'       | '1%'      | '1/16W'  | '0402LF'  | 'CHIP'   | 'CS42802FB05'(!)        = ''              | ''                 | 'CS42802FB05'           | 'R0402'             | '(R0402-0201)'                 | '280K'    | '1%'    | '1/16W'  | 'DISCRETE' | 'RES CHIP 280K 1/16W +-1%(0402)EF'                 | 'CHIPR0402'    | ''          | ''            | '20210526'
 '280K'       | '1%'      | '1/16W'  | '0402LF'  | 'EMPTY'  | 'CS42802FB05'(!)        = ''              | ''                 | 'CS42802FB05'           | 'R0402'             | '(R0402-0201)'                 | '280K'    | '1%'    | '1/16W'  | 'IO'       | 'RES CHIP 280K 1/16W +-1%(0402)EF'                 | 'CHIPR0402'    | ''          | ''            | '20210526'
 '53.6K'      | '0.1%'    | '1/16W'  | '0402LF'  | 'CHIP'   | 'CS35362BB03'(!)        = ''              | ''                 | 'CS35362BB03'           | 'R0402'             | '(R0402-0201)'                 | '53.6K'   | '0.1%'  | '1/16W'  | 'DISCRETE' | 'RES CHIP 53.6K 1/16W +-0.1%(0402)'                | 'CHIPR0402'    | ''          | ''            | '20210526'
 '53.6K'      | '0.1%'    | '1/16W'  | '0402LF'  | 'EMPTY'  | 'CS35362BB03'(!)        = ''              | ''                 | 'CS35362BB03'           | 'R0402'             | '(R0402-0201)'                 | '53.6K'   | '0.1%'  | '1/16W'  | 'IO'       | 'RES CHIP 53.6K 1/16W +-0.1%(0402)'                | 'CHIPR0402'    | ''          | ''            | '20210526'
 '6.65K'      | '0.1%'    | '1/16W'  | '0402LF'  | 'CHIP'   | 'CS26652BB01'(!)        = ''              | ''                 | 'CS26652BB01'           | 'R0402'             | '(R0402-0201)'                 | '6.65K'   | '0.1%'  | '1/16W'  | 'DISCRETE' | 'RES CHIP 6.65K 1/16W +-0.1%(0402)'                | 'CHIPR0402'    | ''          | ''            | '20210526'
 '6.65K'      | '0.1%'    | '1/16W'  | '0402LF'  | 'EMPTY'  | 'CS26652BB01'(!)        = ''              | ''                 | 'CS26652BB01'           | 'R0402'             | '(R0402-0201)'                 | '6.65K'   | '0.1%'  | '1/16W'  | 'IO'       | 'RES CHIP 6.65K 1/16W +-0.1%(0402)'                | 'CHIPR0402'    | ''          | ''            | '20210526'
 '3.74K'      | '0.1%'    | '1/16W'  | '0402LF'  | 'CHIP'   | 'CS23742BB00'(!)        = ''              | ''                 | 'CS23742BB00'           | 'R0402'             | '(R0402-0201)'                 | '3.74K'   | '0.1%'  | '1/16W'  | 'DISCRETE' | 'RES CHIP 3.74K 1/16W +-0.1%(0402)'                | 'CHIPR0402'    | ''          | ''            | '20210526'
 '3.74K'      | '0.1%'    | '1/16W'  | '0402LF'  | 'EMPTY'  | 'CS23742BB00'(!)        = ''              | ''                 | 'CS23742BB00'           | 'R0402'             | '(R0402-0201)'                 | '3.74K'   | '0.1%'  | '1/16W'  | 'IO'       | 'RES CHIP 3.74K 1/16W +-0.1%(0402)'                | 'CHIPR0402'    | ''          | ''            | '20210526'
 '97.6'       | '1%'      | '1/16W'  | '0402LF'  | 'CHIP'   | 'CS09762FB01'(!)        = ''              | ''                 | 'CS09762FB01'           | 'R0402'             | '(R0402-0201)'                 | '97.6'    | '1%'    | '1/16W'  | 'DISCRETE' | 'RES CHIP 97.6 1/16W +-1%(0402)'                   | 'CHIPR0402'    | ''          | ''            | '20210531'
 '97.6'       | '1%'      | '1/16W'  | '0402LF'  | 'EMPTY'  | 'CS09762FB01'(!)        = ''              | ''                 | 'CS09762FB01'           | 'R0402'             | '(R0402-0201)'                 | '97.6'    | '1%'    | '1/16W'  | 'IO'       | 'RES CHIP 97.6 1/16W +-1%(0402)'                   | 'CHIPR0402'    | ''          | ''            | '20210531'
 '0.03'       | '1%'      | '1/10W'  | '0603LF'  | 'CHIP'   | 'CS+0303F901'(!)        = ''              | ''                 | 'CS+0303F901'           | 'R0603'             | '(SMR0603AW)'                  | '0.03'    | '1%'    | '1/10W'  | 'DISCRETE' | 'RES CHIP 0.03 1/10W +-1%(0603)'                   | 'CHIPR0603'    | ''          | ''            | '20210531'
 '0.03'       | '1%'      | '1/10W'  | '0603LF'  | 'EMPTY'  | 'CS+0303F901'(!)        = ''              | ''                 | 'CS+0303F901'           | 'R0603'             | '(SMR0603AW)'                  | '0.03'    | '1%'    | '1/10W'  | 'IO'       | 'RES CHIP 0.03 1/10W +-1%(0603)'                   | 'CHIPR0603'    | ''          | ''            | '20210531'
 '0.25'       | '1%'      | '1/4W'   | '0805LF'  | 'CHIP'   | 'CS+2506FA00'(!)        = ''              | ''                 | 'CS+2506FA00'           | 'R0805'             | '(SMR0805AW)'                  | '0.25'    | '1%'    | '1/4W'   | 'DISCRETE' | 'RES CHIP 0.25 1/4W +-1%(0805)'                    | 'CHIPR0805'    | ''          | ''            | '20210607'
 '0.25'       | '1%'      | '1/4W'   | '0805LF'  | 'EMPTY'  | 'CS+2506FA00'(!)        = ''              | ''                 | 'CS+2506FA00'           | 'R0805'             | '(SMR0805AW)'                  | '0.25'    | '1%'    | '1/4W'   | 'IO'       | 'RES CHIP 0.25 1/4W +-1%(0805)'                    | 'CHIPR0805'    | ''          | ''            | '20210607'
 '75K'        | '0.1%'    | '1/16W'  | '0402LF'  | 'CHIP'   | 'CS37502BB00'(!)        = ''              | ''                 | 'CS37502BB00'           | 'R0402'             | '(R0402-0201)'                 | '75K'     | '0.1%'  | '1/16W'  | 'DISCRETE' | 'RES CHIP 75K 1/16W +-0.1%(0402)'                  | 'CHIPR0402'    | ''          | ''            | '20210610'
 '75K'        | '0.1%'    | '1/16W'  | '0402LF'  | 'EMPTY'  | 'CS37502BB00'(!)        = ''              | ''                 | 'CS37502BB00'           | 'R0402'             | '(R0402-0201)'                 | '75K'     | '0.1%'  | '1/16W'  | 'IO'       | 'RES CHIP 75K 1/16W +-0.1%(0402)'                  | 'CHIPR0402'    | ''          | ''            | '20210610'
 '4.7'        | '5%'      | '1/8W'   | '0805LF'  | 'CHIP'   | 'CS-4704JA31'(!)        = 'End of Design' | 'Comp-Approve'     | 'CS-4704JA31'           | 'R0805_H26'         | '(SMR0805AW)'                  | '4.7'     | '5%'    | '1/8W'   | 'DISCRETE' | 'RES CHIP 4.7 1/8W+-5%(0805)'                      | 'CHIPR0805'    | ''          | ''            | '20210610'
 '4.7'        | '5%'      | '1/8W'   | '0805LF'  | 'EMPTY'  | 'CS-4704JA31'(!)        = 'End of Design' | 'Comp-Approve'     | 'CS-4704JA31'           | 'R0805_H26'         | '(SMR0805AW)'                  | '4.7'     | '5%'    | '1/8W'   | 'IO'       | 'RES CHIP 4.7 1/8W+-5%(0805)'                      | 'CHIPR0805'    | ''          | ''            | '20210610'
 '300'        | '0.1%'    | '1/16W'  | '0402LF'  | 'CHIP'   | 'CS13002BB01'(!)        = ''              | ''                 | 'CS13002BB01'           | 'R0402'             | '(R0402-0201)'                 | '300'     | '0.1%'  | '1/16W'  | 'DISCRETE' | 'RES CHIP 300 1/16W +-0.1%(0402)'                  | 'CHIPR0402'    | ''          | ''            | '20210610'
 '300'        | '0.1%'    | '1/16W'  | '0402LF'  | 'EMPTY'  | 'CS13002BB01'(!)        = ''              | ''                 | 'CS13002BB01'           | 'R0402'             | '(R0402-0201)'                 | '300'     | '0.1%'  | '1/16W'  | 'IO'       | 'RES CHIP 300 1/16W +-0.1%(0402)'                  | 'CHIPR0402'    | ''          | ''            | '20210610'
 '430'        | '1%'      | '1/2W'   | '1206LF'  | 'CHIP'   | 'CS14307F200'(!)        = ''              | ''                 | 'CS14307F200'           | 'R1206XF'           | '(SMR1206AW)'                  | '430'     | '1%'    | '1/2W'   | 'DISCRETE' | 'RES CHIP 430 1/2W +-1%(1206)'                     | 'CHIPR1206'    | ''          | ''            | '20210616'
 '430'        | '1%'      | '1/2W'   | '1206LF'  | 'EMPTY'  | 'CS14307F200'(!)        = ''              | ''                 | 'CS14307F200'           | 'R1206XF'           | '(SMR1206AW)'                  | '430'     | '1%'    | '1/2W'   | 'IO'       | 'RES CHIP 430 1/2W +-1%(1206)'                     | 'CHIPR1206'    | ''          | ''            | '20210616'
 '34'         | '1%'      | '1/16W'  | '0402LF'  | 'CHIP'   | 'CS03402FB00'(!)        = 'End of Design' | 'Comp-Release Qty' | 'CS03402FB00'           | 'R0402'             | '(R0402-0201)'                 | '34'      | '1%'    | '1/16W'  | 'DISCRETE' | 'RES CHIP 34 1/16W +-1%(0402)'                     | 'CHIPR0402'    | ''          | ''            | '20210622'
 '34'         | '1%'      | '1/16W'  | '0402LF'  | 'EMPTY'  | 'CS03402FB00'(!)        = 'End of Design' | 'Comp-Release Qty' | 'CS03402FB00'           | 'R0402'             | '(R0402-0201)'                 | '34'      | '1%'    | '1/16W'  | 'IO'       | 'RES CHIP 34 1/16W +-1%(0402)'                     | 'CHIPR0402'    | ''          | ''            | '20210622'
 '300K'       | '0.1%'    | '1/16W'  | '0402LF'  | 'CHIP'   | 'CS43002BB01'(!)        = 'End of Design' | 'Comp-Approve'     | 'CS43002BB01'           | 'R0402'             | '(R0402-0201)'                 | '300K'    | '0.1%'  | '1/16W'  | 'DISCRETE' | 'RES CHIP 300K 1/16W +-0.1%(0402)'                 | 'CHIPR0402'    | ''          | ''            | '20210622'
 '300K'       | '0.1%'    | '1/16W'  | '0402LF'  | 'EMPTY'  | 'CS43002BB01'(!)        = 'End of Design' | 'Comp-Approve'     | 'CS43002BB01'           | 'R0402'             | '(R0402-0201)'                 | '300K'    | '0.1%'  | '1/16W'  | 'IO'       | 'RES CHIP 300K 1/16W +-0.1%(0402)'                 | 'CHIPR0402'    | ''          | ''            | '20210622'
 '0.0002'     | '5%'      | '1/2W'   | '0805LF'  | 'CHIP'   | 'CS00007JA00'(!)        = ''              | ''                 | 'CS00007JA00'           | 'R0805_H32'         | '(SMR0805AW)'                  | '0.0002'  | '5%'    | '1/2W'   | 'DISCRETE' | 'RESISTOR CHIP 0.0002 1/2W +-5%(0805)'             | 'CHIPR0805'    | ''          | ''            | '20210622'
 '0.0002'     | '5%'      | '1/2W'   | '0805LF'  | 'EMPTY'  | 'CS00007JA00'(!)        = ''              | ''                 | 'CS00007JA00'           | 'R0805_H32'         | '(SMR0805AW)'                  | '0.0002'  | '5%'    | '1/2W'   | 'IO'       | 'RESISTOR CHIP 0.0002 1/2W +-5%(0805)'             | 'CHIPR0805'    | ''          | ''            | '20210622'
 '169'        | '1%'      | '1/20W'  | '0201LF'  | 'CHIP'   | 'CS11691FE01'(!)        = ''              | ''                 | 'CS11691FE01'           | 'R0201'             | '(SMR0201AW)'                  | '169'     | '1%'    | '1/20W'  | 'DISCRETE' | 'RES CHIP 169 1/20W +-1%(0201)'                    | 'CHIPR0201'    | ''          | ''            | '20210622'
 '169'        | '1%'      | '1/20W'  | '0201LF'  | 'EMPTY'  | 'CS11691FE01'(!)        = ''              | ''                 | 'CS11691FE01'           | 'R0201'             | '(SMR0201AW)'                  | '169'     | '1%'    | '1/20W'  | 'IO'       | 'RES CHIP 169 1/20W +-1%(0201)'                    | 'CHIPR0201'    | ''          | ''            | '20210622'
 '8.66'       | '1%'      | '1/16W'  | '0402LF'  | 'CHIP'   | 'CS-8662FB00'(!)        = ''              | ''                 | 'CS-8662FB00'           | 'R0402'             | '(R0402-0201)'                 | '8.66'    | '1%'    | '1/16W'  | 'DISCRETE' | 'RES CHIP 8.66 1/16W+-1%(0402)'                    | 'CHIPR0402'    | ''          | ''            | '20210623'
 '8.66'       | '1%'      | '1/16W'  | '0402LF'  | 'EMPTY'  | 'CS-8662FB00'(!)        = ''              | ''                 | 'CS-8662FB00'           | 'R0402'             | '(R0402-0201)'                 | '8.66'    | '1%'    | '1/16W'  | 'IO'       | 'RES CHIP 8.66 1/16W+-1%(0402)'                    | 'CHIPR0402'    | ''          | ''            | '20210623'
 '2.15K'      | '1%'      | '1/4W'   | '1206LF'  | 'CHIP'   | 'CS22156F201'(!)        = 'End of Design' | 'Comp-Approve'     | 'CS22156F201'           | 'R1206XF'           | '(SMR1206AW)'                  | '2.15K'   | '1%'    | '1/4W'   | 'DISCRETE' | 'RES CHIP 2.15K 1/4W +-1%(1206)EF'                 | 'CHIPR1206'    | ''          | ''            | '20210624'
 '2.15K'      | '1%'      | '1/4W'   | '1206LF'  | 'EMPTY'  | 'CS22156F201'(!)        = 'End of Design' | 'Comp-Approve'     | 'CS22156F201'           | 'R1206XF'           | '(SMR1206AW)'                  | '2.15K'   | '1%'    | '1/4W'   | 'IO'       | 'RES CHIP 2.15K 1/4W +-1%(1206)EF'                 | 'CHIPR1206'    | ''          | ''            | '20210624'
 '475K'       | '1%'      | '1/8W'   | '0805LF'  | 'CHIP'   | 'CS44754FA03'(!)        = ''              | ''                 | 'CS44754FA03'           | 'R0805_H26'         | '(SMR0805AW)'                  | '475K'    | '1%'    | '1/8W'   | 'DISCRETE' | 'RES CHIP 475K 1/8W +-1%(0805)'                    | 'CHIPR0805'    | ''          | ''            | '20210628'
 '475K'       | '1%'      | '1/8W'   | '0805LF'  | 'EMPTY'  | 'CS44754FA03'(!)        = ''              | ''                 | 'CS44754FA03'           | 'R0805_H26'         | '(SMR0805AW)'                  | '475K'    | '1%'    | '1/8W'   | 'IO'       | 'RES CHIP 475K 1/8W +-1%(0805)'                    | 'CHIPR0805'    | ''          | ''            | '20210628'
 '124'        | '0.1%'    | '1/16W'  | '0402LF'  | 'CHIP'   | 'CS11242BB00'(!)        = ''              | ''                 | 'CS11242BB00'           | 'R0402'             | '(R0402-0201)'                 | '124'     | '0.1%'  | '1/16W'  | 'DISCRETE' | 'RES CHIP 124 1/16W+-0.1%(0402)'                   | 'CHIPR0402'    | ''          | ''            | '20210630'
 '124'        | '0.1%'    | '1/16W'  | '0402LF'  | 'EMPTY'  | 'CS11242BB00'(!)        = ''              | ''                 | 'CS11242BB00'           | 'R0402'             | '(R0402-0201)'                 | '124'     | '0.1%'  | '1/16W'  | 'IO'       | 'RES CHIP 124 1/16W+-0.1%(0402)'                   | 'CHIPR0402'    | ''          | ''            | '20210630'
 '909'        | '0.1%'    | '1/16W'  | '0402LF'  | 'CHIP'   | 'CS19092BB01'(!)        = ''              | ''                 | 'CS19092BB01'           | 'R0402'             | '(R0402-0201)'                 | '909'     | '0.1%'  | '1/16W'  | 'DISCRETE' | 'RES CHIP 909 1/16W+-0.1%(0402)'                   | 'CHIPR0402'    | ''          | ''            | '20210630'
 '909'        | '0.1%'    | '1/16W'  | '0402LF'  | 'EMPTY'  | 'CS19092BB01'(!)        = ''              | ''                 | 'CS19092BB01'           | 'R0402'             | '(R0402-0201)'                 | '909'     | '0.1%'  | '1/16W'  | 'IO'       | 'RES CHIP 909 1/16W+-0.1%(0402)'                   | 'CHIPR0402'    | ''          | ''            | '20210630'
 '49.9K'      | '0.1%'    | '1/16W'  | '0402LF'  | 'CHIP'   | 'CS34992BB08'(!)        = ''              | ''                 | 'CS34992BB08'           | 'R0402'             | '(R0402-0201)'                 | '49.9K'   | '0.1%'  | '1/16W'  | 'DISCRETE' | 'RES CHIP 49.9K 1/16W+-0.1%(0402)'                 | 'CHIPR0402'    | ''          | ''            | '20210630'
 '49.9K'      | '0.1%'    | '1/16W'  | '0402LF'  | 'EMPTY'  | 'CS34992BB08'(!)        = ''              | ''                 | 'CS34992BB08'           | 'R0402'             | '(R0402-0201)'                 | '49.9K'   | '0.1%'  | '1/16W'  | 'IO'       | 'RES CHIP 49.9K 1/16W+-0.1%(0402)'                 | 'CHIPR0402'    | ''          | ''            | '20210630'
 '23.2K'      | '0.1%'    | '1/16W'  | '0402LF'  | 'CHIP'   | 'CS32322BB00'(!)        = ''              | ''                 | 'CS32322BB00'           | 'R0402'             | '(R0402-0201)'                 | '23.2K'   | '0.1%'  | '1/16W'  | 'DISCRETE' | 'RES CHIP 23.2K 1/16W +-0.1%(0402)'                | 'CHIPR0402'    | ''          | ''            | '20210630'
 '23.2K'      | '0.1%'    | '1/16W'  | '0402LF'  | 'EMPTY'  | 'CS32322BB00'(!)        = ''              | ''                 | 'CS32322BB00'           | 'R0402'             | '(R0402-0201)'                 | '23.2K'   | '0.1%'  | '1/16W'  | 'IO'       | 'RES CHIP 23.2K 1/16W +-0.1%(0402)'                | 'CHIPR0402'    | ''          | ''            | '20210630'
 '1.69K'      | '0.1%'    | '1/16W'  | '0402LF'  | 'CHIP'   | 'CS21692BB00'(!)        = ''              | ''                 | 'CS21692BB00'           | 'R0402'             | '(R0402-0201)'                 | '1.69K'   | '0.1%'  | '1/16W'  | 'DISCRETE' | 'RES CHIP 1.69K 1/16W+-0.1%(0402)'                 | 'CHIPR0402'    | ''          | ''            | '20210630'
 '1.69K'      | '0.1%'    | '1/16W'  | '0402LF'  | 'EMPTY'  | 'CS21692BB00'(!)        = ''              | ''                 | 'CS21692BB00'           | 'R0402'             | '(R0402-0201)'                 | '1.69K'   | '0.1%'  | '1/16W'  | 'IO'       | 'RES CHIP 1.69K 1/16W+-0.1%(0402)'                 | 'CHIPR0402'    | ''          | ''            | '20210630'
 '3.09K'      | '0.1%'    | '1/16W'  | '0402LF'  | 'CHIP'   | 'CS23092BB02'(!)        = ''              | ''                 | 'CS23092BB02'           | 'R0402'             | '(R0402-0201)'                 | '3.09K'   | '0.1%'  | '1/16W'  | 'DISCRETE' | 'RES CHIP 3.09K 1/16W+-0.1%(0402)'                 | 'CHIPR0402'    | ''          | ''            | '20210630'
 '3.09K'      | '0.1%'    | '1/16W'  | '0402LF'  | 'EMPTY'  | 'CS23092BB02'(!)        = ''              | ''                 | 'CS23092BB02'           | 'R0402'             | '(R0402-0201)'                 | '3.09K'   | '0.1%'  | '1/16W'  | 'IO'       | 'RES CHIP 3.09K 1/16W+-0.1%(0402)'                 | 'CHIPR0402'    | ''          | ''            | '20210630'
 '1.74K'      | '0.1%'    | '1/16W'  | '0402LF'  | 'CHIP'   | 'CS21742BB02'(!)        = ''              | ''                 | 'CS21742BB02'           | 'R0402'             | '(R0402-0201)'                 | '1.74K'   | '0.1%'  | '1/16W'  | 'DISCRETE' | 'RES CHIP 1.74K 1/16W+-0.1%(0402)'                 | 'CHIPR0402'    | ''          | ''            | '20210630'
 '1.74K'      | '0.1%'    | '1/16W'  | '0402LF'  | 'EMPTY'  | 'CS21742BB02'(!)        = ''              | ''                 | 'CS21742BB02'           | 'R0402'             | '(R0402-0201)'                 | '1.74K'   | '0.1%'  | '1/16W'  | 'IO'       | 'RES CHIP 1.74K 1/16W+-0.1%(0402)'                 | 'CHIPR0402'    | ''          | ''            | '20210630'
 '2.55K'      | '0.1%'    | '1/16W'  | '0402LF'  | 'CHIP'   | 'CS22552BB01'(!)        = ''              | ''                 | 'CS22552BB01'           | 'R0402'             | '(R0402-0201)'                 | '2.55K'   | '0.1%'  | '1/16W'  | 'DISCRETE' | 'RES CHIP 2.55K 1/16W+-0.1%(0402)'                 | 'CHIPR0402'    | ''          | ''            | '20210630'
 '2.55K'      | '0.1%'    | '1/16W'  | '0402LF'  | 'EMPTY'  | 'CS22552BB01'(!)        = ''              | ''                 | 'CS22552BB01'           | 'R0402'             | '(R0402-0201)'                 | '2.55K'   | '0.1%'  | '1/16W'  | 'IO'       | 'RES CHIP 2.55K 1/16W+-0.1%(0402)'                 | 'CHIPR0402'    | ''          | ''            | '20210630'
 '1.37K'      | '0.1%'    | '1/16W'  | '0402LF'  | 'CHIP'   | 'CS21372BB00'(!)        = ''              | ''                 | 'CS21372BB00'           | 'R0402'             | '(R0402-0201)'                 | '1.37K'   | '0.1%'  | '1/16W'  | 'DISCRETE' | 'RES CHIP 1.37K 1/16W +-0.1%(0402)'                | 'CHIPR0402'    | ''          | ''            | '20210630'
 '1.37K'      | '0.1%'    | '1/16W'  | '0402LF'  | 'EMPTY'  | 'CS21372BB00'(!)        = ''              | ''                 | 'CS21372BB00'           | 'R0402'             | '(R0402-0201)'                 | '1.37K'   | '0.1%'  | '1/16W'  | 'IO'       | 'RES CHIP 1.37K 1/16W +-0.1%(0402)'                | 'CHIPR0402'    | ''          | ''            | '20210630'
 '453K'       | '1%'      | '1/16W'  | '0402LF'  | 'CHIP'   | 'CS44532FB05'(!)        = ''              | ''                 | 'CS44532FB05'           | 'R0402'             | '(R0402-0201)'                 | '453K'    | '1%'    | '1/16W'  | 'DISCRETE' | 'RES CHIP 453K 1/16W +-1%(0402)EF'                 | 'CHIPR0402'    | ''          | ''            | '20210630'
 '453K'       | '1%'      | '1/16W'  | '0402LF'  | 'EMPTY'  | 'CS44532FB05'(!)        = ''              | ''                 | 'CS44532FB05'           | 'R0402'             | '(R0402-0201)'                 | '453K'    | '1%'    | '1/16W'  | 'IO'       | 'RES CHIP 453K 1/16W +-1%(0402)EF'                 | 'CHIPR0402'    | ''          | ''            | '20210630'
 '17.4'       | '0.1%'    | '1/16W'  | '0402LF'  | 'CHIP'   | 'CS01742BB00'(!)        = ''              | ''                 | 'CS01742BB00'           | 'R0402'             | '(R0402-0201)'                 | '17.4'    | '0.1%'  | '1/16W'  | 'DISCRETE' | 'RES CHIP 17.4 1/16W +-0.1%( 0402)'                | 'CHIPR0402'    | ''          | ''            | '20210701'
 '17.4'       | '0.1%'    | '1/16W'  | '0402LF'  | 'EMPTY'  | 'CS01742BB00'(!)        = ''              | ''                 | 'CS01742BB00'           | 'R0402'             | '(R0402-0201)'                 | '17.4'    | '0.1%'  | '1/16W'  | 'IO'       | 'RES CHIP 17.4 1/16W +-0.1%( 0402)'                | 'CHIPR0402'    | ''          | ''            | '20210701'
 '91'         | '0.1%'    | '1/16W'  | '0402LF'  | 'CHIP'   | 'CS09102BB00'(!)        = ''              | ''                 | 'CS09102BB00'           | 'R0402'             | '(R0402-0201)'                 | '91'      | '0.1%'  | '1/16W'  | 'DISCRETE' | 'RES CHIP 91 1/16W +-0.1%( 0402)'                  | 'CHIPR0402'    | ''          | ''            | '20210701'
 '91'         | '0.1%'    | '1/16W'  | '0402LF'  | 'EMPTY'  | 'CS09102BB00'(!)        = ''              | ''                 | 'CS09102BB00'           | 'R0402'             | '(R0402-0201)'                 | '91'      | '0.1%'  | '1/16W'  | 'IO'       | 'RES CHIP 91 1/16W +-0.1%( 0402)'                  | 'CHIPR0402'    | ''          | ''            | '20210701'
 '332'        | '0.1%'    | '1/16W'  | '0402LF'  | 'CHIP'   | 'CS13322BB00'(!)        = ''              | ''                 | 'CS13322BB00'           | 'R0402'             | '(R0402-0201)'                 | '332'     | '0.1%'  | '1/16W'  | 'DISCRETE' | 'RES CHIP 332 1/16W +-0.1%( 0402)'                 | 'CHIPR0402'    | ''          | ''            | '20210702'
 '332'        | '0.1%'    | '1/16W'  | '0402LF'  | 'EMPTY'  | 'CS13322BB00'(!)        = ''              | ''                 | 'CS13322BB00'           | 'R0402'             | '(R0402-0201)'                 | '332'     | '0.1%'  | '1/16W'  | 'IO'       | 'RES CHIP 332 1/16W +-0.1%( 0402)'                 | 'CHIPR0402'    | ''          | ''            | '20210702'
 '374'        | '0.1%'    | '1/16W'  | '0402LF'  | 'CHIP'   | 'CS13742BB00'(!)        = ''              | ''                 | 'CS13742BB00'           | 'R0402'             | '(R0402-0201)'                 | '374'     | '0.1%'  | '1/16W'  | 'DISCRETE' | 'RES CHIP 374 1/16W +-0.1%( 0402)'                 | 'CHIPR0402'    | ''          | ''            | '20210702'
 '374'        | '0.1%'    | '1/16W'  | '0402LF'  | 'EMPTY'  | 'CS13742BB00'(!)        = ''              | ''                 | 'CS13742BB00'           | 'R0402'             | '(R0402-0201)'                 | '374'     | '0.1%'  | '1/16W'  | 'IO'       | 'RES CHIP 374 1/16W +-0.1%( 0402)'                 | 'CHIPR0402'    | ''          | ''            | '20210702'
 '590'        | '0.1%'    | '1/16W'  | '0402LF'  | 'CHIP'   | 'CS15902BB00'(!)        = ''              | ''                 | 'CS15902BB00'           | 'R0402'             | '(R0402-0201)'                 | '590'     | '0.1%'  | '1/16W'  | 'DISCRETE' | 'RES CHIP 590 1/16W +-0.1%( 0402)'                 | 'CHIPR0402'    | ''          | ''            | '20210702'
 '590'        | '0.1%'    | '1/16W'  | '0402LF'  | 'EMPTY'  | 'CS15902BB00'(!)        = ''              | ''                 | 'CS15902BB00'           | 'R0402'             | '(R0402-0201)'                 | '590'     | '0.1%'  | '1/16W'  | 'IO'       | 'RES CHIP 590 1/16W +-0.1%( 0402)'                 | 'CHIPR0402'    | ''          | ''            | '20210702'
 '300K'       | '1%'      | '1/16W'  | '0402LF'  | 'CHIP'   | 'CS43002FB01'(!)        = 'End of Design' | 'Comp-Approve'     | 'CS43002FB01'           | 'R0402'             | '(R0402-0201)'                 | '300K'    | '1%'    | '1/16W'  | 'DISCRETE' | 'RES CHIP 300K 1/16W +-1%(0402)EF'                 | 'CHIPR0402'    | ''          | ''            | '20210702'
 '300K'       | '1%'      | '1/16W'  | '0402LF'  | 'EMPTY'  | 'CS43002FB01'(!)        = 'End of Design' | 'Comp-Approve'     | 'CS43002FB01'           | 'R0402'             | '(R0402-0201)'                 | '300K'    | '1%'    | '1/16W'  | 'IO'       | 'RES CHIP 300K 1/16W +-1%(0402)EF'                 | 'CHIPR0402'    | ''          | ''            | '20210702'
 '3.92K'      | '0.1%'    | '1/16W'  | '0402LF'  | 'CHIP'   | 'CS23922BB00'(!)        = 'End of Design' | 'Comp-Approve'     | 'CS23922BB00'           | 'R0402'             | '(R0402-0201)'                 | '3.92K'   | '0.1%'  | '1/16W'  | 'DISCRETE' | 'RES CHIP 3.92K 1/16W +-0.1%(0402)'                | 'CHIPR0402'    | ''          | ''            | '20210702'
 '3.92K'      | '0.1%'    | '1/16W'  | '0402LF'  | 'EMPTY'  | 'CS23922BB00'(!)        = 'End of Design' | 'Comp-Approve'     | 'CS23922BB00'           | 'R0402'             | '(R0402-0201)'                 | '3.92K'   | '0.1%'  | '1/16W'  | 'IO'       | 'RES CHIP 3.92K 1/16W +-0.1%(0402)'                | 'CHIPR0402'    | ''          | ''            | '20210702'
 '17.4'       | '1%'      | '1/16W'  | '0402LF'  | 'CHIP'   | 'CS01742FB00'(!)        = ''              | ''                 | 'CS01742FB00'           | 'R0402'             | '(R0402-0201)'                 | '17.4'    | '1%'    | '1/16W'  | 'DISCRETE' | 'RES CHIP 17.4 1/16W +-1%( 0402)'                  | 'CHIPR0402'    | ''          | ''            | '20210707'
 '17.4'       | '1%'      | '1/16W'  | '0402LF'  | 'EMPTY'  | 'CS01742FB00'(!)        = ''              | ''                 | 'CS01742FB00'           | 'R0402'             | '(R0402-0201)'                 | '17.4'    | '1%'    | '1/16W'  | 'IO'       | 'RES CHIP 17.4 1/16W +-1%( 0402)'                  | 'CHIPR0402'    | ''          | ''            | '20210707'
 '84.5'       | '1%'      | '1/16W'  | '0402LF'  | 'CHIP'   | 'CS08452FB01'(!)        = 'End of Design' | 'Comp-Approve'     | 'CS08452FB01'           | 'R0402'             | '(R0402-0201)'                 | '84.5'    | '1%'    | '1/16W'  | 'DISCRETE' | 'RES CHIP 84.5 1/16W 1%(0402)'                     | 'CHIPR0402'    | ''          | ''            | '20210707'
 '84.5'       | '1%'      | '1/16W'  | '0402LF'  | 'EMPTY'  | 'CS08452FB01'(!)        = 'End of Design' | 'Comp-Approve'     | 'CS08452FB01'           | 'R0402'             | '(R0402-0201)'                 | '84.5'    | '1%'    | '1/16W'  | 'IO'       | 'RES CHIP 84.5 1/16W 1%(0402)'                     | 'CHIPR0402'    | ''          | ''            | '20210707'
 '5.1'        | '5%'      | '1/16W'  | '0402LF'  | 'CHIP'   | 'CS-5102JB02'(!)        = ''              | ''                 | 'CS-5102JB02'           | 'R0402'             | '(R0402-0201)'                 | '5.1'     | '5%'    | '1/16W'  | 'DISCRETE' | 'RES CHIP 5.1 1/16W +-5%(0402)EF'                  | 'CHIPR0402'    | ''          | ''            | '20210715'
 '5.1'        | '5%'      | '1/16W'  | '0402LF'  | 'EMPTY'  | 'CS-5102JB02'(!)        = ''              | ''                 | 'CS-5102JB02'           | 'R0402'             | '(R0402-0201)'                 | '5.1'     | '5%'    | '1/16W'  | 'IO'       | 'RES CHIP 5.1 1/16W +-5%(0402)EF'                  | 'CHIPR0402'    | ''          | ''            | '20210715'
 '2.4K'       | '1%'      | '1/16W'  | '0402LF'  | 'CHIP'   | 'CS22402FB02'(!)        = ''              | ''                 | 'CS22402FB02'           | 'R0402'             | '(R0402-0201)'                 | '2.4K'    | '1%'    | '1/16W'  | 'DISCRETE' | 'RES CHIP 2.4K 1/16W+-1%(0402)EF'                  | 'CHIPR0402'    | ''          | ''            | '20210715'
 '2.4K'       | '1%'      | '1/16W'  | '0402LF'  | 'EMPTY'  | 'CS22402FB02'(!)        = ''              | ''                 | 'CS22402FB02'           | 'R0402'             | '(R0402-0201)'                 | '2.4K'    | '1%'    | '1/16W'  | 'IO'       | 'RES CHIP 2.4K 1/16W+-1%(0402)EF'                  | 'CHIPR0402'    | ''          | ''            | '20210715'
 '4.64K'      | '0.5%'    | '1/16W'  | '0402LF'  | 'CHIP'   | 'CS24642DB01'(!)        = ''              | ''                 | 'CS24642DB01'           | 'R0402'             | '(R0402-0201)'                 | '4.64K'   | '0.5%'  | '1/16W'  | 'DISCRETE' | 'RES CHIP 4.64K 1/16W +-0.5%(0402)EF'              | 'CHIPR0402'    | ''          | ''            | '20210715'
 '4.64K'      | '0.5%'    | '1/16W'  | '0402LF'  | 'EMPTY'  | 'CS24642DB01'(!)        = ''              | ''                 | 'CS24642DB01'           | 'R0402'             | '(R0402-0201)'                 | '4.64K'   | '0.5%'  | '1/16W'  | 'IO'       | 'RES CHIP 4.64K 1/16W +-0.5%(0402)EF'              | 'CHIPR0402'    | ''          | ''            | '20210715'
 '15.4K'      | '1%'      | '1/16W'  | '0402LF'  | 'CHIP'   | 'CS31542FB02'(!)        = ''              | ''                 | 'CS31542FB02'           | 'R0402'             | '(R0402-0201)'                 | '15.4K'   | '1%'    | '1/16W'  | 'DISCRETE' | 'RES CHIP 15.4K 1/16W +-1%(0402)EF'                | 'CHIPR0402'    | ''          | ''            | '20210715'
 '15.4K'      | '1%'      | '1/16W'  | '0402LF'  | 'EMPTY'  | 'CS31542FB02'(!)        = ''              | ''                 | 'CS31542FB02'           | 'R0402'             | '(R0402-0201)'                 | '15.4K'   | '1%'    | '1/16W'  | 'IO'       | 'RES CHIP 15.4K 1/16W +-1%(0402)EF'                | 'CHIPR0402'    | ''          | ''            | '20210715'
 '18.2K'      | '0.1%'    | '1/16W'  | '0402LF'  | 'CHIP'   | 'CS31822BB01'(!)        = ''              | ''                 | 'CS31822BB01'           | 'R0402'             | '(R0402-0201)'                 | '18.2K'   | '0.1%'  | '1/16W'  | 'DISCRETE' | 'RES CHIP 18.2K 1/16W +-0.1%(0402)EF'              | 'CHIPR0402'    | ''          | ''            | '20210715'
 '18.2K'      | '0.1%'    | '1/16W'  | '0402LF'  | 'EMPTY'  | 'CS31822BB01'(!)        = ''              | ''                 | 'CS31822BB01'           | 'R0402'             | '(R0402-0201)'                 | '18.2K'   | '0.1%'  | '1/16W'  | 'IO'       | 'RES CHIP 18.2K 1/16W +-0.1%(0402)EF'              | 'CHIPR0402'    | ''          | ''            | '20210715'
 '127K'       | '1%'      | '1/16W'  | '0402LF'  | 'CHIP'   | 'CS41272FB07'(!)        = ''              | ''                 | 'CS41272FB07'           | 'R0402'             | '(R0402-0201)'                 | '127K'    | '1%'    | '1/16W'  | 'DISCRETE' | 'RES CHIP 127K 1/16W +-1%(0402)EF'                 | 'CHIPR0402'    | ''          | ''            | '20210715'
 '127K'       | '1%'      | '1/16W'  | '0402LF'  | 'EMPTY'  | 'CS41272FB07'(!)        = ''              | ''                 | 'CS41272FB07'           | 'R0402'             | '(R0402-0201)'                 | '127K'    | '1%'    | '1/16W'  | 'IO'       | 'RES CHIP 127K 1/16W +-1%(0402)EF'                 | 'CHIPR0402'    | ''          | ''            | '20210715'
 '0'          | '5%'      | '1/4W'   | '1206LF'  | 'CHIP'   | 'CS00006J207'(!)        = 'End of Design' | 'Comp-Approve'     | 'CS00006J207'           | 'R1206XF'           | '(SMR1206AW)'                  | '0'       | '5%'    | '1/4W'   | 'DISCRETE' | 'RES CHIP 0 1/4W +-5%(1206)EF'                     | 'CHIPR1206'    | ''          | ''            | '20210715'
 '0'          | '5%'      | '1/4W'   | '1206LF'  | 'EMPTY'  | 'CS00006J207'(!)        = 'End of Design' | 'Comp-Approve'     | 'CS00006J207'           | 'R1206XF'           | '(SMR1206AW)'                  | '0'       | '5%'    | '1/4W'   | 'IO'       | 'RES CHIP 0 1/4W +-5%(1206)EF'                     | 'CHIPR1206'    | ''          | ''            | '20210715'
 '3.3'        | '1%'      | '1/16W'  | '0402LF'  | 'CHIP'   | 'CS-3302FB01'(!)        = 'End of Design' | 'Comp-Approve'     | 'CS-3302FB01'           | 'R0402'             | '(R0402-0201)'                 | '3.3'     | '1%'    | '1/16W'  | 'DISCRETE' | 'RES CHIP 3.3 1/16W +-1%(0402)EF'                  | 'CHIPR0402'    | ''          | ''            | '20210715'
 '3.3'        | '1%'      | '1/16W'  | '0402LF'  | 'EMPTY'  | 'CS-3302FB01'(!)        = 'End of Design' | 'Comp-Approve'     | 'CS-3302FB01'           | 'R0402'             | '(R0402-0201)'                 | '3.3'     | '1%'    | '1/16W'  | 'IO'       | 'RES CHIP 3.3 1/16W +-1%(0402)EF'                  | 'CHIPR0402'    | ''          | ''            | '20210715'
 '470'        | '1%'      | '1/16W'  | '0402LF'  | 'CHIP'   | 'CS14702FB04'(!)        = 'End of Design' | 'Comp-Approve'     | 'CS14702FB04'           | 'R0402'             | '(R0402-0201)'                 | '470'     | '1%'    | '1/16W'  | 'DISCRETE' | 'RES CHIP 470 1/16W +-1%(0402)EF'                  | 'CHIPR0402'    | ''          | ''            | '20210715'
 '470'        | '1%'      | '1/16W'  | '0402LF'  | 'EMPTY'  | 'CS14702FB04'(!)        = 'End of Design' | 'Comp-Approve'     | 'CS14702FB04'           | 'R0402'             | '(R0402-0201)'                 | '470'     | '1%'    | '1/16W'  | 'IO'       | 'RES CHIP 470 1/16W +-1%(0402)EF'                  | 'CHIPR0402'    | ''          | ''            | '20210715'
 '3.9K'       | '5%'      | '1/16W'  | '0402LF'  | 'CHIP'   | 'CS23902JB04'(!)        = 'End of Design' | 'Comp-Approve'     | 'CS23902JB04'           | 'R0402'             | '(R0402-0201)'                 | '3.9K'    | '5%'    | '1/16W'  | 'DISCRETE' | 'RES CHIP 3.9K 1/16W +-5%(0402)EF'                 | 'CHIPR0402'    | ''          | ''            | '20210715'
 '3.9K'       | '5%'      | '1/16W'  | '0402LF'  | 'EMPTY'  | 'CS23902JB04'(!)        = 'End of Design' | 'Comp-Approve'     | 'CS23902JB04'           | 'R0402'             | '(R0402-0201)'                 | '3.9K'    | '5%'    | '1/16W'  | 'IO'       | 'RES CHIP 3.9K 1/16W +-5%(0402)EF'                 | 'CHIPR0402'    | ''          | ''            | '20210715'
 '4.32K'      | '1%'      | '1/16W'  | '0402LF'  | 'CHIP'   | 'CS24322FB03'(!)        = 'End of Design' | 'Comp-Approve'     | 'CS24322FB03'           | 'R0402'             | '(R0402-0201)'                 | '4.32K'   | '1%'    | '1/16W'  | 'DISCRETE' | 'RES CHIP 4.32K 1/16W +-1%(0402)EF'                | 'CHIPR0402'    | ''          | ''            | '20210715'
 '4.32K'      | '1%'      | '1/16W'  | '0402LF'  | 'EMPTY'  | 'CS24322FB03'(!)        = 'End of Design' | 'Comp-Approve'     | 'CS24322FB03'           | 'R0402'             | '(R0402-0201)'                 | '4.32K'   | '1%'    | '1/16W'  | 'IO'       | 'RES CHIP 4.32K 1/16W +-1%(0402)EF'                | 'CHIPR0402'    | ''          | ''            | '20210715'
 '9.09K'      | '1%'      | '1/16W'  | '0402LF'  | 'CHIP'   | 'CS29092FB05'(!)        = 'End of Design' | 'Comp-Approve'     | 'CS29092FB05'           | 'R0402'             | '(R0402-0201)'                 | '9.09K'   | '1%'    | '1/16W'  | 'DISCRETE' | 'RES CHIP 9.09K 1/16W +-1%(0402)EF'                | 'CHIPR0402'    | ''          | ''            | '20210715'
 '9.09K'      | '1%'      | '1/16W'  | '0402LF'  | 'EMPTY'  | 'CS29092FB05'(!)        = 'End of Design' | 'Comp-Approve'     | 'CS29092FB05'           | 'R0402'             | '(R0402-0201)'                 | '9.09K'   | '1%'    | '1/16W'  | 'IO'       | 'RES CHIP 9.09K 1/16W +-1%(0402)EF'                | 'CHIPR0402'    | ''          | ''            | '20210715'
 '30.1K'      | '1%'      | '1/16W'  | '0402LF'  | 'CHIP'   | 'CS33012FB03'(!)        = 'End of Design' | 'Comp-Approve'     | 'CS33012FB03'           | 'R0402'             | '(R0402-0201)'                 | '30.1K'   | '1%'    | '1/16W'  | 'DISCRETE' | 'RES CHIP 30.1K 1/16W +-1%(0402)EF'                | 'CHIPR0402'    | ''          | ''            | '20210715'
 '30.1K'      | '1%'      | '1/16W'  | '0402LF'  | 'EMPTY'  | 'CS33012FB03'(!)        = 'End of Design' | 'Comp-Approve'     | 'CS33012FB03'           | 'R0402'             | '(R0402-0201)'                 | '30.1K'   | '1%'    | '1/16W'  | 'IO'       | 'RES CHIP 30.1K 1/16W +-1%(0402)EF'                | 'CHIPR0402'    | ''          | ''            | '20210715'
 '84.5K'      | '1%'      | '1/16W'  | '0402LF'  | 'CHIP'   | 'CS38452FB05'(!)        = 'End of Design' | 'Comp-Approve'     | 'CS38452FB05'           | 'R0402'             | '(R0402-0201)'                 | '84.5K'   | '1%'    | '1/16W'  | 'DISCRETE' | 'RES CHIP 84.5K 1/16W +-1%(0402)EF'                | 'CHIPR0402'    | ''          | ''            | '20210715'
 '84.5K'      | '1%'      | '1/16W'  | '0402LF'  | 'EMPTY'  | 'CS38452FB05'(!)        = 'End of Design' | 'Comp-Approve'     | 'CS38452FB05'           | 'R0402'             | '(R0402-0201)'                 | '84.5K'   | '1%'    | '1/16W'  | 'IO'       | 'RES CHIP 84.5K 1/16W +-1%(0402)EF'                | 'CHIPR0402'    | ''          | ''            | '20210715'
 '196K'       | '1%'      | '1/16W'  | '0402LF'  | 'CHIP'   | 'CS41962FB03'(!)        = 'End of Design' | 'Comp-Approve'     | 'CS41962FB03'           | 'R0402'             | '(R0402-0201)'                 | '196K'    | '1%'    | '1/16W'  | 'DISCRETE' | 'RES CHIP 196K 1/16W +-1%(0402)EF'                 | 'CHIPR0402'    | ''          | ''            | '20210715'
 '196K'       | '1%'      | '1/16W'  | '0402LF'  | 'EMPTY'  | 'CS41962FB03'(!)        = 'End of Design' | 'Comp-Approve'     | 'CS41962FB03'           | 'R0402'             | '(R0402-0201)'                 | '196K'    | '1%'    | '1/16W'  | 'IO'       | 'RES CHIP 196K 1/16W +-1%(0402)EF'                 | 'CHIPR0402'    | ''          | ''            | '20210715'
 '18K'        | '1%'      | '1/16W'  | '0402LF'  | 'CHIP'   | 'CS31802FB04'(!)        = ''              | ''                 | 'CS31802FB04'           | 'R0402'             | '(R0402-0201)'                 | '18K'     | '1%'    | '1/16W'  | 'DISCRETE' | 'RES CHIP 18K 1/16W +-1%(0402)EF'                  | 'CHIPR0402'    | ''          | ''            | '20210719'
 '18K'        | '1%'      | '1/16W'  | '0402LF'  | 'EMPTY'  | 'CS31802FB04'(!)        = ''              | ''                 | 'CS31802FB04'           | 'R0402'             | '(R0402-0201)'                 | '18K'     | '1%'    | '1/16W'  | 'IO'       | 'RES CHIP 18K 1/16W +-1%(0402)EF'                  | 'CHIPR0402'    | ''          | ''            | '20210719'
 '4.7'        | '1%'      | '1/16W'  | '0402LF'  | 'CHIP'   | 'CS-4702FB09'(!)        = ''              | ''                 | 'CS-4702FB09'           | 'R0402'             | '(R0402-0201)'                 | '4.7'     | '1%'    | '1/16W'  | 'DISCRETE' | 'RES CHIP 4.7 1/16W +-1%(0402)EF'                  | 'CHIPR0402'    | ''          | ''            | '20210719'
 '4.7'        | '1%'      | '1/16W'  | '0402LF'  | 'EMPTY'  | 'CS-4702FB09'(!)        = ''              | ''                 | 'CS-4702FB09'           | 'R0402'             | '(R0402-0201)'                 | '4.7'     | '1%'    | '1/16W'  | 'IO'       | 'RES CHIP 4.7 1/16W +-1%(0402)EF'                  | 'CHIPR0402'    | ''          | ''            | '20210719'
 '5.23K'      | '1%'      | '1/16W'  | '0402LF'  | 'CHIP'   | 'CS25232FB08'(!)        = ''              | ''                 | 'CS25232FB08'           | 'R0402'             | '(R0402-0201)'                 | '5.23K'   | '1%'    | '1/16W'  | 'DISCRETE' | 'RES CHIP 5.23K 1/16W +-1%(0402)EF'                | 'CHIPR0402'    | ''          | ''            | '20210719'
 '5.23K'      | '1%'      | '1/16W'  | '0402LF'  | 'EMPTY'  | 'CS25232FB08'(!)        = ''              | ''                 | 'CS25232FB08'           | 'R0402'             | '(R0402-0201)'                 | '5.23K'   | '1%'    | '1/16W'  | 'IO'       | 'RES CHIP 5.23K 1/16W +-1%(0402)EF'                | 'CHIPR0402'    | ''          | ''            | '20210719'
 '7.32K'      | '0.1%'    | '1/16W'  | '0402LF'  | 'CHIP'   | 'CS27322BB09'(!)        = ''              | ''                 | 'CS27322BB09'           | 'R0402'             | '(R0402-0201)'                 | '7.32K'   | '0.1%'  | '1/16W'  | 'DISCRETE' | 'RES CHIP 7.32K 1/16W +-0.1% (0402)EF'             | 'CHIPR0402'    | ''          | ''            | '20210719'
 '7.32K'      | '0.1%'    | '1/16W'  | '0402LF'  | 'EMPTY'  | 'CS27322BB09'(!)        = ''              | ''                 | 'CS27322BB09'           | 'R0402'             | '(R0402-0201)'                 | '7.32K'   | '0.1%'  | '1/16W'  | 'IO'       | 'RES CHIP 7.32K 1/16W +-0.1% (0402)EF'             | 'CHIPR0402'    | ''          | ''            | '20210719'
 '11.8K'      | '0.1%'    | '1/16W'  | '0402LF'  | 'CHIP'   | 'CS31182BB06'(!)        = ''              | ''                 | 'CS31182BB06'           | 'R0402'             | '(R0402-0201)'                 | '11.8K'   | '0.1%'  | '1/16W'  | 'DISCRETE' | 'RES CHIP 11.8K 1/16W +-0.1%(0402)EF'              | 'CHIPR0402'    | ''          | ''            | '20210719'
 '11.8K'      | '0.1%'    | '1/16W'  | '0402LF'  | 'EMPTY'  | 'CS31182BB06'(!)        = ''              | ''                 | 'CS31182BB06'           | 'R0402'             | '(R0402-0201)'                 | '11.8K'   | '0.1%'  | '1/16W'  | 'IO'       | 'RES CHIP 11.8K 1/16W +-0.1%(0402)EF'              | 'CHIPR0402'    | ''          | ''            | '20210719'
 '12.4K'      | '0.1%'    | '1/16W'  | '0402LF'  | 'CHIP'   | 'CS31242BB10'(!)        = ''              | ''                 | 'CS31242BB10'           | 'R0402'             | '(R0402-0201)'                 | '12.4K'   | '0.1%'  | '1/16W'  | 'DISCRETE' | 'RES CHIP 12.4K 1/16W +-0.1%( 0402)EF'             | 'CHIPR0402'    | ''          | ''            | '20210719'
 '12.4K'      | '0.1%'    | '1/16W'  | '0402LF'  | 'EMPTY'  | 'CS31242BB10'(!)        = ''              | ''                 | 'CS31242BB10'           | 'R0402'             | '(R0402-0201)'                 | '12.4K'   | '0.1%'  | '1/16W'  | 'IO'       | 'RES CHIP 12.4K 1/16W +-0.1%( 0402)EF'             | 'CHIPR0402'    | ''          | ''            | '20210719'
 '26.1K'      | '0.1%'    | '1/16W'  | '0402LF'  | 'CHIP'   | 'CS32612BB02'(!)        = ''              | ''                 | 'CS32612BB02'           | 'R0402'             | '(R0402-0201)'                 | '26.1K'   | '0.1%'  | '1/16W'  | 'DISCRETE' | 'RES CHIP 26.1K 1/16W +-0.1%(0402)EF'              | 'CHIPR0402'    | ''          | ''            | '20210720'
 '26.1K'      | '0.1%'    | '1/16W'  | '0402LF'  | 'EMPTY'  | 'CS32612BB02'(!)        = ''              | ''                 | 'CS32612BB02'           | 'R0402'             | '(R0402-0201)'                 | '26.1K'   | '0.1%'  | '1/16W'  | 'IO'       | 'RES CHIP 26.1K 1/16W +-0.1%(0402)EF'              | 'CHIPR0402'    | ''          | ''            | '20210720'
 '36K'        | '0.1%'    | '1/16W'  | '0402LF'  | 'CHIP'   | 'CS33602BB01'(!)        = ''              | ''                 | 'CS33602BB01'           | 'R0402'             | '(R0402-0201)'                 | '36K'     | '0.1%'  | '1/16W'  | 'DISCRETE' | 'RES CHIP 36K 1/16W +-0.1%(0402)EF'                | 'CHIPR0402'    | ''          | ''            | '20210720'
 '36K'        | '0.1%'    | '1/16W'  | '0402LF'  | 'EMPTY'  | 'CS33602BB01'(!)        = ''              | ''                 | 'CS33602BB01'           | 'R0402'             | '(R0402-0201)'                 | '36K'     | '0.1%'  | '1/16W'  | 'IO'       | 'RES CHIP 36K 1/16W +-0.1%(0402)EF'                | 'CHIPR0402'    | ''          | ''            | '20210720'
 '23.2K'      | '1%'      | '1/16W'  | '0402LF'  | 'CHIP'   | 'CS32322FB03'(!)        = 'End of Design' | 'Comp-Approve'     | 'CS32322FB03'           | 'R0402'             | '(R0402-0201)'                 | '23.2K'   | '1%'    | '1/16W'  | 'DISCRETE' | 'RES CHIP 23.2K 1/16W +-1%(0402)EF'                | 'CHIPR0402'    | ''          | ''            | '20210720'
 '23.2K'      | '1%'      | '1/16W'  | '0402LF'  | 'EMPTY'  | 'CS32322FB03'(!)        = 'End of Design' | 'Comp-Approve'     | 'CS32322FB03'           | 'R0402'             | '(R0402-0201)'                 | '23.2K'   | '1%'    | '1/16W'  | 'IO'       | 'RES CHIP 23.2K 1/16W +-1%(0402)EF'                | 'CHIPR0402'    | ''          | ''            | '20210720'
 '0.003'      | '1%'      | '3W'     | '2512LF'  | 'CHIP'   | 'CS+003DFR06'(!)        = ''              | ''                 | 'CS+003DFR06'           | 'R2512XZ'           | '(SMR2512AW)'                  | '0.003'   | '1%'    | '3W'     | 'DISCRETE' | 'RES CHIP 0.003 3W +-1%(2512)CYN'                  | 'CHIPR2512'    | ''          | ''            | '20210727'
 '0.003'      | '1%'      | '3W'     | '2512LF'  | 'EMPTY'  | 'CS+003DFR06'(!)        = ''              | ''                 | 'CS+003DFR06'           | 'R2512XZ'           | '(SMR2512AW)'                  | '0.003'   | '1%'    | '3W'     | 'IO'       | 'RES CHIP 0.003 3W +-1%(2512)CYN'                  | 'CHIPR2512'    | ''          | ''            | '20210727'
 '316'        | '1%'      | '1/16W'  | '0402LF'  | 'CHIP'   | 'CS13162FB01'(!)        = ''              | ''                 | 'CS13162FB01'           | 'R0402'             | '(R0402-0201)'                 | '316'     | '1%'    | '1/16W'  | 'DISCRETE' | 'RES CHIP 316 1/16W +-1%(0402)EF'                  | 'CHIPR0402'    | ''          | ''            | '20210727'
 '316'        | '1%'      | '1/16W'  | '0402LF'  | 'EMPTY'  | 'CS13162FB01'(!)        = ''              | ''                 | 'CS13162FB01'           | 'R0402'             | '(R0402-0201)'                 | '316'     | '1%'    | '1/16W'  | 'IO'       | 'RES CHIP 316 1/16W +-1%(0402)EF'                  | 'CHIPR0402'    | ''          | ''            | '20210727'
 '1K'         | '5%'      | '1/4W'   | '1206LF'  | 'CHIP'   | 'CS21006J202'(!)        = ''              | ''                 | 'CS21006J202'           | 'R1206XN'           | '(SMR1206AW)'                  | '1K'      | '5%'    | '1/4W'   | 'DISCRETE' | 'RES CHIP 1K 1/4W +-5%(1206)EF'                    | 'CHIPR1206'    | ''          | ''            | '20210727'
 '1K'         | '5%'      | '1/4W'   | '1206LF'  | 'EMPTY'  | 'CS21006J202'(!)        = ''              | ''                 | 'CS21006J202'           | 'R1206XN'           | '(SMR1206AW)'                  | '1K'      | '5%'    | '1/4W'   | 'IO'       | 'RES CHIP 1K 1/4W +-5%(1206)EF'                    | 'CHIPR1206'    | ''          | ''            | '20210727'
 '2.2K'       | '0.1%'    | '1/16W'  | '0402LF'  | 'CHIP'   | 'CS22202BB02'(!)        = ''              | ''                 | 'CS22202BB02'           | 'R0402'             | '(R0402-0201)'                 | '2.2K'    | '0.1%'  | '1/16W'  | 'DISCRETE' | 'RES CHIP 2.2K 1/16W +-0.1%(0402)'                 | 'CHIPR0402'    | ''          | ''            | '20210730'
 '2.2K'       | '0.1%'    | '1/16W'  | '0402LF'  | 'EMPTY'  | 'CS22202BB02'(!)        = ''              | ''                 | 'CS22202BB02'           | 'R0402'             | '(R0402-0201)'                 | '2.2K'    | '0.1%'  | '1/16W'  | 'IO'       | 'RES CHIP 2.2K 1/16W +-0.1%(0402)'                 | 'CHIPR0402'    | ''          | ''            | '20210730'
 '0.05'       | '1%'      | '1/2W'   | '1206LF'  | 'CHIP'   | 'CS+0507F200'(!)        = ''              | ''                 | 'CS+0507F200'           | 'R1206XQ'           | '(SMR1206AW)'                  | '0.05'    | '1%'    | '1/2W'   | 'DISCRETE' | 'RES CHIP 0.05 1/2W +-1%(1206)'                    | 'CHIPR1206'    | ''          | ''            | '20210802'
 '0.05'       | '1%'      | '1/2W'   | '1206LF'  | 'EMPTY'  | 'CS+0507F200'(!)        = ''              | ''                 | 'CS+0507F200'           | 'R1206XQ'           | '(SMR1206AW)'                  | '0.05'    | '1%'    | '1/2W'   | 'IO'       | 'RES CHIP 0.05 1/2W +-1%(1206)'                    | 'CHIPR1206'    | ''          | ''            | '20210802'
 '27.4'       | '1%'      | '1/20W'  | '0201LF'  | 'CHIP'   | 'CS02741FE02'(!)        = ''              | ''                 | 'CS02741FE02'           | 'R0201'             | '(SMR0201AW)'                  | '27.4'    | '1%'    | '1/20W'  | 'DISCRETE' | 'RES CHIP 27.4 1/20W +-1%(0201)EF'                 | 'CHIPR0201'    | ''          | ''            | '20210804'
 '27.4'       | '1%'      | '1/20W'  | '0201LF'  | 'EMPTY'  | 'CS02741FE02'(!)        = ''              | ''                 | 'CS02741FE02'           | 'R0201'             | '(SMR0201AW)'                  | '27.4'    | '1%'    | '1/20W'  | 'IO'       | 'RES CHIP 27.4 1/20W +-1%(0201)EF'                 | 'CHIPR0201'    | ''          | ''            | '20210804'
 '1.5K'       | '1%'      | '1/20W'  | '0201LF'  | 'CHIP'   | 'CS21501FE14'(!)        = ''              | ''                 | 'CS21501FE14'           | 'R0201'             | '(SMR0201AW)'                  | '1.5K'    | '1%'    | '1/20W'  | 'DISCRETE' | 'RES CHIP 1.5K 1/20W +-1%(0201)EF'                 | 'CHIPR0201'    | ''          | ''            | '20210804'
 '1.5K'       | '1%'      | '1/20W'  | '0201LF'  | 'EMPTY'  | 'CS21501FE14'(!)        = ''              | ''                 | 'CS21501FE14'           | 'R0201'             | '(SMR0201AW)'                  | '1.5K'    | '1%'    | '1/20W'  | 'IO'       | 'RES CHIP 1.5K 1/20W +-1%(0201)EF'                 | 'CHIPR0201'    | ''          | ''            | '20210804'
 '1.24K'      | '1%'      | '1/16W'  | '0402LF'  | 'CHIP'   | 'CS21242FB04'(!)        = 'End of Design' | 'Comp-Approve'     | 'CS21242FB04'           | 'R0402'             | '(R0402-0201)'                 | '1.24K'   | '1%'    | '1/16W'  | 'DISCRETE' | 'RES CHIP 1.24K 1/16W +-1%(0402)EF'                | 'CHIPR0402'    | ''          | ''            | '20210804'
 '1.24K'      | '1%'      | '1/16W'  | '0402LF'  | 'EMPTY'  | 'CS21242FB04'(!)        = 'End of Design' | 'Comp-Approve'     | 'CS21242FB04'           | 'R0402'             | '(R0402-0201)'                 | '1.24K'   | '1%'    | '1/16W'  | 'IO'       | 'RES CHIP 1.24K 1/16W +-1%(0402)EF'                | 'CHIPR0402'    | ''          | ''            | '20210804'
 '1.69K'      | '1%'      | '1/16W'  | '0402LF'  | 'CHIP'   | 'CS21692FB04'(!)        = 'End of Design' | 'Comp-Approve'     | 'CS21692FB04'           | 'R0402'             | '(R0402-0201)'                 | '1.69K'   | '1%'    | '1/16W'  | 'DISCRETE' | 'RES CHIP 1.69K 1/16W +-1%(0402)EF'                | 'CHIPR0402'    | ''          | ''            | '20210804'
 '1.69K'      | '1%'      | '1/16W'  | '0402LF'  | 'EMPTY'  | 'CS21692FB04'(!)        = 'End of Design' | 'Comp-Approve'     | 'CS21692FB04'           | 'R0402'             | '(R0402-0201)'                 | '1.69K'   | '1%'    | '1/16W'  | 'IO'       | 'RES CHIP 1.69K 1/16W +-1%(0402)EF'                | 'CHIPR0402'    | ''          | ''            | '20210804'
 '2.74K'      | '1%'      | '1/16W'  | '0402LF'  | 'CHIP'   | 'CS22742FB05'(!)        = 'End of Design' | 'Comp-Approve'     | 'CS22742FB05'           | 'R0402'             | '(R0402-0201)'                 | '2.74K'   | '1%'    | '1/16W'  | 'DISCRETE' | 'RES CHIP 2.74K 1/16W +-1%(0402)EF'                | 'CHIPR0402'    | ''          | ''            | '20210804'
 '2.74K'      | '1%'      | '1/16W'  | '0402LF'  | 'EMPTY'  | 'CS22742FB05'(!)        = 'End of Design' | 'Comp-Approve'     | 'CS22742FB05'           | 'R0402'             | '(R0402-0201)'                 | '2.74K'   | '1%'    | '1/16W'  | 'IO'       | 'RES CHIP 2.74K 1/16W +-1%(0402)EF'                | 'CHIPR0402'    | ''          | ''            | '20210804'
 '5.49K'      | '1%'      | '1/16W'  | '0402LF'  | 'CHIP'   | 'CS25492FB02'(!)        = 'End of Design' | 'Comp-Approve'     | 'CS25492FB02'           | 'R0402'             | '(R0402-0201)'                 | '5.49K'   | '1%'    | '1/16W'  | 'DISCRETE' | 'RES CHIP 5.49K 1/16W +-1%(0402) EF'               | 'CHIPR0402'    | ''          | ''            | '20210804'
 '5.49K'      | '1%'      | '1/16W'  | '0402LF'  | 'EMPTY'  | 'CS25492FB02'(!)        = 'End of Design' | 'Comp-Approve'     | 'CS25492FB02'           | 'R0402'             | '(R0402-0201)'                 | '5.49K'   | '1%'    | '1/16W'  | 'IO'       | 'RES CHIP 5.49K 1/16W +-1%(0402) EF'               | 'CHIPR0402'    | ''          | ''            | '20210804'
 '680'        | '0.1%'    | '1/16W'  | '0402LF'  | 'CHIP'   | 'CS16802BB00'(!)        = ''              | ''                 | 'CS16802BB00'           | 'R0402'             | '(R0402-0201)'                 | '680'     | '0.1%'  | '1/16W'  | 'DISCRETE' | 'RES CHIP 680 1/16W +-0.1%(0402)'                  | 'CHIPR0402'    | ''          | ''            | '20210804'
 '680'        | '0.1%'    | '1/16W'  | '0402LF'  | 'EMPTY'  | 'CS16802BB00'(!)        = ''              | ''                 | 'CS16802BB00'           | 'R0402'             | '(R0402-0201)'                 | '680'     | '0.1%'  | '1/16W'  | 'IO'       | 'RES CHIP 680 1/16W +-0.1%(0402)'                  | 'CHIPR0402'    | ''          | ''            | '20210804'
 '15K'        | '1%'      | '1/16W'  | '0402LF'  | 'CHIP'   | 'CS31502FB12'(!)        = ''              | ''                 | 'CS31502FB12'           | 'R0402'             | '(R0402-0201)'                 | '15K'     | '1%'    | '1/16W'  | 'DISCRETE' | 'RES CHIP 15K 1/16W +-1%(0402)TAI'                 | 'CHIPR0402'    | ''          | ''            | '20210809'
 '15K'        | '1%'      | '1/16W'  | '0402LF'  | 'EMPTY'  | 'CS31502FB12'(!)        = ''              | ''                 | 'CS31502FB12'           | 'R0402'             | '(R0402-0201)'                 | '15K'     | '1%'    | '1/16W'  | 'IO'       | 'RES CHIP 15K 1/16W +-1%(0402)TAI'                 | 'CHIPR0402'    | ''          | ''            | '20210809'
 '1.65K'      | '0.1%'    | '1/16W'  | '0402LF'  | 'CHIP'   | 'CS21652BB00'(!)        = ''              | ''                 | 'CS21652BB00'           | 'R0402'             | '(R0402-0201)'                 | '1.65K'   | '0.1%'  | '1/16W'  | 'DISCRETE' | 'RES CHIP 1.65K 1/16W +-0.1%(0402)'                | 'CHIPR0402'    | ''          | ''            | '20210811'
 '1.65K'      | '0.1%'    | '1/16W'  | '0402LF'  | 'EMPTY'  | 'CS21652BB00'(!)        = ''              | ''                 | 'CS21652BB00'           | 'R0402'             | '(R0402-0201)'                 | '1.65K'   | '0.1%'  | '1/16W'  | 'IO'       | 'RES CHIP 1.65K 1/16W +-0.1%(0402)'                | 'CHIPR0402'    | ''          | ''            | '20210811'
 '2.87K'      | '0.1%'    | '1/16W'  | '0402LF'  | 'CHIP'   | 'CS22872BB01'(!)        = ''              | ''                 | 'CS22872BB01'           | 'R0402'             | '(R0402-0201)'                 | '2.87K'   | '0.1%'  | '1/16W'  | 'DISCRETE' | 'RES CHIP 2.87K 1/16W+-0.1%( 0402)'                | 'CHIPR0402'    | ''          | ''            | '20210811'
 '2.87K'      | '0.1%'    | '1/16W'  | '0402LF'  | 'EMPTY'  | 'CS22872BB01'(!)        = ''              | ''                 | 'CS22872BB01'           | 'R0402'             | '(R0402-0201)'                 | '2.87K'   | '0.1%'  | '1/16W'  | 'IO'       | 'RES CHIP 2.87K 1/16W+-0.1%( 0402)'                | 'CHIPR0402'    | ''          | ''            | '20210811'
 '1.13K'      | '0.1%'    | '1/16W'  | '0402LF'  | 'CHIP'   | 'CS21132BB00'(!)        = ''              | ''                 | 'CS21132BB00'           | 'R0402'             | '(R0402-0201)'                 | '1.13K'   | '0.1%'  | '1/16W'  | 'DISCRETE' | 'RES CHIP 1.13K 1/16W+-0.1%( 0402)'                | 'CHIPR0402'    | ''          | ''            | '20210811'
 '1.13K'      | '0.1%'    | '1/16W'  | '0402LF'  | 'EMPTY'  | 'CS21132BB00'(!)        = ''              | ''                 | 'CS21132BB00'           | 'R0402'             | '(R0402-0201)'                 | '1.13K'   | '0.1%'  | '1/16W'  | 'IO'       | 'RES CHIP 1.13K 1/16W+-0.1%( 0402)'                | 'CHIPR0402'    | ''          | ''            | '20210811'
 '4.53K'      | '0.1%'    | '1/16W'  | '0402LF'  | 'CHIP'   | 'CS24532BB00'(!)        = ''              | ''                 | 'CS24532BB00'           | 'R0402'             | '(R0402-0201)'                 | '4.53K'   | '0.1%'  | '1/16W'  | 'DISCRETE' | 'RES CHIP 4.53K 1/16W+-0.1%( 0402)'                | 'CHIPR0402'    | ''          | ''            | '20210811'
 '4.53K'      | '0.1%'    | '1/16W'  | '0402LF'  | 'EMPTY'  | 'CS24532BB00'(!)        = ''              | ''                 | 'CS24532BB00'           | 'R0402'             | '(R0402-0201)'                 | '4.53K'   | '0.1%'  | '1/16W'  | 'IO'       | 'RES CHIP 4.53K 1/16W+-0.1%( 0402)'                | 'CHIPR0402'    | ''          | ''            | '20210811'
 '360'        | '1%'      | '1/16W'  | '0402LF'  | 'CHIP'   | 'CS13602FB00'(!)        = 'End of Design' | 'Comp-Approve'     | 'CS13602FB00'           | 'R0402'             | '(R0402-0201)'                 | '360'     | '1%'    | '1/16W'  | 'DISCRETE' | 'RES CHIP 360 1/16W +-1%(0402)'                    | 'CHIPR0402'    | ''          | ''            | '20210817'
 '360'        | '1%'      | '1/16W'  | '0402LF'  | 'EMPTY'  | 'CS13602FB00'(!)        = 'End of Design' | 'Comp-Approve'     | 'CS13602FB00'           | 'R0402'             | '(R0402-0201)'                 | '360'     | '1%'    | '1/16W'  | 'IO'       | 'RES CHIP 360 1/16W +-1%(0402)'                    | 'CHIPR0402'    | ''          | ''            | '20210817'
 '0.0002'     | '1%'      | '4W'     | '2725LF'  | 'CHIP'   | 'CS0000FFT11'(!)        = ''              | ''                 | 'CS0000FFT11'           | 'R2725'             | '(SMR2725AW)'                  | '0.0002'  | '1%'    | '4W'     | 'DISCRETE' | 'RES CHIP 0.0002 4W +-1%(2725)RLC'                 | 'CHIPR2725'    | ''          | ''            | '20210817'
 '0.0002'     | '1%'      | '4W'     | '2725LF'  | 'EMPTY'  | 'CS0000FFT11'(!)        = ''              | ''                 | 'CS0000FFT11'           | 'R2725'             | '(SMR2725AW)'                  | '0.0002'  | '1%'    | '4W'     | 'IO'       | 'RES CHIP 0.0002 4W +-1%(2725)RLC'                 | 'CHIPR2725'    | ''          | ''            | '20210817'
 '10K'        | '1%'      | '1/2W'   | '1206LF'  | 'CHIP'   | 'CS31007F200'(!)        = ''              | ''                 | 'CS31007F200'           | 'R1206XI'           | '(SMR1206AW)'                  | '10K'     | '1%'    | '1/2W'   | 'DISCRETE' | 'RES CHIP 10K 1/2W +-1%(1206)'                     | 'CHIPR1206'    | ''          | ''            | '20210820'
 '10K'        | '1%'      | '1/2W'   | '1206LF'  | 'EMPTY'  | 'CS31007F200'(!)        = ''              | ''                 | 'CS31007F200'           | 'R1206XI'           | '(SMR1206AW)'                  | '10K'     | '1%'    | '1/2W'   | 'IO'       | 'RES CHIP 10K 1/2W +-1%(1206)'                     | 'CHIPR1206'    | ''          | ''            | '20210820'
 '20K'        | '0.1%'    | '1/4W'   | '1206LF'  | 'CHIP'   | 'CS32006B200'(!)        = ''              | ''                 | 'CS32006B200'           | 'R1206XM'           | '(SMR1206AW)'                  | '20K'     | '0.1%'  | '1/4W'   | 'DISCRETE' | 'RES CHIP 20K 1/4W +-0.1%(1206)'                   | 'CHIPR1206'    | ''          | ''            | '20210823'
 '20K'        | '0.1%'    | '1/4W'   | '1206LF'  | 'EMPTY'  | 'CS32006B200'(!)        = ''              | ''                 | 'CS32006B200'           | 'R1206XM'           | '(SMR1206AW)'                  | '20K'     | '0.1%'  | '1/4W'   | 'IO'       | 'RES CHIP 20K 1/4W +-0.1%(1206)'                   | 'CHIPR1206'    | ''          | ''            | '20210823'
 '20K'        | '1%'      | '1/8W'   | '0805LF'  | 'CHIP'   | 'CS32004FA05'(!)        = ''              | ''                 | 'CS32004FA05'           | 'R0805_H26'         | '(SMR0805AW)'                  | '20K'     | '1%'    | '1/8W'   | 'DISCRETE' | 'RES CHIP 20K 1/8W +-1%(0805)EF'                   | 'CHIPR0805'    | ''          | ''            | '20210824'
 '20K'        | '1%'      | '1/8W'   | '0805LF'  | 'EMPTY'  | 'CS32004FA05'(!)        = ''              | ''                 | 'CS32004FA05'           | 'R0805_H26'         | '(SMR0805AW)'                  | '20K'     | '1%'    | '1/8W'   | 'IO'       | 'RES CHIP 20K 1/8W +-1%(0805)EF'                   | 'CHIPR0805'    | ''          | ''            | '20210824'
 '100'        | '1%'      | '1/8W'   | '0805LF'  | 'CHIP'   | 'CS11004FA05'(!)        = ''              | ''                 | 'CS11004FA05'           | 'R0805_H26'         | '(SMR0805AW)'                  | '100'     | '1%'    | '1/8W'   | 'DISCRETE' | 'RES CHIP 100 1/8W +-1%(0805)EF'                   | 'CHIPR0805'    | ''          | ''            | '20210824'
 '100'        | '1%'      | '1/8W'   | '0805LF'  | 'EMPTY'  | 'CS11004FA05'(!)        = ''              | ''                 | 'CS11004FA05'           | 'R0805_H26'         | '(SMR0805AW)'                  | '100'     | '1%'    | '1/8W'   | 'IO'       | 'RES CHIP 100 1/8W +-1%(0805)EF'                   | 'CHIPR0805'    | ''          | ''            | '20210824'
 '3.3K'       | '1%'      | '1/8W'   | '0805LF'  | 'CHIP'   | 'CS23304FA00'(!)        = ''              | ''                 | 'CS23304FA00'           | 'R0805_H26'         | '(SMR0805AW)'                  | '3.3K'    | '1%'    | '1/8W'   | 'DISCRETE' | 'RES CHIP 3.3K 1/8W +-1%(0805)EF'                  | 'CHIPR0805'    | ''          | ''            | '20210824'
 '3.3K'       | '1%'      | '1/8W'   | '0805LF'  | 'EMPTY'  | 'CS23304FA00'(!)        = ''              | ''                 | 'CS23304FA00'           | 'R0805_H26'         | '(SMR0805AW)'                  | '3.3K'    | '1%'    | '1/8W'   | 'IO'       | 'RES CHIP 3.3K 1/8W +-1%(0805)EF'                  | 'CHIPR0805'    | ''          | ''            | '20210824'
 '43K'        | '1%'      | '1/8W'   | '0805LF'  | 'CHIP'   | 'CS34304FA01'(!)        = ''              | ''                 | 'CS34304FA01'           | 'R0805_H26'         | '(SMR0805AW)'                  | '43K'     | '1%'    | '1/8W'   | 'DISCRETE' | 'RES CHIP 43K 1/8W +-1%(0805)EF'                   | 'CHIPR0805'    | ''          | ''            | '20210824'
 '43K'        | '1%'      | '1/8W'   | '0805LF'  | 'EMPTY'  | 'CS34304FA01'(!)        = ''              | ''                 | 'CS34304FA01'           | 'R0805_H26'         | '(SMR0805AW)'                  | '43K'     | '1%'    | '1/8W'   | 'IO'       | 'RES CHIP 43K 1/8W +-1%(0805)EF'                   | 'CHIPR0805'    | ''          | ''            | '20210824'
 '174K'       | '1%'      | '1/8W'   | '0805LF'  | 'CHIP'   | 'CS41744FA01'(!)        = ''              | ''                 | 'CS41744FA01'           | 'R0805_H26'         | '(SMR0805AW)'                  | '174K'    | '1%'    | '1/8W'   | 'DISCRETE' | 'RES CHIP 174K 1/8W +-1%(0805)EF'                  | 'CHIPR0805'    | ''          | ''            | '20210824'
 '174K'       | '1%'      | '1/8W'   | '0805LF'  | 'EMPTY'  | 'CS41744FA01'(!)        = ''              | ''                 | 'CS41744FA01'           | 'R0805_H26'         | '(SMR0805AW)'                  | '174K'    | '1%'    | '1/8W'   | 'IO'       | 'RES CHIP 174K 1/8W +-1%(0805)EF'                  | 'CHIPR0805'    | ''          | ''            | '20210824'
 '2.05M'      | '1%'      | '1/8W'   | '0805LF'  | 'CHIP'   | 'CS52054FA01'(!)        = ''              | ''                 | 'CS52054FA01'           | 'R0805_H26'         | '(SMR0805AW)'                  | '2.05M'   | '1%'    | '1/8W'   | 'DISCRETE' | 'RES CHIP 2.05M 1/8W +-1%(0805)EF'                 | 'CHIPR0805'    | ''          | ''            | '20210824'
 '2.05M'      | '1%'      | '1/8W'   | '0805LF'  | 'EMPTY'  | 'CS52054FA01'(!)        = ''              | ''                 | 'CS52054FA01'           | 'R0805_H26'         | '(SMR0805AW)'                  | '2.05M'   | '1%'    | '1/8W'   | 'IO'       | 'RES CHIP 2.05M 1/8W +-1%(0805)EF'                 | 'CHIPR0805'    | ''          | ''            | '20210824'
 '330K'       | '1%'      | '1/16W'  | '0402LF'  | 'CHIP'   | 'CS43302FB06'(!)        = ''              | ''                 | 'CS43302FB06'           | 'R0402'             | '(R0402-0201)'                 | '330K'    | '1%'    | '1/16W'  | 'DISCRETE' | 'RES CHIP 330K 1/16W +-1%(0402)EF'                 | 'CHIPR0402'    | ''          | ''            | '20210824'
 '330K'       | '1%'      | '1/16W'  | '0402LF'  | 'EMPTY'  | 'CS43302FB06'(!)        = ''              | ''                 | 'CS43302FB06'           | 'R0402'             | '(R0402-0201)'                 | '330K'    | '1%'    | '1/16W'  | 'IO'       | 'RES CHIP 330K 1/16W +-1%(0402)EF'                 | 'CHIPR0402'    | ''          | ''            | '20210824'
 '43K'        | '1%'      | '1/10W'  | '0603LF'  | 'CHIP'   | 'CS34303F905'(!)        = ''              | ''                 | 'CS34303F905'           | 'R0603'             | '(SMR0603AW)'                  | '43K'     | '1%'    | '1/10W'  | 'DISCRETE' | 'RES CHIP 43K 1/10W +-1%(0603)EF'                  | 'CHIPR0603'    | ''          | ''            | '20210824'
 '43K'        | '1%'      | '1/10W'  | '0603LF'  | 'EMPTY'  | 'CS34303F905'(!)        = ''              | ''                 | 'CS34303F905'           | 'R0603'             | '(SMR0603AW)'                  | '43K'     | '1%'    | '1/10W'  | 'IO'       | 'RES CHIP 43K 1/10W +-1%(0603)EF'                  | 'CHIPR0603'    | ''          | ''            | '20210824'
 '1K'         | '0.5%'    | '1/20W'  | '0201LF'  | 'CHIP'   | 'CS21001DE02'(!)        = ''              | ''                 | 'CS21001DE02'           | 'R0201'             | '(SMR0201AW)'                  | '1K'      | '0.5%'  | '1/20W'  | 'DISCRETE' | 'RES CHIP 1K 1/20W +-0.5%(0201)'                   | 'CHIPR0201'    | ''          | ''            | '20210825'
 '1K'         | '0.5%'    | '1/20W'  | '0201LF'  | 'EMPTY'  | 'CS21001DE02'(!)        = ''              | ''                 | 'CS21001DE02'           | 'R0201'             | '(SMR0201AW)'                  | '1K'      | '0.5%'  | '1/20W'  | 'IO'       | 'RES CHIP 1K 1/20W +-0.5%(0201)'                   | 'CHIPR0201'    | ''          | ''            | '20210825'
 '910'        | '1%'      | '1/2W'   | '1206LF'  | 'CHIP'   | 'CS19107F200'(!)        = ''              | ''                 | 'CS19107F200'           | 'R1206XF'           | '(SMR1206AW)'                  | '910'     | '1%'    | '1/2W'   | 'DISCRETE' | 'RES CHIP 910 1/2W +-1%(1206)'                     | 'CHIPR1206'    | ''          | ''            | '20210830'
 '910'        | '1%'      | '1/2W'   | '1206LF'  | 'EMPTY'  | 'CS19107F200'(!)        = ''              | ''                 | 'CS19107F200'           | 'R1206XF'           | '(SMR1206AW)'                  | '910'     | '1%'    | '1/2W'   | 'IO'       | 'RES CHIP 910 1/2W +-1%(1206)'                     | 'CHIPR1206'    | ''          | ''            | '20210830'
 '261'        | '1%'      | '1/10W'  | '0603LF'  | 'CHIP'   | 'CS12613F900'(!)        = ''              | ''                 | 'CS12613F900'           | 'R0603'             | '(SMR0603AW)'                  | '261'     | '1%'    | '1/10W'  | 'DISCRETE' | 'RES CHIP 261 1/10W +-1%(0603)'                    | 'CHIPR0603'    | ''          | ''            | '20210830'
 '261'        | '1%'      | '1/10W'  | '0603LF'  | 'EMPTY'  | 'CS12613F900'(!)        = ''              | ''                 | 'CS12613F900'           | 'R0603'             | '(SMR0603AW)'                  | '261'     | '1%'    | '1/10W'  | 'IO'       | 'RES CHIP 261 1/10W +-1%(0603)'                    | 'CHIPR0603'    | ''          | ''            | '20210830'
 '330'        | '1%'      | '1/2W'   | '1206LF'  | 'CHIP'   | 'CS13307F201'(!)        = ''              | ''                 | 'CS13307F201'           | 'R1206XT'           | '(SMR1206AW)'                  | '330'     | '1%'    | '1/2W'   | 'DISCRETE' | 'RES CHIP 330 1/2W+-1%(1206)SR'                    | 'CHIPR1206'    | ''          | ''            | '20210910'
 '330'        | '1%'      | '1/2W'   | '1206LF'  | 'EMPTY'  | 'CS13307F201'(!)        = ''              | ''                 | 'CS13307F201'           | 'R1206XT'           | '(SMR1206AW)'                  | '330'     | '1%'    | '1/2W'   | 'IO'       | 'RES CHIP 330 1/2W+-1%(1206)SR'                    | 'CHIPR1206'    | ''          | ''            | '20210910'
 '0'          | ''        | '1/3W'   | '0603LF'  | 'CHIP'   | 'CS0000CT900'(!)        = ''              | ''                 | 'CS0000CT900'           | 'R0603'             | '(SMR0603AW)'                  | '0'       | ''      | '1/3W'   | 'DISCRETE' | 'RES CHIP 0 1/3W (0603)WTC'                        | 'CHIPR0603'    | ''          | ''            | '20210910'
 '0'          | ''        | '1/3W'   | '0603LF'  | 'EMPTY'  | 'CS0000CT900'(!)        = ''              | ''                 | 'CS0000CT900'           | 'R0603'             | '(SMR0603AW)'                  | '0'       | ''      | '1/3W'   | 'IO'       | 'RES CHIP 0 1/3W (0603)WTC'                        | 'CHIPR0603'    | ''          | ''            | '20210910'
 '158K'       | '1%'      | '1/16W'  | '0402LF'  | 'CHIP'   | 'CS41582FB02'(!)        = ''              | ''                 | 'CS41582FB02'           | 'R0402'             | '(R0402-0201)'                 | '158K'    | '1%'    | '1/16W'  | 'DISCRETE' | 'RES CHIP 158K 1/16W +-1% (0402)EF'                | 'CHIPR0402'    | ''          | ''            | '20210916'
 '158K'       | '1%'      | '1/16W'  | '0402LF'  | 'EMPTY'  | 'CS41582FB02'(!)        = ''              | ''                 | 'CS41582FB02'           | 'R0402'             | '(R0402-0201)'                 | '158K'    | '1%'    | '1/16W'  | 'IO'       | 'RES CHIP 158K 1/16W +-1% (0402)EF'                | 'CHIPR0402'    | ''          | ''            | '20210916'
 '95.3K'      | '1%'      | '1/8W'   | '0805LF'  | 'CHIP'   | 'CS39534FA04'(!)        = ''              | ''                 | 'CS39534FA04'           | 'R0805_H26'         | '(SMR0805AW)'                  | '95.3K'   | '1%'    | '1/8W'   | 'DISCRETE' | 'RES CHIP 95.3K 1/8W +-1%(0805)EF'                 | 'CHIPR0805'    | ''          | ''            | '20210916'
 '95.3K'      | '1%'      | '1/8W'   | '0805LF'  | 'EMPTY'  | 'CS39534FA04'(!)        = ''              | ''                 | 'CS39534FA04'           | 'R0805_H26'         | '(SMR0805AW)'                  | '95.3K'   | '1%'    | '1/8W'   | 'IO'       | 'RES CHIP 95.3K 1/8W +-1%(0805)EF'                 | 'CHIPR0805'    | ''          | ''            | '20210916'
 '10'         | '1%'      | '1/10W'  | '0603LF'  | 'CHIP'   | 'CS01003F904'(!)        = 'End of Design' | 'Comp-Approve'     | 'CS01003F904'           | 'R0603_H24'         | '(SMR0603AW)'                  | '10'      | '1%'    | '1/10W'  | 'DISCRETE' | 'RES CHIP 10 1/10W +-1%(0603)EF'                   | 'CHIPR0603'    | ''          | ''            | '20210916'
 '10'         | '1%'      | '1/10W'  | '0603LF'  | 'EMPTY'  | 'CS01003F904'(!)        = 'End of Design' | 'Comp-Approve'     | 'CS01003F904'           | 'R0603_H24'         | '(SMR0603AW)'                  | '10'      | '1%'    | '1/10W'  | 'IO'       | 'RES CHIP 10 1/10W +-1%(0603)EF'                   | 'CHIPR0603'    | ''          | ''            | '20210916'
 '2.26K'      | '1%'      | '1/16W'  | '0402LF'  | 'CHIP'   | 'CS22262FB02'(!)        = 'End of Design' | 'Comp-Approve'     | 'CS22262FB02'           | 'R0402'             | '(R0402-0201)'                 | '2.26K'   | '1%'    | '1/16W'  | 'DISCRETE' | 'RES CHIP 2.26K 1/16W +-1%(0402)EF'                | 'CHIPR0402'    | ''          | ''            | '20210916'
 '2.26K'      | '1%'      | '1/16W'  | '0402LF'  | 'EMPTY'  | 'CS22262FB02'(!)        = 'End of Design' | 'Comp-Approve'     | 'CS22262FB02'           | 'R0402'             | '(R0402-0201)'                 | '2.26K'   | '1%'    | '1/16W'  | 'IO'       | 'RES CHIP 2.26K 1/16W +-1%(0402)EF'                | 'CHIPR0402'    | ''          | ''            | '20210916'
 '499K'       | '1%'      | '1/16W'  | '0402LF'  | 'CHIP'   | 'CS44992FB04'(!)        = 'End of Design' | 'Comp-Approve'     | 'CS44992FB04'           | 'R0402'             | '(R0402-0201)'                 | '499K'    | '1%'    | '1/16W'  | 'DISCRETE' | 'RES CHIP 499K 1/16W +-1% (0402)EF'                | 'CHIPR0402'    | ''          | ''            | '20210916'
 '499K'       | '1%'      | '1/16W'  | '0402LF'  | 'EMPTY'  | 'CS44992FB04'(!)        = 'End of Design' | 'Comp-Approve'     | 'CS44992FB04'           | 'R0402'             | '(R0402-0201)'                 | '499K'    | '1%'    | '1/16W'  | 'IO'       | 'RES CHIP 499K 1/16W +-1% (0402)EF'                | 'CHIPR0402'    | ''          | ''            | '20210916'
 '2.49K'      | '0.1%'    | '1/16W'  | '0402LF'  | 'CHIP'   | 'CS22492BB00'(!)        = ''              | ''                 | 'CS22492BB00'           | 'R0402'             | '(R0402-0201)'                 | '2.49K'   | '0.1%'  | '1/16W'  | 'DISCRETE' | 'RES CHIP 2.49K 1/16W +-0.1%(0402)'                | 'CHIPR0402'    | ''          | ''            | '20210916'
 '2.49K'      | '0.1%'    | '1/16W'  | '0402LF'  | 'EMPTY'  | 'CS22492BB00'(!)        = ''              | ''                 | 'CS22492BB00'           | 'R0402'             | '(R0402-0201)'                 | '2.49K'   | '0.1%'  | '1/16W'  | 'IO'       | 'RES CHIP 2.49K 1/16W +-0.1%(0402)'                | 'CHIPR0402'    | ''          | ''            | '20210916'
 '2.43K'      | '1%'      | '1/16W'  | '0402LF'  | 'CHIP'   | 'CS22432FB01'(!)        = 'End of Design' | 'Comp-Approve'     | 'CS22432FB01'           | 'R0402'             | '(R0402-0201)'                 | '2.43K'   | '1%'    | '1/16W'  | 'DISCRETE' | 'RES CHIP 2.43K 1/16W +-1%(0402)EF'                | 'CHIPR0402'    | ''          | ''            | '20210916'
 '2.43K'      | '1%'      | '1/16W'  | '0402LF'  | 'EMPTY'  | 'CS22432FB01'(!)        = 'End of Design' | 'Comp-Approve'     | 'CS22432FB01'           | 'R0402'             | '(R0402-0201)'                 | '2.43K'   | '1%'    | '1/16W'  | 'IO'       | 'RES CHIP 2.43K 1/16W +-1%(0402)EF'                | 'CHIPR0402'    | ''          | ''            | '20210916'
 '0.040'      | '1%'      | '1/2W'   | '1206LF'  | 'CHIP'   | 'CS+0407F200'(!)        = ''              | ''                 | 'CS+0407F200'           | 'R1206XG'           | '(SMR1206AW)'                  | '0.040'   | '1%'    | '1/2W'   | 'DISCRETE' | 'RES CHIP 0.040 1/2W,1%(1206)'                     | 'CHIPR1206'    | ''          | ''            | '20210917'
 '0.040'      | '1%'      | '1/2W'   | '1206LF'  | 'EMPTY'  | 'CS+0407F200'(!)        = ''              | ''                 | 'CS+0407F200'           | 'R1206XG'           | '(SMR1206AW)'                  | '0.040'   | '1%'    | '1/2W'   | 'IO'       | 'RES CHIP 0.040 1/2W,1%(1206)'                     | 'CHIPR1206'    | ''          | ''            | '20210917'
 '0'          | '5%'      | '1/4W'   | '0603LF'  | 'CHIP'   | 'CS00006J903'(!)        = ''              | ''                 | 'CS00006J903'           | 'R0603_H26'         | '(SMR0603AW)'                  | '0'       | '5%'    | '1/4W'   | 'DISCRETE' | 'RES CHIP 0 1/4W +-5%(0603)ERO'                    | 'CHIPR0603'    | ''          | ''            | '20210927'
 '0'          | '5%'      | '1/4W'   | '0603LF'  | 'EMPTY'  | 'CS00006J903'(!)        = ''              | ''                 | 'CS00006J903'           | 'R0603_H26'         | '(SMR0603AW)'                  | '0'       | '5%'    | '1/4W'   | 'IO'       | 'RES CHIP 0 1/4W +-5%(0603)ERO'                    | 'CHIPR0603'    | ''          | ''            | '20210927'
 '0.0005'     | '1%'      | '1.5W'   | '1206LF'  | 'CHIP'   | 'CS0000EF201'(!)        = ''              | ''                 | 'CS0000EF201'           | 'R1206XS'           | '(SMR1206AW)'                  | '0.0005'  | '1%'    | '1.5W'   | 'DISCRETE' | 'RES CHIP 0.0005 1.5W +-1% (1206)'                 | 'CHIPR1206'    | ''          | ''            | '20210928'
 '0.0005'     | '1%'      | '1.5W'   | '1206LF'  | 'EMPTY'  | 'CS0000EF201'(!)        = ''              | ''                 | 'CS0000EF201'           | 'R1206XS'           | '(SMR1206AW)'                  | '0.0005'  | '1%'    | '1.5W'   | 'IO'       | 'RES CHIP 0.0005 1.5W +-1% (1206)'                 | 'CHIPR1206'    | ''          | ''            | '20210928'
 '261'        | '1%'      | '1/10W'  | '0603LF'  | 'CHIP'   | 'CS12613F902'(!)        = ''              | ''                 | 'CS12613F902'           | 'R0603_H24'         | '(SMR0603AW)'                  | '261'     | '1%'    | '1/10W'  | 'DISCRETE' | 'RES CHIP 261 1/10W +-1%(0603)EF'                  | 'CHIPR0603'    | ''          | ''            | '20211026'
 '261'        | '1%'      | '1/10W'  | '0603LF'  | 'EMPTY'  | 'CS12613F902'(!)        = ''              | ''                 | 'CS12613F902'           | 'R0603_H24'         | '(SMR0603AW)'                  | '261'     | '1%'    | '1/10W'  | 'IO'       | 'RES CHIP 261 1/10W +-1%(0603)EF'                  | 'CHIPR0603'    | ''          | ''            | '20211026'
 '49.9'       | '1%'      | '1/10W'  | '0603LF'  | 'CHIP'   | 'CS04993F909'(!)        = 'End of Design' | 'Comp-Approve'     | 'CS04993F909'           | 'R0603'             | '(SMR0603AW)'                  | '49.9'    | '1%'    | '1/10W'  | 'DISCRETE' | 'RES CHIP 49.9 1/10W +-1%(0603)EF'                 | 'CHIPR0603'    | ''          | ''            | '20211026'
 '49.9'       | '1%'      | '1/10W'  | '0603LF'  | 'EMPTY'  | 'CS04993F909'(!)        = 'End of Design' | 'Comp-Approve'     | 'CS04993F909'           | 'R0603'             | '(SMR0603AW)'                  | '49.9'    | '1%'    | '1/10W'  | 'IO'       | 'RES CHIP 49.9 1/10W +-1%(0603)EF'                 | 'CHIPR0603'    | ''          | ''            | '20211026'
 '0'          | '5%'      | '1/4W'   | '0603LF'  | 'CHIP'   | 'CS00006J900'(!)        = ''              | ''                 | 'CS00006J900'           | 'R0603'             | '(SMR0603AW)'                  | '0'       | '5%'    | '1/4W'   | 'DISCRETE' | 'RES CHIP 0 1/4W +-5%(0603)'                       | 'CHIPR0603'    | ''          | ''            | '20211026'
 '0'          | '5%'      | '1/4W'   | '0603LF'  | 'EMPTY'  | 'CS00006J900'(!)        = ''              | ''                 | 'CS00006J900'           | 'R0603'             | '(SMR0603AW)'                  | '0'       | '5%'    | '1/4W'   | 'IO'       | 'RES CHIP 0 1/4W +-5%(0603)'                       | 'CHIPR0603'    | ''          | ''            | '20211026'
 '47K'        | '0.1%'    | '1/16W'  | '0402LF'  | 'CHIP'   | 'CS34702BB05'(!)        = ''              | ''                 | 'CS34702BB05'           | 'R0402'             | '(R0402-0201)'                 | '47K'     | '0.1%'  | '1/16W'  | 'DISCRETE' | 'RES CHIP 47K 1/16W +-0.1%(0402)EF'                | 'CHIPR0402'    | ''          | ''            | '20211028'
 '47K'        | '0.1%'    | '1/16W'  | '0402LF'  | 'EMPTY'  | 'CS34702BB05'(!)        = ''              | ''                 | 'CS34702BB05'           | 'R0402'             | '(R0402-0201)'                 | '47K'     | '0.1%'  | '1/16W'  | 'IO'       | 'RES CHIP 47K 1/16W +-0.1%(0402)EF'                | 'CHIPR0402'    | ''          | ''            | '20211028'
 '24K'        | '1%'      | '1/16W'  | '0402LF'  | 'CHIP'   | 'CS32402FB03'(!)        = ''              | ''                 | 'CS32402FB03'           | 'R0402'             | '(R0402-0201)'                 | '24K'     | '1%'    | '1/16W'  | 'DISCRETE' | 'RES CHIP 24K 1/16W +-1%(0402)EF'                  | 'CHIPR0402'    | ''          | ''            | '20211111'
 '24K'        | '1%'      | '1/16W'  | '0402LF'  | 'EMPTY'  | 'CS32402FB03'(!)        = ''              | ''                 | 'CS32402FB03'           | 'R0402'             | '(R0402-0201)'                 | '24K'     | '1%'    | '1/16W'  | 'IO'       | 'RES CHIP 24K 1/16W +-1%(0402)EF'                  | 'CHIPR0402'    | ''          | ''            | '20211111'
 '18.7K'      | '1%'      | '1/16W'  | '0402LF'  | 'CHIP'   | 'CS31872FB05'(!)        = ''              | ''                 | 'CS31872FB05'           | 'R0402'             | '(R0402-0201)'                 | '18.7K'   | '1%'    | '1/16W'  | 'DISCRETE' | 'RES CHIP 18.7K 1/16W +-1%(0402)EF'                | 'CHIPR0402'    | ''          | ''            | '20211111'
 '18.7K'      | '1%'      | '1/16W'  | '0402LF'  | 'EMPTY'  | 'CS31872FB05'(!)        = ''              | ''                 | 'CS31872FB05'           | 'R0402'             | '(R0402-0201)'                 | '18.7K'   | '1%'    | '1/16W'  | 'IO'       | 'RES CHIP 18.7K 1/16W +-1%(0402)EF'                | 'CHIPR0402'    | ''          | ''            | '20211111'
 '820K'       | '1%'      | '1/16W'  | '0402LF'  | 'CHIP'   | 'CS48202FB00'(!)        = 'End of Design' | 'Comp-Approve'     | 'CS48202FB00'           | 'R0402'             | '(R0402-0201)'                 | '820K'    | '1%'    | '1/16W'  | 'DISCRETE' | 'RES CHIP 820K 1/16W +-1%(0402)'                   | 'CHIPR0402'    | ''          | ''            | '20211124'
 '820K'       | '1%'      | '1/16W'  | '0402LF'  | 'EMPTY'  | 'CS48202FB00'(!)        = 'End of Design' | 'Comp-Approve'     | 'CS48202FB00'           | 'R0402'             | '(R0402-0201)'                 | '820K'    | '1%'    | '1/16W'  | 'IO'       | 'RES CHIP 820K 1/16W +-1%(0402)'                   | 'CHIPR0402'    | ''          | ''            | '20211124'
 '36'         | '1%'      | '1/20W'  | '0201LF'  | 'CHIP'   | 'CS03601FE00'(!)        = ''              | ''                 | 'CS03601FE00'           | 'R0201'             | '(SMR0201AW)'                  | '36'      | '1%'    | '1/20W'  | 'DISCRETE' | 'RES CHIP 36 1/20W,+-1%(0201)'                     | 'CHIPR0201'    | ''          | ''            | '20211130'
 '36'         | '1%'      | '1/20W'  | '0201LF'  | 'EMPTY'  | 'CS03601FE00'(!)        = ''              | ''                 | 'CS03601FE00'           | 'R0201'             | '(SMR0201AW)'                  | '36'      | '1%'    | '1/20W'  | 'IO'       | 'RES CHIP 36 1/20W,+-1%(0201)'                     | 'CHIPR0201'    | ''          | ''            | '20211130'
 '75K'        | '0.1%'    | '1/16W'  | '0402LF'  | 'CHIP'   | 'CS37502BB01'(!)        = ''              | ''                 | 'CS37502BB01'           | 'R0402'             | '(R0402-0201)'                 | '75K'     | '0.1%'  | '1/16W'  | 'DISCRETE' | 'RES CHIP 75K 1/16W +-0.1%(0402)EF'                | 'CHIPR0402'    | ''          | ''            | '20211207'
 '75K'        | '0.1%'    | '1/16W'  | '0402LF'  | 'EMPTY'  | 'CS37502BB01'(!)        = ''              | ''                 | 'CS37502BB01'           | 'R0402'             | '(R0402-0201)'                 | '75K'     | '0.1%'  | '1/16W'  | 'IO'       | 'RES CHIP 75K 1/16W +-0.1%(0402)EF'                | 'CHIPR0402'    | ''          | ''            | '20211207'
 '2K'         | '0.1%'    | '1/16W'  | '0402LF'  | 'CHIP'   | 'CS22002BB07'(!)        = ''              | ''                 | 'CS22002BB07'           | 'R0402'             | '(R0402-0201)'                 | '2K'      | '0.1%'  | '1/16W'  | 'DISCRETE' | 'RES CHIP 2K 1/16W +-0.1%(0402)EF'                 | 'CHIPR0402'    | ''          | ''            | '20211207'
 '2K'         | '0.1%'    | '1/16W'  | '0402LF'  | 'EMPTY'  | 'CS22002BB07'(!)        = ''              | ''                 | 'CS22002BB07'           | 'R0402'             | '(R0402-0201)'                 | '2K'      | '0.1%'  | '1/16W'  | 'IO'       | 'RES CHIP 2K 1/16W +-0.1%(0402)EF'                 | 'CHIPR0402'    | ''          | ''            | '20211207'
 '2.2'        | '1%'      | '1/8W'   | '0805LF'  | 'CHIP'   | 'CS-2204FA02'(!)        = 'End of Design' | 'Comp-Approve'     | 'CS-2204FA02'           | 'R0805'             | '(SMR0805AW)'                  | '2.2'     | '1%'    | '1/8W'   | 'DISCRETE' | 'RES CHIP 2.2 1/8W +-1%(0805)EF'                   | 'CHIPR0805'    | ''          | ''            | '20211210'
 '2.2'        | '1%'      | '1/8W'   | '0805LF'  | 'EMPTY'  | 'CS-2204FA02'(!)        = 'End of Design' | 'Comp-Approve'     | 'CS-2204FA02'           | 'R0805'             | '(SMR0805AW)'                  | '2.2'     | '1%'    | '1/8W'   | 'IO'       | 'RES CHIP 2.2 1/8W +-1%(0805)EF'                   | 'CHIPR0805'    | ''          | ''            | '20211210'
 '1.65K'      | '1%'      | '1/16W'  | '0402LF'  | 'CHIP'   | 'CS21652FB05'(!)        = 'End of Design' | 'Comp-Approve'     | 'CS21652FB05'           | 'R0402'             | '(R0402-0201)'                 | '1.65K'   | '1%'    | '1/16W'  | 'DISCRETE' | 'RES CHIP 1.65K 1/16W +-1%(0402)EF'                | 'CHIPR0402'    | ''          | ''            | '20211214'
 '1.65K'      | '1%'      | '1/16W'  | '0402LF'  | 'EMPTY'  | 'CS21652FB05'(!)        = 'End of Design' | 'Comp-Approve'     | 'CS21652FB05'           | 'R0402'             | '(R0402-0201)'                 | '1.65K'   | '1%'    | '1/16W'  | 'IO'       | 'RES CHIP 1.65K 1/16W +-1%(0402)EF'                | 'CHIPR0402'    | ''          | ''            | '20211214'
 '3.83K'      | '1%'      | '1/16W'  | '0402LF'  | 'CHIP'   | 'CS23832FB04'(!)        = 'End of Design' | 'Comp-Approve'     | 'CS23832FB04'           | 'R0402'             | '(R0402-0201)'                 | '3.83K'   | '1%'    | '1/16W'  | 'DISCRETE' | 'RES CHIP 3.83K 1/16W +-1%(0402)EF'                | 'CHIPR0402'    | ''          | ''            | '20211214'
 '3.83K'      | '1%'      | '1/16W'  | '0402LF'  | 'EMPTY'  | 'CS23832FB04'(!)        = 'End of Design' | 'Comp-Approve'     | 'CS23832FB04'           | 'R0402'             | '(R0402-0201)'                 | '3.83K'   | '1%'    | '1/16W'  | 'IO'       | 'RES CHIP 3.83K 1/16W +-1%(0402)EF'                | 'CHIPR0402'    | ''          | ''            | '20211214'
 '4.99K'      | '0.1%'    | '1/16W'  | '0402LF'  | 'CHIP'   | 'CS24992BB04'(!)        = ''              | ''                 | 'CS24992BB04'           | 'R0402'             | '(R0402-0201)'                 | '4.99K'   | '0.1%'  | '1/16W'  | 'DISCRETE' | 'RES CHIP 4.99K 1/16W +-0.1%(0402)EF'              | 'CHIPR0402'    | ''          | ''            | '20211216'
 '4.99K'      | '0.1%'    | '1/16W'  | '0402LF'  | 'EMPTY'  | 'CS24992BB04'(!)        = ''              | ''                 | 'CS24992BB04'           | 'R0402'             | '(R0402-0201)'                 | '4.99K'   | '0.1%'  | '1/16W'  | 'IO'       | 'RES CHIP 4.99K 1/16W +-0.1%(0402)EF'              | 'CHIPR0402'    | ''          | ''            | '20211216'
 '9.53K'      | '1%'      | '1/16W'  | '0402LF'  | 'CHIP'   | 'CS29532FB06'(!)        = ''              | ''                 | 'CS29532FB06'           | 'R0402'             | '(R0402-0201)'                 | '9.53K'   | '1%'    | '1/16W'  | 'DISCRETE' | 'RES CHIP 9.53K 1/16W +-1%(0402)EF'                | 'CHIPR0402'    | ''          | ''            | '20211216'
 '9.53K'      | '1%'      | '1/16W'  | '0402LF'  | 'EMPTY'  | 'CS29532FB06'(!)        = ''              | ''                 | 'CS29532FB06'           | 'R0402'             | '(R0402-0201)'                 | '9.53K'   | '1%'    | '1/16W'  | 'IO'       | 'RES CHIP 9.53K 1/16W +-1%(0402)EF'                | 'CHIPR0402'    | ''          | ''            | '20211216'
 '37.4K'      | '1%'      | '1/16W'  | '0402LF'  | 'CHIP'   | 'CS33742FB05'(!)        = 'End of Design' | 'Comp-Approve'     | 'CS33742FB05'           | 'R0402'             | '(R0402-0201)'                 | '37.4K'   | '1%'    | '1/16W'  | 'DISCRETE' | 'RES CHIP 37.4K 1/16W +-1%(0402)EF'                | 'CHIPR0402'    | ''          | ''            | '20211216'
 '37.4K'      | '1%'      | '1/16W'  | '0402LF'  | 'EMPTY'  | 'CS33742FB05'(!)        = 'End of Design' | 'Comp-Approve'     | 'CS33742FB05'           | 'R0402'             | '(R0402-0201)'                 | '37.4K'   | '1%'    | '1/16W'  | 'IO'       | 'RES CHIP 37.4K 1/16W +-1%(0402)EF'                | 'CHIPR0402'    | ''          | ''            | '20211216'
 '3.01K'      | '1%'      | '1/16W'  | '0402LF'  | 'CHIP'   | 'CS23012FB04'(!)        = 'End of Design' | 'Comp-Approve'     | 'CS23012FB04'           | 'R0402'             | '(R0402-0201)'                 | '3.01K'   | '1%'    | '1/16W'  | 'DISCRETE' | 'RES CHIP 3.01K 1/16W +-1%(0402)EF'                | 'CHIPR0402'    | ''          | ''            | '20211222'
 '3.01K'      | '1%'      | '1/16W'  | '0402LF'  | 'EMPTY'  | 'CS23012FB04'(!)        = 'End of Design' | 'Comp-Approve'     | 'CS23012FB04'           | 'R0402'             | '(R0402-0201)'                 | '3.01K'   | '1%'    | '1/16W'  | 'IO'       | 'RES CHIP 3.01K 1/16W +-1%(0402)EF'                | 'CHIPR0402'    | ''          | ''            | '20211222'
 '3K'         | '1%'      | '1/16W'  | '0402LF'  | 'CHIP'   | 'CS23002FB02'(!)        = 'End of Design' | 'Comp-Approve'     | 'CS23002FB02'           | 'R0402'             | '(R0402-0201)'                 | '3K'      | '1%'    | '1/16W'  | 'DISCRETE' | 'RES CHIP 3K 1/16W +-1%(0402)EF'                   | 'CHIPR0402'    | ''          | ''            | '20211222'
 '3K'         | '1%'      | '1/16W'  | '0402LF'  | 'EMPTY'  | 'CS23002FB02'(!)        = 'End of Design' | 'Comp-Approve'     | 'CS23002FB02'           | 'R0402'             | '(R0402-0201)'                 | '3K'      | '1%'    | '1/16W'  | 'IO'       | 'RES CHIP 3K 1/16W +-1%(0402)EF'                   | 'CHIPR0402'    | ''          | ''            | '20211222'
 '8.2K'       | '1%'      | '1/16W'  | '0402LF'  | 'CHIP'   | 'CS28202FB01'(!)        = 'End of Design' | 'Comp-Approve'     | 'CS28202FB01'           | 'R0402'             | '(R0402-0201)'                 | '8.2K'    | '1%'    | '1/16W'  | 'DISCRETE' | 'RES CHIP 8.2K 1/16W +-1%(0402)EF'                 | 'CHIPR0402'    | ''          | ''            | '20211222'
 '8.2K'       | '1%'      | '1/16W'  | '0402LF'  | 'EMPTY'  | 'CS28202FB01'(!)        = 'End of Design' | 'Comp-Approve'     | 'CS28202FB01'           | 'R0402'             | '(R0402-0201)'                 | '8.2K'    | '1%'    | '1/16W'  | 'IO'       | 'RES CHIP 8.2K 1/16W +-1%(0402)EF'                 | 'CHIPR0402'    | ''          | ''            | '20211222'
 '825'        | '1%'      | '1/16W'  | '0402LF'  | 'CHIP'   | 'CS18252FB03'(!)        = 'End of Design' | 'Comp-Approve'     | 'CS18252FB03'           | 'R0402'             | '(R0402-0201)'                 | '825'     | '1%'    | '1/16W'  | 'DISCRETE' | 'RES CHIP 825 1/16W +-1% (0402) EF'                | 'CHIPR0402'    | ''          | ''            | '20211222'
 '825'        | '1%'      | '1/16W'  | '0402LF'  | 'EMPTY'  | 'CS18252FB03'(!)        = 'End of Design' | 'Comp-Approve'     | 'CS18252FB03'           | 'R0402'             | '(R0402-0201)'                 | '825'     | '1%'    | '1/16W'  | 'IO'       | 'RES CHIP 825 1/16W +-1% (0402) EF'                | 'CHIPR0402'    | ''          | ''            | '20211222'
 '2.8K'       | '1%'      | '1/16W'  | '0402LF'  | 'CHIP'   | 'CS22802FB04'(!)        = 'End of Design' | 'Comp-Approve'     | 'CS22802FB04'           | 'R0402'             | '(R0402-0201)'                 | '2.8K'    | '1%'    | '1/16W'  | 'DISCRETE' | 'RES CHIP 2.8K 1/16W +-1%(0402)EF'                 | 'CHIPR0402'    | ''          | ''            | '20211222'
 '2.8K'       | '1%'      | '1/16W'  | '0402LF'  | 'EMPTY'  | 'CS22802FB04'(!)        = 'End of Design' | 'Comp-Approve'     | 'CS22802FB04'           | 'R0402'             | '(R0402-0201)'                 | '2.8K'    | '1%'    | '1/16W'  | 'IO'       | 'RES CHIP 2.8K 1/16W +-1%(0402)EF'                 | 'CHIPR0402'    | ''          | ''            | '20211222'
 '3.3'        | '1%'      | '1/10W'  | '0603LF'  | 'CHIP'   | 'CS-3303F905'(!)        = ''              | ''                 | 'CS-3303F905'           | 'R0603'             | '(SMR0603AW)'                  | '3.3'     | '1%'    | '1/10W'  | 'DISCRETE' | 'RES CHIP 3.3 1/10W +-1%(0603)EF'                  | 'CHIPR0603'    | ''          | ''            | '20211224'
 '3.3'        | '1%'      | '1/10W'  | '0603LF'  | 'EMPTY'  | 'CS-3303F905'(!)        = ''              | ''                 | 'CS-3303F905'           | 'R0603'             | '(SMR0603AW)'                  | '3.3'     | '1%'    | '1/10W'  | 'IO'       | 'RES CHIP 3.3 1/10W +-1%(0603)EF'                  | 'CHIPR0603'    | ''          | ''            | '20211224'
 '499'        | '1%'      | '1/10W'  | '0603LF'  | 'CHIP'   | 'CS14993F901'(!)        = 'End of Design' | 'Comp-Approve'     | 'CS14993F901'           | 'R0603'             | '(SMR0603AW)'                  | '499'     | '1%'    | '1/10W'  | 'DISCRETE' | 'RES CHIP 499 1/10W +-1%(0603)EF'                  | 'CHIPR0603'    | ''          | ''            | '20211227'
 '499'        | '1%'      | '1/10W'  | '0603LF'  | 'EMPTY'  | 'CS14993F901'(!)        = 'End of Design' | 'Comp-Approve'     | 'CS14993F901'           | 'R0603'             | '(SMR0603AW)'                  | '499'     | '1%'    | '1/10W'  | 'IO'       | 'RES CHIP 499 1/10W +-1%(0603)EF'                  | 'CHIPR0603'    | ''          | ''            | '20211227'
 '48.7K'      | '1%'      | '1/16W'  | '0402LF'  | 'CHIP'   | 'CS34872FB03'(!)        = 'End of Design' | 'Comp-Approve'     | 'CS34872FB03'           | 'R0402'             | '(R0402-0201)'                 | '48.7K'   | '1%'    | '1/16W'  | 'DISCRETE' | 'RES CHIP 48.7K 1/16W +-1%(0402)EF'                | 'CHIPR0402'    | ''          | ''            | '20211227'
 '48.7K'      | '1%'      | '1/16W'  | '0402LF'  | 'EMPTY'  | 'CS34872FB03'(!)        = 'End of Design' | 'Comp-Approve'     | 'CS34872FB03'           | 'R0402'             | '(R0402-0201)'                 | '48.7K'   | '1%'    | '1/16W'  | 'IO'       | 'RES CHIP 48.7K 1/16W +-1%(0402)EF'                | 'CHIPR0402'    | ''          | ''            | '20211227'
 '1.3K'       | '1%'      | '1/16W'  | '0402LF'  | 'CHIP'   | 'CS21302FB07'(!)        = ''              | ''                 | 'CS21302FB07'           | 'R0402'             | '(R0402-0201)'                 | '1.3K'    | '1%'    | '1/16W'  | 'DISCRETE' | 'RES CHIP 1.3K 1/16W +-1%(0402)EF'                 | 'CHIPR0402'    | ''          | ''            | '20220106'
 '1.3K'       | '1%'      | '1/16W'  | '0402LF'  | 'EMPTY'  | 'CS21302FB07'(!)        = ''              | ''                 | 'CS21302FB07'           | 'R0402'             | '(R0402-0201)'                 | '1.3K'    | '1%'    | '1/16W'  | 'IO'       | 'RES CHIP 1.3K 1/16W +-1%(0402)EF'                 | 'CHIPR0402'    | ''          | ''            | '20220106'
 '499K'       | '1%'      | '1/8W'   | '0805LF'  | 'CHIP'   | 'CS44994FA04'(!)        = ''              | ''                 | 'CS44994FA04'           | 'R0805_H26'         | '(SMR0805AW)'                  | '499K'    | '1%'    | '1/8W'   | 'DISCRETE' | 'RES CHIP 499K 1/8W+-1%(0805)EF'                   | 'CHIPR0805'    | ''          | ''            | '20220107'
 '499K'       | '1%'      | '1/8W'   | '0805LF'  | 'EMPTY'  | 'CS44994FA04'(!)        = ''              | ''                 | 'CS44994FA04'           | 'R0805_H26'         | '(SMR0805AW)'                  | '499K'    | '1%'    | '1/8W'   | 'IO'       | 'RES CHIP 499K 1/8W+-1%(0805)EF'                   | 'CHIPR0805'    | ''          | ''            | '20220107'
 '1'          | '1%'      | '2W'     | '2512LF'  | 'CHIP'   | 'CS-100AFR03'(!)        = ''              | ''                 | 'CS-100AFR03'           | 'R2512XU_H30'       | '(SMR2512AW)'                  | '1'       | '1%'    | '2W'     | 'DISCRETE' | 'RES CHIP 1 2W +-1%(2512)EF'                       | 'CHIPR2512'    | ''          | ''            | '20220111'
 '1'          | '1%'      | '2W'     | '2512LF'  | 'EMPTY'  | 'CS-100AFR03'(!)        = ''              | ''                 | 'CS-100AFR03'           | 'R2512XU_H30'       | '(SMR2512AW)'                  | '1'       | '1%'    | '2W'     | 'IO'       | 'RES CHIP 1 2W +-1%(2512)EF'                       | 'CHIPR2512'    | ''          | ''            | '20220111'
 '3.01'       | '1%'      | '1/16W'  | '0402LF'  | 'CHIP'   | 'CS-3012FB00'(!)        = ''              | ''                 | 'CS-3012FB00'           | 'R0402'             | '(R0402-0201)'                 | '3.01'    | '1%'    | '1/16W'  | 'DISCRETE' | 'RES CHIP 3.01 1/16W +-1% (0402)EF'                | 'CHIPR0402'    | ''          | ''            | '20220111'
 '3.01'       | '1%'      | '1/16W'  | '0402LF'  | 'EMPTY'  | 'CS-3012FB00'(!)        = ''              | ''                 | 'CS-3012FB00'           | 'R0402'             | '(R0402-0201)'                 | '3.01'    | '1%'    | '1/16W'  | 'IO'       | 'RES CHIP 3.01 1/16W +-1% (0402)EF'                | 'CHIPR0402'    | ''          | ''            | '20220111'
 '4.99'       | '1%'      | '1/16W'  | '0402LF'  | 'CHIP'   | 'CS-4992FB02'(!)        = 'End of Design' | 'Comp-Approve'     | 'CS-4992FB02'           | 'R0402'             | '(R0402-0201)'                 | '4.99'    | '1%'    | '1/16W'  | 'DISCRETE' | 'RES CHIP 4.99 1/16W +-1%(0402)EF'                 | 'CHIPR0402'    | ''          | ''            | '20220111'
 '4.99'       | '1%'      | '1/16W'  | '0402LF'  | 'EMPTY'  | 'CS-4992FB02'(!)        = 'End of Design' | 'Comp-Approve'     | 'CS-4992FB02'           | 'R0402'             | '(R0402-0201)'                 | '4.99'    | '1%'    | '1/16W'  | 'IO'       | 'RES CHIP 4.99 1/16W +-1%(0402)EF'                 | 'CHIPR0402'    | ''          | ''            | '20220111'
 '1.07K'      | '1%'      | '1/16W'  | '0402LF'  | 'CHIP'   | 'CS21072FB04'(!)        = ''              | ''                 | 'CS21072FB04'           | 'R0402'             | '(R0402-0201)'                 | '1.07K'   | '1%'    | '1/16W'  | 'DISCRETE' | 'RES CHIP 1.07K 1/16W +-1%(0402)EF'                | 'CHIPR0402'    | ''          | ''            | '20220118'
 '1.07K'      | '1%'      | '1/16W'  | '0402LF'  | 'EMPTY'  | 'CS21072FB04'(!)        = ''              | ''                 | 'CS21072FB04'           | 'R0402'             | '(R0402-0201)'                 | '1.07K'   | '1%'    | '1/16W'  | 'IO'       | 'RES CHIP 1.07K 1/16W +-1%(0402)EF'                | 'CHIPR0402'    | ''          | ''            | '20220118'
 '390K'       | '1%'      | '1/16W'  | '0402LF'  | 'CHIP'   | 'CS43902FB01'(!)        = ''              | ''                 | 'CS43902FB01'           | 'R0402'             | '(R0402-0201)'                 | '390K'    | '1%'    | '1/16W'  | 'DISCRETE' | 'RES CHIP 390K 1/16W +-1%(0402)EF'                 | 'CHIPR0402'    | ''          | ''            | '20220207'
 '390K'       | '1%'      | '1/16W'  | '0402LF'  | 'EMPTY'  | 'CS43902FB01'(!)        = ''              | ''                 | 'CS43902FB01'           | 'R0402'             | '(R0402-0201)'                 | '390K'    | '1%'    | '1/16W'  | 'IO'       | 'RES CHIP 390K 1/16W +-1%(0402)EF'                 | 'CHIPR0402'    | ''          | ''            | '20220207'
 '1.96K'      | '1%'      | '1/16W'  | '0402LF'  | 'CHIP'   | 'CS21962FB05'(!)        = ''              | ''                 | 'CS21962FB05'           | 'R0402'             | '(R0402-0201)'                 | '1.96K'   | '1%'    | '1/16W'  | 'DISCRETE' | 'RES CHIP 1.96K 1/16W +-1%(0402)EF'                | 'CHIPR0402'    | ''          | ''            | '20220208'
 '1.96K'      | '1%'      | '1/16W'  | '0402LF'  | 'EMPTY'  | 'CS21962FB05'(!)        = ''              | ''                 | 'CS21962FB05'           | 'R0402'             | '(R0402-0201)'                 | '1.96K'   | '1%'    | '1/16W'  | 'IO'       | 'RES CHIP 1.96K 1/16W +-1%(0402)EF'                | 'CHIPR0402'    | ''          | ''            | '20220208'
 '3.09K'      | '1%'      | '1/16W'  | '0402LF'  | 'CHIP'   | 'CS23092FB04'(!)        = ''              | ''                 | 'CS23092FB04'           | 'R0402'             | '(R0402-0201)'                 | '3.09K'   | '1%'    | '1/16W'  | 'DISCRETE' | 'RES CHIP 3.09K 1/16W +-1%(0402)EF'                | 'CHIPR0402'    | ''          | ''            | '20220209'
 '3.09K'      | '1%'      | '1/16W'  | '0402LF'  | 'EMPTY'  | 'CS23092FB04'(!)        = ''              | ''                 | 'CS23092FB04'           | 'R0402'             | '(R0402-0201)'                 | '3.09K'   | '1%'    | '1/16W'  | 'IO'       | 'RES CHIP 3.09K 1/16W +-1%(0402)EF'                | 'CHIPR0402'    | ''          | ''            | '20220209'
 '8.66K'      | '1%'      | '1/16W'  | '0402LF'  | 'CHIP'   | 'CS28662FB02'(!)        = 'End of Design' | 'Comp-Approve'     | 'CS28662FB02'           | 'R0402'             | '(R0402-0201)'                 | '8.66K'   | '1%'    | '1/16W'  | 'DISCRETE' | 'RES CHIP 8.66K 1/16W +-1%(0402)EF'                | 'CHIPR0402'    | ''          | ''            | '20220216'
 '8.66K'      | '1%'      | '1/16W'  | '0402LF'  | 'EMPTY'  | 'CS28662FB02'(!)        = 'End of Design' | 'Comp-Approve'     | 'CS28662FB02'           | 'R0402'             | '(R0402-0201)'                 | '8.66K'   | '1%'    | '1/16W'  | 'IO'       | 'RES CHIP 8.66K 1/16W +-1%(0402)EF'                | 'CHIPR0402'    | ''          | ''            | '20220216'
 '4.7'        | '5%'      | '1W'     | '2512LF'  | 'CHIP'   | 'CS-4708JR01'(!)        = ''              | ''                 | 'CS-4708JR01'           | 'R2512XAA'          | '(SMR2512AW)'                  | '4.7'     | '5%'    | '1W'     | 'DISCRETE' | 'RES CHIP 4.7 1W +-5%(2512)SR'                     | 'CHIPR2512'    | ''          | ''            | '20220225'
 '4.7'        | '5%'      | '1W'     | '2512LF'  | 'EMPTY'  | 'CS-4708JR01'(!)        = ''              | ''                 | 'CS-4708JR01'           | 'R2512XAA'          | '(SMR2512AW)'                  | '4.7'     | '5%'    | '1W'     | 'IO'       | 'RES CHIP 4.7 1W +-5%(2512)SR'                     | 'CHIPR2512'    | ''          | ''            | '20220225'
 '51'         | '5%'      | '1/8W'   | '0805LF'  | 'CHIP'   | 'CS05104JA01'(!)        = ''              | ''                 | 'CS05104JA01'           | 'R0805_H26'         | '(SMR0805AW)'                  | '51'      | '5%'    | '1/8W'   | 'DISCRETE' | 'RES CHIP 51 1/8W +-5%(0805)EF'                    | 'CHIPR0805'    | ''          | ''            | '20220301'
 '51'         | '5%'      | '1/8W'   | '0805LF'  | 'EMPTY'  | 'CS05104JA01'(!)        = ''              | ''                 | 'CS05104JA01'           | 'R0805_H26'         | '(SMR0805AW)'                  | '51'      | '5%'    | '1/8W'   | 'IO'       | 'RES CHIP 51 1/8W +-5%(0805)EF'                    | 'CHIPR0805'    | ''          | ''            | '20220301'
 '1'          | '5%'      | '1W'     | '2512LF'  | 'CHIP'   | 'CS-1008JR00'(!)        = ''              | ''                 | 'CS-1008JR00'           | 'R2512XU_H30'       | '(SMR2512AW)'                  | '1'       | '5%'    | '1W'     | 'DISCRETE' | 'RES CHIP 1 1W +-5%(2512)SR'                       | 'CHIPR2512'    | ''          | ''            | '20220301'
 '1'          | '5%'      | '1W'     | '2512LF'  | 'EMPTY'  | 'CS-1008JR00'(!)        = ''              | ''                 | 'CS-1008JR00'           | 'R2512XU_H30'       | '(SMR2512AW)'                  | '1'       | '5%'    | '1W'     | 'IO'       | 'RES CHIP 1 1W +-5%(2512)SR'                       | 'CHIPR2512'    | ''          | ''            | '20220301'
 '0'          | ''        | '1/16W'  | '0402LF'  | 'CHIP'   | 'CS00002TB03'(!)        = ''              | ''                 | 'CS00002TB03'           | 'R0402'             | '(R0402-0201)'                 | '0'       | ''      | '1/16W'  | 'DISCRETE' | 'RES CHIP 0 1/16W (0402)EF'                        | 'CHIPR0402'    | ''          | ''            | '20220301'
 '0'          | ''        | '1/16W'  | '0402LF'  | 'EMPTY'  | 'CS00002TB03'(!)        = ''              | ''                 | 'CS00002TB03'           | 'R0402'             | '(R0402-0201)'                 | '0'       | ''      | '1/16W'  | 'IO'       | 'RES CHIP 0 1/16W (0402)EF'                        | 'CHIPR0402'    | ''          | ''            | '20220301'
 '38.3K'      | '0.1%'    | '1/16W'  | '0402LF'  | 'CHIP'   | 'CS33832BB00'(!)        = ''              | ''                 | 'CS33832BB00'           | 'R0402'             | '(R0402-0201)'                 | '38.3K'   | '0.1%'  | '1/16W'  | 'DISCRETE' | 'RES CHIP 38.3K 1/16W  +-0.1%(0402)'               | 'CHIPR0402'    | ''          | ''            | '20220316'
 '38.3K'      | '0.1%'    | '1/16W'  | '0402LF'  | 'EMPTY'  | 'CS33832BB00'(!)        = ''              | ''                 | 'CS33832BB00'           | 'R0402'             | '(R0402-0201)'                 | '38.3K'   | '0.1%'  | '1/16W'  | 'IO'       | 'RES CHIP 38.3K 1/16W  +-0.1%(0402)'               | 'CHIPR0402'    | ''          | ''            | '20220316'
 '110'        | '1%'      | '1/16W'  | '0402LF'  | 'CHIP'   | 'CS11102FB03'(!)        = ''              | ''                 | 'CS11102FB03'           | 'R0402'             | '(R0402-0201)'                 | '110'     | '1%'    | '1/16W'  | 'DISCRETE' | 'RES CHIP 110 1/16W +-1%(0402)EF'                  | 'CHIPR0402'    | ''          | ''            | '20220316'
 '110'        | '1%'      | '1/16W'  | '0402LF'  | 'EMPTY'  | 'CS11102FB03'(!)        = ''              | ''                 | 'CS11102FB03'           | 'R0402'             | '(R0402-0201)'                 | '110'     | '1%'    | '1/16W'  | 'IO'       | 'RES CHIP 110 1/16W +-1%(0402)EF'                  | 'CHIPR0402'    | ''          | ''            | '20220316'
 '3.32K'      | '1%'      | '1/16W'  | '0402LF'  | 'CHIP'   | 'CS23322FB05'(!)        = 'End of Design' | 'Comp-Approve'     | 'CS23322FB05'           | 'R0402'             | '(R0402-0201)'                 | '3.32K'   | '1%'    | '1/16W'  | 'DISCRETE' | 'RES CHIP 3.32K 1/16W +-1%(0402)EF'                | 'CHIPR0402'    | ''          | ''            | '20220316'
 '3.32K'      | '1%'      | '1/16W'  | '0402LF'  | 'EMPTY'  | 'CS23322FB05'(!)        = 'End of Design' | 'Comp-Approve'     | 'CS23322FB05'           | 'R0402'             | '(R0402-0201)'                 | '3.32K'   | '1%'    | '1/16W'  | 'IO'       | 'RES CHIP 3.32K 1/16W +-1%(0402)EF'                | 'CHIPR0402'    | ''          | ''            | '20220316'
 '0.03'       | '1%'      | '1/2W'   | '0805LF'  | 'CHIP'   | 'CS+0307FA00'(!)        = ''              | ''                 | 'CS+0307FA00'           | 'R0805'             | '(SMR0805AW)'                  | '0.03'    | '1%'    | '1/2W'   | 'DISCRETE' | 'RES CHIP 0.03 1/2W 1%(0805)'                      | 'CHIPR0805'    | ''          | ''            | '20220316'
 '0.03'       | '1%'      | '1/2W'   | '0805LF'  | 'EMPTY'  | 'CS+0307FA00'(!)        = ''              | ''                 | 'CS+0307FA00'           | 'R0805'             | '(SMR0805AW)'                  | '0.03'    | '1%'    | '1/2W'   | 'IO'       | 'RES CHIP 0.03 1/2W 1%(0805)'                      | 'CHIPR0805'    | ''          | ''            | '20220316'
 '0'          | ''        | '1/8W'   | '0402LF'  | 'CHIP'   | 'CS00004TB04'(!)        = ''              | ''                 | 'CS00004TB04'           | 'R0402_H20'         | '(R0402-0201_H20)'             | '0'       | ''      | '1/8W'   | 'DISCRETE' | 'RES CHIP 0 OHM 1/8W JUMPER (0402)'                | 'CHIPR0402'    | ''          | ''            | '20220316'
 '0'          | ''        | '1/8W'   | '0402LF'  | 'EMPTY'  | 'CS00004TB04'(!)        = ''              | ''                 | 'CS00004TB04'           | 'R0402_H20'         | '(R0402-0201_H20)'             | '0'       | ''      | '1/8W'   | 'IO'       | 'RES CHIP 0 OHM 1/8W JUMPER (0402)'                | 'CHIPR0402'    | ''          | ''            | '20220316'
 '10.7K'      | '0.1%'    | '1/16W'  | '0402LF'  | 'CHIP'   | 'CS31072BB03'(!)        = ''              | ''                 | 'CS31072BB03'           | 'R0402'             | '(R0402-0201)'                 | '10.7K'   | '0.1%'  | '1/16W'  | 'DISCRETE' | 'RES CHIP 10.7K 1/16W +-0.1%(0402)EF'              | 'CHIPR0402'    | ''          | ''            | '20220316'
 '10.7K'      | '0.1%'    | '1/16W'  | '0402LF'  | 'EMPTY'  | 'CS31072BB03'(!)        = ''              | ''                 | 'CS31072BB03'           | 'R0402'             | '(R0402-0201)'                 | '10.7K'   | '0.1%'  | '1/16W'  | 'IO'       | 'RES CHIP 10.7K 1/16W +-0.1%(0402)EF'              | 'CHIPR0402'    | ''          | ''            | '20220316'
 '38.3K'      | '0.1%'    | '1/16W'  | '0402LF'  | 'CHIP'   | 'CS33832BB06'(!)        = ''              | ''                 | 'CS33832BB06'           | 'R0402'             | '(R0402-0201)'                 | '38.3K'   | '0.1%'  | '1/16W'  | 'DISCRETE' | 'RES CHIP 38.3K 1/16W +-0.1%(0402)EF'              | 'CHIPR0402'    | ''          | ''            | '20220316'
 '38.3K'      | '0.1%'    | '1/16W'  | '0402LF'  | 'EMPTY'  | 'CS33832BB06'(!)        = ''              | ''                 | 'CS33832BB06'           | 'R0402'             | '(R0402-0201)'                 | '38.3K'   | '0.1%'  | '1/16W'  | 'IO'       | 'RES CHIP 38.3K 1/16W +-0.1%(0402)EF'              | 'CHIPR0402'    | ''          | ''            | '20220316'
 '11.3K'      | '0.1%'    | '1/16W'  | '0402LF'  | 'CHIP'   | 'CS31132BB02'(!)        = ''              | ''                 | 'CS31132BB02'           | 'R0402'             | '(R0402-0201)'                 | '11.3K'   | '0.1%'  | '1/16W'  | 'DISCRETE' | 'RES CHIP 11.3K 1/16W +-0.1%(0402)EF'              | 'CHIPR0402'    | ''          | ''            | '20220316'
 '11.3K'      | '0.1%'    | '1/16W'  | '0402LF'  | 'EMPTY'  | 'CS31132BB02'(!)        = ''              | ''                 | 'CS31132BB02'           | 'R0402'             | '(R0402-0201)'                 | '11.3K'   | '0.1%'  | '1/16W'  | 'IO'       | 'RES CHIP 11.3K 1/16W +-0.1%(0402)EF'              | 'CHIPR0402'    | ''          | ''            | '20220316'
 '243'        | '1%'      | '1/4W'   | '1206LF'  | 'CHIP'   | 'CS12436F201'(!)        = ''              | ''                 | 'CS12436F201'           | 'R1206XN'           | '(SMR1206AW)'                  | '243'     | '1%'    | '1/4W'   | 'DISCRETE' | 'RES CHIP 243 1/4W +-1%(1206)EF'                   | 'CHIPR1206'    | ''          | ''            | '20220322'
 '243'        | '1%'      | '1/4W'   | '1206LF'  | 'EMPTY'  | 'CS12436F201'(!)        = ''              | ''                 | 'CS12436F201'           | 'R1206XN'           | '(SMR1206AW)'                  | '243'     | '1%'    | '1/4W'   | 'IO'       | 'RES CHIP 243 1/4W +-1%(1206)EF'                   | 'CHIPR1206'    | ''          | ''            | '20220322'
 '634'        | '1%'      | '1/16W'  | '0402LF'  | 'CHIP'   | 'CS16342FB01'(!)        = 'End of Design' | 'Comp-Approve'     | 'CS16342FB01'           | 'R0402'             | '(R0402-0201)'                 | '634'     | '1%'    | '1/16W'  | 'DISCRETE' | 'RES CHIP 634 1/16W +-1%(0402)EF'                  | 'CHIPR0402'    | ''          | ''            | '20220406'
 '634'        | '1%'      | '1/16W'  | '0402LF'  | 'EMPTY'  | 'CS16342FB01'(!)        = 'End of Design' | 'Comp-Approve'     | 'CS16342FB01'           | 'R0402'             | '(R0402-0201)'                 | '634'     | '1%'    | '1/16W'  | 'IO'       | 'RES CHIP 634 1/16W +-1%(0402)EF'                  | 'CHIPR0402'    | ''          | ''            | '20220406'
 '0'          | '1%'      | '1/10W'  | '0603LF'  | 'CHIP'   | 'CS00003F905'(!)        = ''              | ''                 | 'CS00003F905'           | 'R0603'             | '(SMR0603AW)'                  | '0'       | '1%'    | '1/10W'  | 'DISCRETE' | 'RES CHIP 0 1/10W +-1% (0603)EF'                   | 'CHIPR0603'    | ''          | ''            | '20220407'
 '0'          | '1%'      | '1/10W'  | '0603LF'  | 'EMPTY'  | 'CS00003F905'(!)        = ''              | ''                 | 'CS00003F905'           | 'R0603'             | '(SMR0603AW)'                  | '0'       | '1%'    | '1/10W'  | 'IO'       | 'RES CHIP 0 1/10W +-1% (0603)EF'                   | 'CHIPR0603'    | ''          | ''            | '20220407'
 '487'        | '1%'      | '1/16W'  | '0402LF'  | 'CHIP'   | 'CS14872FB01'(!)        = ''              | ''                 | 'CS14872FB01'           | 'R0402'             | '(R0402-0201)'                 | '487'     | '1%'    | '1/16W'  | 'DISCRETE' | 'RES CHIP 487 1/16W +-1%(0402) EF'                 | 'CHIPR0402'    | ''          | ''            | '20220407'
 '487'        | '1%'      | '1/16W'  | '0402LF'  | 'EMPTY'  | 'CS14872FB01'(!)        = ''              | ''                 | 'CS14872FB01'           | 'R0402'             | '(R0402-0201)'                 | '487'     | '1%'    | '1/16W'  | 'IO'       | 'RES CHIP 487 1/16W +-1%(0402) EF'                 | 'CHIPR0402'    | ''          | ''            | '20220407'
 '5.62K'      | '1%'      | '1/16W'  | '0402LF'  | 'CHIP'   | 'CS25622FB04'(!)        = ''              | ''                 | 'CS25622FB04'           | 'R0402'             | '(R0402-0201)'                 | '5.62K'   | '1%'    | '1/16W'  | 'DISCRETE' | 'RES CHIP 5.62K 1/16W +-1%(0402)EF'                | 'CHIPR0402'    | ''          | ''            | '20220408'
 '5.62K'      | '1%'      | '1/16W'  | '0402LF'  | 'EMPTY'  | 'CS25622FB04'(!)        = ''              | ''                 | 'CS25622FB04'           | 'R0402'             | '(R0402-0201)'                 | '5.62K'   | '1%'    | '1/16W'  | 'IO'       | 'RES CHIP 5.62K 1/16W +-1%(0402)EF'                | 'CHIPR0402'    | ''          | ''            | '20220408'
 '20K'        | '1%'      | '1/4W'   | '1206LF'  | 'CHIP'   | 'CS32006F205'(!)        = ''              | ''                 | 'CS32006F205'           | 'R1206XN'           | '(SMR1206AW)'                  | '20K'     | '1%'    | '1/4W'   | 'DISCRETE' | 'RES CHIP 20K 1/4W +-1%(1206)EF'                   | 'CHIPR1206'    | ''          | ''            | '20220408'
 '20K'        | '1%'      | '1/4W'   | '1206LF'  | 'EMPTY'  | 'CS32006F205'(!)        = ''              | ''                 | 'CS32006F205'           | 'R1206XN'           | '(SMR1206AW)'                  | '20K'     | '1%'    | '1/4W'   | 'IO'       | 'RES CHIP 20K 1/4W +-1%(1206)EF'                   | 'CHIPR1206'    | ''          | ''            | '20220408'
 '32.4K'      | '1%'      | '1/16W'  | '0402LF'  | 'CHIP'   | 'CS33242FB03'(!)        = 'End of Design' | 'Comp-Approve'     | 'CS33242FB03'           | 'R0402'             | '(R0402-0201)'                 | '32.4K'   | '1%'    | '1/16W'  | 'DISCRETE' | 'RES CHIP 32.4K 1/16W +-1%(0402)EF'                | 'CHIPR0402'    | ''          | ''            | '20220413'
 '32.4K'      | '1%'      | '1/16W'  | '0402LF'  | 'EMPTY'  | 'CS33242FB03'(!)        = 'End of Design' | 'Comp-Approve'     | 'CS33242FB03'           | 'R0402'             | '(R0402-0201)'                 | '32.4K'   | '1%'    | '1/16W'  | 'IO'       | 'RES CHIP 32.4K 1/16W +-1%(0402)EF'                | 'CHIPR0402'    | ''          | ''            | '20220413'
 '6.19K'      | '1%'      | '1/10W'  | '0603LF'  | 'CHIP'   | 'CS26193F901'(!)        = ''              | ''                 | 'CS26193F901'           | 'R0603'             | '(SMR0603AW)'                  | '6.19K'   | '1%'    | '1/10W'  | 'DISCRETE' | 'RES CHIP 6.19K 1/10W +-1%(0603)EF'                | 'CHIPR0603'    | ''          | ''            | '20220421'
 '6.19K'      | '1%'      | '1/10W'  | '0603LF'  | 'EMPTY'  | 'CS26193F901'(!)        = ''              | ''                 | 'CS26193F901'           | 'R0603'             | '(SMR0603AW)'                  | '6.19K'   | '1%'    | '1/10W'  | 'IO'       | 'RES CHIP 6.19K 1/10W +-1%(0603)EF'                | 'CHIPR0603'    | ''          | ''            | '20220421'
 '68.1'       | '1%'      | '1/16W'  | '0402LF'  | 'CHIP'   | 'CS06812FB03'(!)        = 'End of Design' | 'Comp-Approve'     | 'CS06812FB03'           | 'R0402'             | '(R0402-0201)'                 | '68.1'    | '1%'    | '1/16W'  | 'DISCRETE' | 'RES CHIP 68.1 1/16W +-1%(0402)EF'                 | 'CHIPR0402'    | ''          | ''            | '20220421'
 '68.1'       | '1%'      | '1/16W'  | '0402LF'  | 'EMPTY'  | 'CS06812FB03'(!)        = 'End of Design' | 'Comp-Approve'     | 'CS06812FB03'           | 'R0402'             | '(R0402-0201)'                 | '68.1'    | '1%'    | '1/16W'  | 'IO'       | 'RES CHIP 68.1 1/16W +-1%(0402)EF'                 | 'CHIPR0402'    | ''          | ''            | '20220421'
 '10.5K'      | '1%'      | '1/16W'  | '0402LF'  | 'CHIP'   | 'CS31052FB03'(!)        = ''              | ''                 | 'CS31052FB03'           | 'R0402'             | '(R0402-0201)'                 | '10.5K'   | '1%'    | '1/16W'  | 'DISCRETE' | 'RES CHIP 10.5K 1/16W +-1%(0402)EF'                | 'CHIPR0402'    | ''          | ''            | '20220426'
 '10.5K'      | '1%'      | '1/16W'  | '0402LF'  | 'EMPTY'  | 'CS31052FB03'(!)        = ''              | ''                 | 'CS31052FB03'           | 'R0402'             | '(R0402-0201)'                 | '10.5K'   | '1%'    | '1/16W'  | 'IO'       | 'RES CHIP 10.5K 1/16W +-1%(0402)EF'                | 'CHIPR0402'    | ''          | ''            | '20220426'
 '124K'       | '1%'      | '1/16W'  | '0402LF'  | 'CHIP'   | 'CS41242FB04'(!)        = ''              | ''                 | 'CS41242FB04'           | 'R0402'             | '(R0402-0201)'                 | '124K'    | '1%'    | '1/16W'  | 'DISCRETE' | 'RES CHIP 124K 1/16W +-1%(0402)EF'                 | 'CHIPR0402'    | ''          | ''            | '20220510'
 '124K'       | '1%'      | '1/16W'  | '0402LF'  | 'EMPTY'  | 'CS41242FB04'(!)        = ''              | ''                 | 'CS41242FB04'           | 'R0402'             | '(R0402-0201)'                 | '124K'    | '1%'    | '1/16W'  | 'IO'       | 'RES CHIP 124K 1/16W +-1%(0402)EF'                 | 'CHIPR0402'    | ''          | ''            | '20220510'
 '0.1'        | '1%'      | '2W'     | '2512LF'  | 'CHIP'   | 'CS+100AFR00'(!)        = ''              | ''                 | 'CS+100AFR00'           | 'R2512XAB'          | '(SMR2512AW)'                  | '0.1'     | '1%'    | '2W'     | 'DISCRETE' | 'RES CHIP 0.1 2W +-1%(2512)'                       | 'CHIPR2512'    | ''          | ''            | '20220510'
 '0.1'        | '1%'      | '2W'     | '2512LF'  | 'EMPTY'  | 'CS+100AFR00'(!)        = ''              | ''                 | 'CS+100AFR00'           | 'R2512XAB'          | '(SMR2512AW)'                  | '0.1'     | '1%'    | '2W'     | 'IO'       | 'RES CHIP 0.1 2W +-1%(2512)'                       | 'CHIPR2512'    | ''          | ''            | '20220510'
 '348K'       | '1%'      | '1/4W'   | '1206LF'  | 'CHIP'   | 'CS43486F201'(!)        = ''              | ''                 | 'CS43486F201'           | 'R1206XB'           | '(SMR1206AW)'                  | '348K'    | '1%'    | '1/4W'   | 'DISCRETE' | 'RES CHIP 348K 1/4W +-1%(1206)'                    | 'CHIPR1206'    | ''          | ''            | '20220510'
 '348K'       | '1%'      | '1/4W'   | '1206LF'  | 'EMPTY'  | 'CS43486F201'(!)        = ''              | ''                 | 'CS43486F201'           | 'R1206XB'           | '(SMR1206AW)'                  | '348K'    | '1%'    | '1/4W'   | 'IO'       | 'RES CHIP 348K 1/4W +-1%(1206)'                    | 'CHIPR1206'    | ''          | ''            | '20220510'
 '191K'       | '1%'      | '1/4W'   | '1206LF'  | 'CHIP'   | 'CS41916F200'(!)        = ''              | ''                 | 'CS41916F200'           | 'R1206XB'           | '(SMR1206AW)'                  | '191K'    | '1%'    | '1/4W'   | 'DISCRETE' | 'RES CHIP 191K 1/4W +-1% (1206)'                   | 'CHIPR1206'    | ''          | ''            | '20220510'
 '191K'       | '1%'      | '1/4W'   | '1206LF'  | 'EMPTY'  | 'CS41916F200'(!)        = ''              | ''                 | 'CS41916F200'           | 'R1206XB'           | '(SMR1206AW)'                  | '191K'    | '1%'    | '1/4W'   | 'IO'       | 'RES CHIP 191K 1/4W +-1% (1206)'                   | 'CHIPR1206'    | ''          | ''            | '20220510'
 '6.34K'      | '1%'      | '1/16W'  | '0402LF'  | 'CHIP'   | 'CS26342FB02'(!)        = 'End of Design' | 'Comp-Approve'     | 'CS26342FB02'           | 'R0402'             | '(R0402-0201)'                 | '6.34K'   | '1%'    | '1/16W'  | 'DISCRETE' | 'RES CHIP 6.34K 1/16W +-1%(0402)EF'                | 'CHIPR0402'    | ''          | ''            | '20220510'
 '6.34K'      | '1%'      | '1/16W'  | '0402LF'  | 'EMPTY'  | 'CS26342FB02'(!)        = 'End of Design' | 'Comp-Approve'     | 'CS26342FB02'           | 'R0402'             | '(R0402-0201)'                 | '6.34K'   | '1%'    | '1/16W'  | 'IO'       | 'RES CHIP 6.34K 1/16W +-1%(0402)EF'                | 'CHIPR0402'    | ''          | ''            | '20220510'
 '7.5'        | '1%'      | '1/16W'  | '0402LF'  | 'CHIP'   | 'CS-7502FB02'(!)        = ''              | ''                 | 'CS-7502FB02'           | 'R0402'             | '(R0402-0201)'                 | '7.5'     | '1%'    | '1/16W'  | 'DISCRETE' | 'RES CHIP 7.5 1/16W +-1%(0402)EF'                  | 'CHIPR0402'    | ''          | ''            | '20220512'
 '7.5'        | '1%'      | '1/16W'  | '0402LF'  | 'EMPTY'  | 'CS-7502FB02'(!)        = ''              | ''                 | 'CS-7502FB02'           | 'R0402'             | '(R0402-0201)'                 | '7.5'     | '1%'    | '1/16W'  | 'IO'       | 'RES CHIP 7.5 1/16W +-1%(0402)EF'                  | 'CHIPR0402'    | ''          | ''            | '20220512'
 '4.7'        | '5%'      | '1/10W'  | '0603LF'  | 'CHIP'   | 'CS-4703J917'(!)        = ''              | ''                 | 'CS-4703J917'           | 'R0603'             | '(SMR0603AW)'                  | '4.7'     | '5%'    | '1/10W'  | 'DISCRETE' | 'RES CHIP 4.7 1/10W +-5%(0603)'                    | 'CHIPR0603'    | ''          | ''            | '20220519'
 '4.7'        | '5%'      | '1/10W'  | '0603LF'  | 'EMPTY'  | 'CS-4703J917'(!)        = ''              | ''                 | 'CS-4703J917'           | 'R0603'             | '(SMR0603AW)'                  | '4.7'     | '5%'    | '1/10W'  | 'IO'       | 'RES CHIP 4.7 1/10W +-5%(0603)'                    | 'CHIPR0603'    | ''          | ''            | '20220519'
 '47K'        | '1%'      | '1/4W'   | '1206LF'  | 'CHIP'   | 'CS34706F200'(!)        = ''              | ''                 | 'CS34706F200'           | 'R1206XM'           | '(SMR1206AW)'                  | '47K'     | '1%'    | '1/4W'   | 'DISCRETE' | 'RES CHIP 47K 1/4W 1%(1206)'                       | 'CHIPR1206'    | ''          | ''            | '20220520'
 '47K'        | '1%'      | '1/4W'   | '1206LF'  | 'EMPTY'  | 'CS34706F200'(!)        = ''              | ''                 | 'CS34706F200'           | 'R1206XM'           | '(SMR1206AW)'                  | '47K'     | '1%'    | '1/4W'   | 'IO'       | 'RES CHIP 47K 1/4W 1%(1206)'                       | 'CHIPR1206'    | ''          | ''            | '20220520'
 '0.005'      | '1%'      | '1W'     | '1206LF'  | 'CHIP'   | 'CS+0058F202'(!)        = 'End of Design' | 'Comp-Approve'     | 'CS+0058F202'           | 'R1206XG'           | '(SMR1206AW)'                  | '0.005'   | '1%'    | '1W'     | 'DISCRETE' | 'RES CHIP 0.005 1W +-1%(1206)EF'                   | 'CHIPR1206'    | ''          | ''            | '20220524'
 '0.005'      | '1%'      | '1W'     | '1206LF'  | 'EMPTY'  | 'CS+0058F202'(!)        = 'End of Design' | 'Comp-Approve'     | 'CS+0058F202'           | 'R1206XG'           | '(SMR1206AW)'                  | '0.005'   | '1%'    | '1W'     | 'IO'       | 'RES CHIP 0.005 1W +-1%(1206)EF'                   | 'CHIPR1206'    | ''          | ''            | '20220524'
 '237K'       | '1%'      | '1/16W'  | '0402LF'  | 'CHIP'   | 'CS42372FB04'(!)        = ''              | ''                 | 'CS42372FB04'           | 'R0402'             | '(R0402-0201)'                 | '237K'    | '1%'    | '1/16W'  | 'DISCRETE' | 'RES CHIP 237K 1/16W +-1% (0402)EF'                | 'CHIPR0402'    | ''          | ''            | '20220606'
 '237K'       | '1%'      | '1/16W'  | '0402LF'  | 'EMPTY'  | 'CS42372FB04'(!)        = ''              | ''                 | 'CS42372FB04'           | 'R0402'             | '(R0402-0201)'                 | '237K'    | '1%'    | '1/16W'  | 'IO'       | 'RES CHIP 237K 1/16W +-1% (0402)EF'                | 'CHIPR0402'    | ''          | ''            | '20220606'
 '56.2K'      | '0.1%'    | '1/16W'  | '0402LF'  | 'CHIP'   | 'CS35622BB04'(!)        = ''              | ''                 | 'CS35622BB04'           | 'R0402'             | '(R0402-0201)'                 | '56.2K'   | '0.1%'  | '1/16W'  | 'DISCRETE' | 'RES CHIP 56.2K 1/16W +-0.1%(0402)YGO'             | 'CHIPR0402'    | ''          | ''            | '20220608'
 '56.2K'      | '0.1%'    | '1/16W'  | '0402LF'  | 'EMPTY'  | 'CS35622BB04'(!)        = ''              | ''                 | 'CS35622BB04'           | 'R0402'             | '(R0402-0201)'                 | '56.2K'   | '0.1%'  | '1/16W'  | 'IO'       | 'RES CHIP 56.2K 1/16W +-0.1%(0402)YGO'             | 'CHIPR0402'    | ''          | ''            | '20220608'
 '12.4K'      | '1%'      | '1/16W'  | '0402LF'  | 'CHIP'   | 'CS31242FB09'(!)        = ''              | ''                 | 'CS31242FB09'           | 'R0402'             | '(R0402-0201)'                 | '12.4K'   | '1%'    | '1/16W'  | 'DISCRETE' | 'RES CHIP 12.4K 1/16W +-1% (0402)YGO'              | 'CHIPR0402'    | ''          | ''            | '20220608'
 '12.4K'      | '1%'      | '1/16W'  | '0402LF'  | 'EMPTY'  | 'CS31242FB09'(!)        = ''              | ''                 | 'CS31242FB09'           | 'R0402'             | '(R0402-0201)'                 | '12.4K'   | '1%'    | '1/16W'  | 'IO'       | 'RES CHIP 12.4K 1/16W +-1% (0402)YGO'              | 'CHIPR0402'    | ''          | ''            | '20220608'
 '20K'        | '0.1%'    | '1/16W'  | '0402LF'  | 'CHIP'   | 'CS32002BB10'(!)        = ''              | ''                 | 'CS32002BB10'           | 'R0402'             | '(R0402-0201)'                 | '20K'     | '0.1%'  | '1/16W'  | 'DISCRETE' | 'RES CHIP 20K 1/16W +-0.1%(0402)YGO'               | 'CHIPR0402'    | ''          | ''            | '20220608'
 '20K'        | '0.1%'    | '1/16W'  | '0402LF'  | 'EMPTY'  | 'CS32002BB10'(!)        = ''              | ''                 | 'CS32002BB10'           | 'R0402'             | '(R0402-0201)'                 | '20K'     | '0.1%'  | '1/16W'  | 'IO'       | 'RES CHIP 20K 1/16W +-0.1%(0402)YGO'               | 'CHIPR0402'    | ''          | ''            | '20220608'
 '10K'        | '1%'      | '1/16W'  | '0402LF'  | 'CHIP'   | 'CS31002FB10'(!)        = ''              | ''                 | 'CS31002FB10'           | 'R0402'             | '(R0402-0201)'                 | '10K'     | '1%'    | '1/16W'  | 'DISCRETE' | 'RES CHIP 10K(1%,1/16W,0402)YGO'                   | 'CHIPR0402'    | ''          | ''            | '20220608'
 '10K'        | '1%'      | '1/16W'  | '0402LF'  | 'EMPTY'  | 'CS31002FB10'(!)        = ''              | ''                 | 'CS31002FB10'           | 'R0402'             | '(R0402-0201)'                 | '10K'     | '1%'    | '1/16W'  | 'IO'       | 'RES CHIP 10K(1%,1/16W,0402)YGO'                   | 'CHIPR0402'    | ''          | ''            | '20220608'
 '5.36K'      | '1%'      | '1/16W'  | '0402LF'  | 'CHIP'   | 'CS25362FB06'(!)        = ''              | ''                 | 'CS25362FB06'           | 'R0402'             | '(R0402-0201)'                 | '5.36K'   | '1%'    | '1/16W'  | 'DISCRETE' | 'RES CHIP 5.36K 1/16W +-1% (0402)YGO'              | 'CHIPR0402'    | ''          | ''            | '20220608'
 '5.36K'      | '1%'      | '1/16W'  | '0402LF'  | 'EMPTY'  | 'CS25362FB06'(!)        = ''              | ''                 | 'CS25362FB06'           | 'R0402'             | '(R0402-0201)'                 | '5.36K'   | '1%'    | '1/16W'  | 'IO'       | 'RES CHIP 5.36K 1/16W +-1% (0402)YGO'              | 'CHIPR0402'    | ''          | ''            | '20220608'
 '10.7K'      | '0.1%'    | '1/16W'  | '0402LF'  | 'CHIP'   | 'CS31072BB00'(!)        = ''              | ''                 | 'CS31072BB00'           | 'R0402'             | '(R0402-0201)'                 | '10.7K'   | '0.1%'  | '1/16W'  | 'DISCRETE' | 'RES CHIP 10.7K 1/16W +-0.1%(0402)'                | 'CHIPR0402'    | ''          | ''            | '20220610'
 '10.7K'      | '0.1%'    | '1/16W'  | '0402LF'  | 'EMPTY'  | 'CS31072BB00'(!)        = ''              | ''                 | 'CS31072BB00'           | 'R0402'             | '(R0402-0201)'                 | '10.7K'   | '0.1%'  | '1/16W'  | 'IO'       | 'RES CHIP 10.7K 1/16W +-0.1%(0402)'                | 'CHIPR0402'    | ''          | ''            | '20220610'
 '1.91K'      | '1%'      | '1/16W'  | '0402LF'  | 'CHIP'   | 'CS21912FB13'(!)        = 'End of Design' | 'Comp-Approve'     | 'CS21912FB13'           | 'R0402'             | '(R0402-0201)'                 | '1.91K'   | '1%'    | '1/16W'  | 'DISCRETE' | 'RES CHIP 1.91K 1/16W +-1%(0402)'                  | 'CHIPR0402'    | ''          | ''            | '20220610'
 '1.91K'      | '1%'      | '1/16W'  | '0402LF'  | 'EMPTY'  | 'CS21912FB13'(!)        = 'End of Design' | 'Comp-Approve'     | 'CS21912FB13'           | 'R0402'             | '(R0402-0201)'                 | '1.91K'   | '1%'    | '1/16W'  | 'IO'       | 'RES CHIP 1.91K 1/16W +-1%(0402)'                  | 'CHIPR0402'    | ''          | ''            | '20220610'
 '20M'        | '1%'      | '1/16W'  | '0402LF'  | 'CHIP'   | 'CS62002FB01'(!)        = ''              | ''                 | 'CS62002FB01'           | 'R0402'             | '(R0402-0201)'                 | '20M'     | '1%'    | '1/16W'  | 'DISCRETE' | 'RES CHIP 20M 1/16W +-1%(0402)EF'                  | 'CHIPR0402'    | ''          | ''            | '20220613'
 '20M'        | '1%'      | '1/16W'  | '0402LF'  | 'EMPTY'  | 'CS62002FB01'(!)        = ''              | ''                 | 'CS62002FB01'           | 'R0402'             | '(R0402-0201)'                 | '20M'     | '1%'    | '1/16W'  | 'IO'       | 'RES CHIP 20M 1/16W +-1%(0402)EF'                  | 'CHIPR0402'    | ''          | ''            | '20220613'
 '30K'        | '1%'      | '1/16W'  | '0402LF'  | 'CHIP'   | 'CS33002FB02'(!)        = 'End of Design' | 'Comp-Approve'     | 'CS33002FB02'           | 'R0402'             | '(R0402-0201)'                 | '30K'     | '1%'    | '1/16W'  | 'DISCRETE' | 'RES CHIP 30K 1/16W +-1%(0402)EF'                  | 'CHIPR0402'    | ''          | ''            | '20220616'
 '30K'        | '1%'      | '1/16W'  | '0402LF'  | 'EMPTY'  | 'CS33002FB02'(!)        = 'End of Design' | 'Comp-Approve'     | 'CS33002FB02'           | 'R0402'             | '(R0402-0201)'                 | '30K'     | '1%'    | '1/16W'  | 'IO'       | 'RES CHIP 30K 1/16W +-1%(0402)EF'                  | 'CHIPR0402'    | ''          | ''            | '20220616'
 '13.7K'      | '1%'      | '1/16W'  | '0402LF'  | 'CHIP'   | 'CS31372FB03'(!)        = 'End of Design' | 'Comp-Approve'     | 'CS31372FB03'           | 'R0402'             | '(R0402-0201)'                 | '13.7K'   | '1%'    | '1/16W'  | 'DISCRETE' | 'RES CHIP 13.7K 1/16W +-1%(0402)EF'                | 'CHIPR0402'    | ''          | ''            | '20220622'
 '13.7K'      | '1%'      | '1/16W'  | '0402LF'  | 'EMPTY'  | 'CS31372FB03'(!)        = 'End of Design' | 'Comp-Approve'     | 'CS31372FB03'           | 'R0402'             | '(R0402-0201)'                 | '13.7K'   | '1%'    | '1/16W'  | 'IO'       | 'RES CHIP 13.7K 1/16W +-1%(0402)EF'                | 'CHIPR0402'    | ''          | ''            | '20220622'
 '16.9K'      | '1%'      | '1/16W'  | '0402LF'  | 'CHIP'   | 'CS31692FB13'(!)        = ''              | ''                 | 'CS31692FB13'           | 'R0402'             | '(R0402-0201)'                 | '16.9K'   | '1%'    | '1/16W'  | 'DISCRETE' | 'RES CHIP 16.9K 1/16W +-1% (0402)WTC'              | 'CHIPR0402'    | ''          | ''            | '20220624'
 '16.9K'      | '1%'      | '1/16W'  | '0402LF'  | 'EMPTY'  | 'CS31692FB13'(!)        = ''              | ''                 | 'CS31692FB13'           | 'R0402'             | '(R0402-0201)'                 | '16.9K'   | '1%'    | '1/16W'  | 'IO'       | 'RES CHIP 16.9K 1/16W +-1% (0402)WTC'              | 'CHIPR0402'    | ''          | ''            | '20220624'
 '16.9K'      | '1%'      | '1/16W'  | '0402LF'  | 'CHIP'   | 'CS31692FB14'(!)        = ''              | ''                 | 'CS31692FB14'           | 'R0402'             | '(R0402-0201)'                 | '16.9K'   | '1%'    | '1/16W'  | 'DISCRETE' | 'RES CHIP 16.9K 1/16W +-1% (0402)YGO'              | 'CHIPR0402'    | ''          | ''            | '20220624'
 '16.9K'      | '1%'      | '1/16W'  | '0402LF'  | 'EMPTY'  | 'CS31692FB14'(!)        = ''              | ''                 | 'CS31692FB14'           | 'R0402'             | '(R0402-0201)'                 | '16.9K'   | '1%'    | '1/16W'  | 'IO'       | 'RES CHIP 16.9K 1/16W +-1% (0402)YGO'              | 'CHIPR0402'    | ''          | ''            | '20220624'
 '120K'       | '1%'      | '1/16W'  | '0402LF'  | 'CHIP'   | 'CS41202FB15'(!)        = ''              | ''                 | 'CS41202FB15'           | 'R0402'             | '(R0402-0201)'                 | '120K'    | '1%'    | '1/16W'  | 'DISCRETE' | 'RES CHIP 120K 1/16W +-1%( 0402)CYN'               | 'CHIPR0402'    | ''          | ''            | '20220624'
 '120K'       | '1%'      | '1/16W'  | '0402LF'  | 'EMPTY'  | 'CS41202FB15'(!)        = ''              | ''                 | 'CS41202FB15'           | 'R0402'             | '(R0402-0201)'                 | '120K'    | '1%'    | '1/16W'  | 'IO'       | 'RES CHIP 120K 1/16W +-1%( 0402)CYN'               | 'CHIPR0402'    | ''          | ''            | '20220624'
 '120K'       | '1%'      | '1/16W'  | '0402LF'  | 'CHIP'   | 'CS41202FB16'(!)        = ''              | ''                 | 'CS41202FB16'           | 'R0402'             | '(R0402-0201)'                 | '120K'    | '1%'    | '1/16W'  | 'DISCRETE' | 'RES CHIP 120K 1/16W +-1%( 0402)YGO'               | 'CHIPR0402'    | ''          | ''            | '20220624'
 '120K'       | '1%'      | '1/16W'  | '0402LF'  | 'EMPTY'  | 'CS41202FB16'(!)        = ''              | ''                 | 'CS41202FB16'           | 'R0402'             | '(R0402-0201)'                 | '120K'    | '1%'    | '1/16W'  | 'IO'       | 'RES CHIP 120K 1/16W +-1%( 0402)YGO'               | 'CHIPR0402'    | ''          | ''            | '20220624'
 '0'          | '1%'      | '1/2W'   | '1206LF'  | 'CHIP'   | 'CS00007F201'(!)        = ''              | ''                 | 'CS00007F201'           | 'R1206XI'           | '(SMR1206AW)'                  | '0'       | '1%'    | '1/2W'   | 'DISCRETE' | 'RES CHIP 0 1/2W +-1%(1206)WTC'                    | 'CHIPR1206'    | ''          | ''            | '20220624'
 '0'          | '1%'      | '1/2W'   | '1206LF'  | 'EMPTY'  | 'CS00007F201'(!)        = ''              | ''                 | 'CS00007F201'           | 'R1206XI'           | '(SMR1206AW)'                  | '0'       | '1%'    | '1/2W'   | 'IO'       | 'RES CHIP 0 1/2W +-1%(1206)WTC'                    | 'CHIPR1206'    | ''          | ''            | '20220624'
 '0'          | '1%'      | '1/2W'   | '1206LF'  | 'CHIP'   | 'CS00007F202'(!)        = ''              | ''                 | 'CS00007F202'           | 'R1206XF'           | '(SMR1206AW)'                  | '0'       | '1%'    | '1/2W'   | 'DISCRETE' | 'RES CHIP 0 1/2W +-1%(1206)YGO'                    | 'CHIPR1206'    | ''          | ''            | '20220624'
 '0'          | '1%'      | '1/2W'   | '1206LF'  | 'EMPTY'  | 'CS00007F202'(!)        = ''              | ''                 | 'CS00007F202'           | 'R1206XF'           | '(SMR1206AW)'                  | '0'       | '1%'    | '1/2W'   | 'IO'       | 'RES CHIP 0 1/2W +-1%(1206)YGO'                    | 'CHIPR1206'    | ''          | ''            | '20220624'
 '127'        | '1%'      | '1/16W'  | '0402LF'  | 'CHIP'   | 'CS11272FB21'(!)        = 'End of Design' | 'Comp-Approve'     | 'CS11272FB21'           | 'R0402'             | '(R0402-0201)'                 | '127'     | '1%'    | '1/16W'  | 'DISCRETE' | 'RES CHIP 127 1/16W +-1%(0402)'                    | 'CHIPR0402'    | ''          | ''            | '20220704'
 '127'        | '1%'      | '1/16W'  | '0402LF'  | 'EMPTY'  | 'CS11272FB21'(!)        = 'End of Design' | 'Comp-Approve'     | 'CS11272FB21'           | 'R0402'             | '(R0402-0201)'                 | '127'     | '1%'    | '1/16W'  | 'IO'       | 'RES CHIP 127 1/16W +-1%(0402)'                    | 'CHIPR0402'    | ''          | ''            | '20220704'
 '0.001'      | '1%'      | '2W'     | '2512LF'  | 'CHIP'   | 'CS+001AFR12'(!)        = ''              | ''                 | 'CS+001AFR12'           | 'R2512XG'           | '(SMR2512AW)'                  | '0.001'   | '1%'    | '2W'     | 'DISCRETE' | 'RES CHIP 0.001 2W +-1%(2512)RLC'                  | 'CHIPR2512'    | ''          | ''            | '20220704'
 '0.001'      | '1%'      | '2W'     | '2512LF'  | 'EMPTY'  | 'CS+001AFR12'(!)        = ''              | ''                 | 'CS+001AFR12'           | 'R2512XG'           | '(SMR2512AW)'                  | '0.001'   | '1%'    | '2W'     | 'IO'       | 'RES CHIP 0.001 2W +-1%(2512)RLC'                  | 'CHIPR2512'    | ''          | ''            | '20220704'
 '7.5M'       | '1%'      | '1/16W'  | '0402LF'  | 'CHIP'   | 'CS57502FB00'(!)        = ''              | ''                 | 'CS57502FB00'           | 'R0402'             | '(R0402-0201)'                 | '7.5M'    | '1%'    | '1/16W'  | 'DISCRETE' | 'RES CHIP 7.5M 1/16W +-1%(0402)'                   | 'CHIPR0402'    | ''          | ''            | '20220704'
 '7.5M'       | '1%'      | '1/16W'  | '0402LF'  | 'EMPTY'  | 'CS57502FB00'(!)        = ''              | ''                 | 'CS57502FB00'           | 'R0402'             | '(R0402-0201)'                 | '7.5M'    | '1%'    | '1/16W'  | 'IO'       | 'RES CHIP 7.5M 1/16W +-1%(0402)'                   | 'CHIPR0402'    | ''          | ''            | '20220704'
 '619K'       | '1%'      | '1/8W'   | '0805LF'  | 'CHIP'   | 'CS46194FA00'(!)        = ''              | ''                 | 'CS46194FA00'           | 'R0805'             | '(SMR0805AW)'                  | '619K'    | '1%'    | '1/8W'   | 'DISCRETE' | 'RES CHIP 619K 1/8W +-1%(0805)'                    | 'CHIPR0805'    | ''          | ''            | '20220715'
 '619K'       | '1%'      | '1/8W'   | '0805LF'  | 'EMPTY'  | 'CS46194FA00'(!)        = ''              | ''                 | 'CS46194FA00'           | 'R0805'             | '(SMR0805AW)'                  | '619K'    | '1%'    | '1/8W'   | 'IO'       | 'RES CHIP 619K 1/8W +-1%(0805)'                    | 'CHIPR0805'    | ''          | ''            | '20220715'
 '97.6K'      | '1%'      | '1/8W'   | '0805LF'  | 'CHIP'   | 'CS39764FA00'(!)        = ''              | ''                 | 'CS39764FA00'           | 'R0805'             | '(SMR0805AW)'                  | '97.6K'   | '1%'    | '1/8W'   | 'DISCRETE' | 'RES CHIP 97.6K 1/8W +-1%(0805)'                   | 'CHIPR0805'    | ''          | ''            | '20220715'
 '97.6K'      | '1%'      | '1/8W'   | '0805LF'  | 'EMPTY'  | 'CS39764FA00'(!)        = ''              | ''                 | 'CS39764FA00'           | 'R0805'             | '(SMR0805AW)'                  | '97.6K'   | '1%'    | '1/8W'   | 'IO'       | 'RES CHIP 97.6K 1/8W +-1%(0805)'                   | 'CHIPR0805'    | ''          | ''            | '20220715'
 '16K'        | '1%'      | '1/16W'  | '0402LF'  | 'CHIP'   | 'CS31602FB01'(!)        = 'End of Design' | 'Comp-Approve'     | 'CS31602FB01'           | 'R0402'             | '(R0402-0201)'                 | '16K'     | '1%'    | '1/16W'  | 'DISCRETE' | 'RES CHIP 16K 1/16W +-1%(0402)EF'                  | 'CHIPR0402'    | ''          | ''            | '20220802'
 '16K'        | '1%'      | '1/16W'  | '0402LF'  | 'EMPTY'  | 'CS31602FB01'(!)        = 'End of Design' | 'Comp-Approve'     | 'CS31602FB01'           | 'R0402'             | '(R0402-0201)'                 | '16K'     | '1%'    | '1/16W'  | 'IO'       | 'RES CHIP 16K 1/16W +-1%(0402)EF'                  | 'CHIPR0402'    | ''          | ''            | '20220802'
 '374K'       | '1%'      | '1/16W'  | '0402LF'  | 'CHIP'   | 'CS43742FB00'(!)        = 'End of Design' | 'Comp-Approve'     | 'CS43742FB00'           | 'R0402'             | '(R0402-0201)'                 | '374K'    | '1%'    | '1/16W'  | 'DISCRETE' | 'RES CHIP 374K 1/16W +-1%(0402)'                   | 'CHIPR0402'    | ''          | ''            | '20220803'
 '374K'       | '1%'      | '1/16W'  | '0402LF'  | 'EMPTY'  | 'CS43742FB00'(!)        = 'End of Design' | 'Comp-Approve'     | 'CS43742FB00'           | 'R0402'             | '(R0402-0201)'                 | '374K'    | '1%'    | '1/16W'  | 'IO'       | 'RES CHIP 374K 1/16W +-1%(0402)'                   | 'CHIPR0402'    | ''          | ''            | '20220803'
 '10K'        | '1%'      | '1/20W'  | '0201LF'  | 'CHIP'   | 'CS31001FE16'(!)        = ''              | ''                 | 'CS31001FE16'           | 'R0201'             | '(SMR0201AW)'                  | '10K'     | '1%'    | '1/20W'  | 'DISCRETE' | 'RES CHIP 10K 1/20W +-1%(0201)YGO'                 | 'CHIPR0201'    | ''          | ''            | '20220816'
 '10K'        | '1%'      | '1/20W'  | '0201LF'  | 'EMPTY'  | 'CS31001FE16'(!)        = ''              | ''                 | 'CS31001FE16'           | 'R0201'             | '(SMR0201AW)'                  | '10K'     | '1%'    | '1/20W'  | 'IO'       | 'RES CHIP 10K 1/20W +-1%(0201)YGO'                 | 'CHIPR0201'    | ''          | ''            | '20220816'
 '0.03'       | '1%'      | '1/2W'   | '0805LF'  | 'CHIP'   | 'CS+0307FA02'(!)        = ''              | ''                 | 'CS+0307FA02'           | 'R0805_H26'         | '(SMR0805AW)'                  | '0.03'    | '1%'    | '1/2W'   | 'DISCRETE' | 'RES CHIP 0.03 1/2W 1%(0805)H0.55'                 | 'CHIPR0805'    | ''          | ''            | '20220818'
 '0.03'       | '1%'      | '1/2W'   | '0805LF'  | 'EMPTY'  | 'CS+0307FA02'(!)        = ''              | ''                 | 'CS+0307FA02'           | 'R0805_H26'         | '(SMR0805AW)'                  | '0.03'    | '1%'    | '1/2W'   | 'IO'       | 'RES CHIP 0.03 1/2W 1%(0805)H0.55'                 | 'CHIPR0805'    | ''          | ''            | '20220818'
 '470'        | '1%'      | '1/20W'  | '0201LF'  | 'CHIP'   | 'CS14701FE10'(!)        = ''              | ''                 | 'CS14701FE10'           | 'R0201'             | '(SMR0201AW)'                  | '470'     | '1%'    | '1/20W'  | 'DISCRETE' | 'RES CHIP 470 1/20W +-1% (0201)YGO'                | 'CHIPR0201'    | ''          | ''            | '20220818'
 '470'        | '1%'      | '1/20W'  | '0201LF'  | 'EMPTY'  | 'CS14701FE10'(!)        = ''              | ''                 | 'CS14701FE10'           | 'R0201'             | '(SMR0201AW)'                  | '470'     | '1%'    | '1/20W'  | 'IO'       | 'RES CHIP 470 1/20W +-1% (0201)YGO'                | 'CHIPR0201'    | ''          | ''            | '20220818'
 '0'          | ''        | '1/16W'  | '0402LF'  | 'CHIP'   | 'CS00002TB04'(!)        = ''              | ''                 | 'CS00002TB04'           | 'R0402'             | '(R0402-0201)'                 | '0'       | ''      | '1/16W'  | 'DISCRETE' | 'RES CHIP 0 1/16W(0402)WTC'                        | 'CHIPR0402'    | ''          | ''            | '20220824'
 '0'          | ''        | '1/16W'  | '0402LF'  | 'EMPTY'  | 'CS00002TB04'(!)        = ''              | ''                 | 'CS00002TB04'           | 'R0402'             | '(R0402-0201)'                 | '0'       | ''      | '1/16W'  | 'IO'       | 'RES CHIP 0 1/16W(0402)WTC'                        | 'CHIPR0402'    | ''          | ''            | '20220824'
 '0.2'        | '1%'      | '1/16W'  | '0402LF'  | 'CHIP'   | 'CS+2002FB00'(!)        = ''              | ''                 | 'CS+2002FB00'           | 'R0402'             | '(R0402-0201)'                 | '0.2'     | '1%'    | '1/16W'  | 'DISCRETE' | 'RES CHIP 0.2 1/16W +-1%(0402)'                    | 'CHIPR0402'    | ''          | ''            | '20220829'
 '0.2'        | '1%'      | '1/16W'  | '0402LF'  | 'EMPTY'  | 'CS+2002FB00'(!)        = ''              | ''                 | 'CS+2002FB00'           | 'R0402'             | '(R0402-0201)'                 | '0.2'     | '1%'    | '1/16W'  | 'IO'       | 'RES CHIP 0.2 1/16W +-1%(0402)'                    | 'CHIPR0402'    | ''          | ''            | '20220829'
 '56.2K'      | '1%'      | '1/10W'  | '0603LF'  | 'CHIP'   | 'CS35623F924'(!)        = ''              | ''                 | 'CS35623F924'           | 'R0603'             | '(SMR0603AW)'                  | '56.2K'   | '1%'    | '1/10W'  | 'DISCRETE' | 'RESISTOR CHIP 56.2K,1/10W,+-1%(0603)'             | 'CHIPR0603'    | ''          | ''            | '20220829'
 '56.2K'      | '1%'      | '1/10W'  | '0603LF'  | 'EMPTY'  | 'CS35623F924'(!)        = ''              | ''                 | 'CS35623F924'           | 'R0603'             | '(SMR0603AW)'                  | '56.2K'   | '1%'    | '1/10W'  | 'IO'       | 'RESISTOR CHIP 56.2K,1/10W,+-1%(0603)'             | 'CHIPR0603'    | ''          | ''            | '20220829'
 '42.2K'      | '1%'      | '1/16W'  | '0402LF'  | 'CHIP'   | 'CS34222FB06'(!)        = ''              | ''                 | 'CS34222FB06'           | 'R0402'             | '(R0402-0201)'                 | '42.2K'   | '1%'    | '1/16W'  | 'DISCRETE' | 'RES CHIP 42.2K 1/16W +-1%(0402)EF'                | 'CHIPR0402'    | ''          | ''            | '20220905'
 '42.2K'      | '1%'      | '1/16W'  | '0402LF'  | 'EMPTY'  | 'CS34222FB06'(!)        = ''              | ''                 | 'CS34222FB06'           | 'R0402'             | '(R0402-0201)'                 | '42.2K'   | '1%'    | '1/16W'  | 'IO'       | 'RES CHIP 42.2K 1/16W +-1%(0402)EF'                | 'CHIPR0402'    | ''          | ''            | '20220905'
 '2.94K'      | '1%'      | '1/16W'  | '0402LF'  | 'CHIP'   | 'CS22942FB03'(!)        = 'End of Design' | 'Comp-Approve'     | 'CS22942FB03'           | 'R0402'             | '(R0402-0201)'                 | '2.94K'   | '1%'    | '1/16W'  | 'DISCRETE' | 'RES CHIP 2.94K 1/16W +-1%(0402)EF'                | 'CHIPR0402'    | ''          | ''            | '20220927'
 '2.94K'      | '1%'      | '1/16W'  | '0402LF'  | 'EMPTY'  | 'CS22942FB03'(!)        = 'End of Design' | 'Comp-Approve'     | 'CS22942FB03'           | 'R0402'             | '(R0402-0201)'                 | '2.94K'   | '1%'    | '1/16W'  | 'IO'       | 'RES CHIP 2.94K 1/16W +-1%(0402)EF'                | 'CHIPR0402'    | ''          | ''            | '20220927'
 '45.3K'      | '0.1%'    | '1/16W'  | '0402LF'  | 'CHIP'   | 'CS34532BB01'(!)        = ''              | ''                 | 'CS34532BB01'           | 'R0402'             | '(R0402-0201)'                 | '45.3K'   | '0.1%'  | '1/16W'  | 'DISCRETE' | 'RES CHIP 45.3K 1/16W +-0.1%(0402)'                | 'CHIPR0402'    | ''          | ''            | '20220928'
 '45.3K'      | '0.1%'    | '1/16W'  | '0402LF'  | 'EMPTY'  | 'CS34532BB01'(!)        = ''              | ''                 | 'CS34532BB01'           | 'R0402'             | '(R0402-0201)'                 | '45.3K'   | '0.1%'  | '1/16W'  | 'IO'       | 'RES CHIP 45.3K 1/16W +-0.1%(0402)'                | 'CHIPR0402'    | ''          | ''            | '20220928'
 '383K'       | '1%'      | '1/16W'  | '0402LF'  | 'CHIP'   | 'CS43832FB00'(!)        = 'End of Design' | 'Comp-Approve'     | 'CS43832FB00'           | 'R0402'             | '(R0402-0201)'                 | '383K'    | '1%'    | '1/16W'  | 'DISCRETE' | 'RES CHIP 383K 1/16W +-1% (0402)'                  | 'CHIPR0402'    | ''          | ''            | '20220929'
 '383K'       | '1%'      | '1/16W'  | '0402LF'  | 'EMPTY'  | 'CS43832FB00'(!)        = 'End of Design' | 'Comp-Approve'     | 'CS43832FB00'           | 'R0402'             | '(R0402-0201)'                 | '383K'    | '1%'    | '1/16W'  | 'IO'       | 'RES CHIP 383K 1/16W +-1% (0402)'                  | 'CHIPR0402'    | ''          | ''            | '20220929'
 '5.1'        | '1%'      | '1/8W'   | '0805LF'  | 'CHIP'   | 'CS-5104FA21'(!)        = ''              | ''                 | 'CS-5104FA21'           | 'R0805_H26'         | '(SMR0805AW)'                  | '5.1'     | '1%'    | '1/8W'   | 'DISCRETE' | 'RES CHIP 5.1 1/8W +-1%(0805)'                     | 'CHIPR0805'    | ''          | ''            | '20221003'
 '5.1'        | '1%'      | '1/8W'   | '0805LF'  | 'EMPTY'  | 'CS-5104FA21'(!)        = ''              | ''                 | 'CS-5104FA21'           | 'R0805_H26'         | '(SMR0805AW)'                  | '5.1'     | '1%'    | '1/8W'   | 'IO'       | 'RES CHIP 5.1 1/8W +-1%(0805)'                     | 'CHIPR0805'    | ''          | ''            | '20221003'
 '5.6'        | '1%'      | '1/16W'  | '0402LF'  | 'CHIP'   | 'CS-5602FB00'(!)        = 'End of Design' | 'Comp-Approve'     | 'CS-5602FB00'           | 'R0402'             | '(R0402-0201)'                 | '5.6'     | '1%'    | '1/16W'  | 'DISCRETE' | 'RES CHIP 5.6 1/16W 1%(0402)'                      | 'CHIPR0402'    | ''          | ''            | '20221007'
 '5.6'        | '1%'      | '1/16W'  | '0402LF'  | 'EMPTY'  | 'CS-5602FB00'(!)        = 'End of Design' | 'Comp-Approve'     | 'CS-5602FB00'           | 'R0402'             | '(R0402-0201)'                 | '5.6'     | '1%'    | '1/16W'  | 'IO'       | 'RES CHIP 5.6 1/16W 1%(0402)'                      | 'CHIPR0402'    | ''          | ''            | '20221007'
 '3.83K'      | '0.1%'    | '1/16W'  | '0402LF'  | 'CHIP'   | 'CS23832BB01'(!)        = ''              | ''                 | 'CS23832BB01'           | 'R0402'             | '(R0402-0201)'                 | '3.83K'   | '0.1%'  | '1/16W'  | 'DISCRETE' | 'RES CHIP 3.83K 1/16W +-0.1% (0402)'               | 'CHIPR0402'    | ''          | ''            | '20221011'
 '3.83K'      | '0.1%'    | '1/16W'  | '0402LF'  | 'EMPTY'  | 'CS23832BB01'(!)        = ''              | ''                 | 'CS23832BB01'           | 'R0402'             | '(R0402-0201)'                 | '3.83K'   | '0.1%'  | '1/16W'  | 'IO'       | 'RES CHIP 3.83K 1/16W +-0.1% (0402)'               | 'CHIPR0402'    | ''          | ''            | '20221011'
 '0'          | '5%'      | '1/16W'  | '0402LF'  | 'CHIP'   | 'CS00002JB15'(!)        = ''              | ''                 | 'CS00002JB15'           | 'R0402'             | '(R0402-0201)'                 | '0'       | '5%'    | '1/16W'  | 'DISCRETE' | 'RES CHIP 0(5%,1/16W,0402)YGO'                     | 'CHIPR0402'    | ''          | ''            | '20221017'
 '0'          | '5%'      | '1/16W'  | '0402LF'  | 'EMPTY'  | 'CS00002JB15'(!)        = ''              | ''                 | 'CS00002JB15'           | 'R0402'             | '(R0402-0201)'                 | '0'       | '5%'    | '1/16W'  | 'IO'       | 'RES CHIP 0(5%,1/16W,0402)YGO'                     | 'CHIPR0402'    | ''          | ''            | '20221017'
 '1K'         | '5%'      | '1/16W'  | '0402LF'  | 'CHIP'   | 'CS21002JB25'(!)        = ''              | ''                 | 'CS21002JB25'           | 'R0402'             | '(R0402-0201)'                 | '1K'      | '5%'    | '1/16W'  | 'DISCRETE' | 'RES CHIP 1K 1/16W 5%(0402) WTC'                   | 'CHIPR0402'    | ''          | ''            | '20221017'
 '1K'         | '5%'      | '1/16W'  | '0402LF'  | 'EMPTY'  | 'CS21002JB25'(!)        = ''              | ''                 | 'CS21002JB25'           | 'R0402'             | '(R0402-0201)'                 | '1K'      | '5%'    | '1/16W'  | 'IO'       | 'RES CHIP 1K 1/16W 5%(0402) WTC'                   | 'CHIPR0402'    | ''          | ''            | '20221017'
 '4.7K'       | '5%'      | '1/16W'  | '0402LF'  | 'CHIP'   | 'CS24702JB18'(!)        = ''              | ''                 | 'CS24702JB18'           | 'R0402'             | '(R0402-0201)'                 | '4.7K'    | '5%'    | '1/16W'  | 'DISCRETE' | 'RES CHIP 4.7K 1/16W +-5% (0402)WTC'               | 'CHIPR0402'    | ''          | ''            | '20221017'
 '4.7K'       | '5%'      | '1/16W'  | '0402LF'  | 'EMPTY'  | 'CS24702JB18'(!)        = ''              | ''                 | 'CS24702JB18'           | 'R0402'             | '(R0402-0201)'                 | '4.7K'    | '5%'    | '1/16W'  | 'IO'       | 'RES CHIP 4.7K 1/16W +-5% (0402)WTC'               | 'CHIPR0402'    | ''          | ''            | '20221017'
 '10'         | '1%'      | '1/16W'  | '0402LF'  | 'CHIP'   | 'CS01002FB29'(!)        = ''              | ''                 | 'CS01002FB29'           | 'R0402'             | '(R0402-0201)'                 | '10'      | '1%'    | '1/16W'  | 'DISCRETE' | 'RES CHIP 10 1/16W +-1%(0402)CYN'                  | 'CHIPR0402'    | ''          | ''            | '20221017'
 '10'         | '1%'      | '1/16W'  | '0402LF'  | 'EMPTY'  | 'CS01002FB29'(!)        = ''              | ''                 | 'CS01002FB29'           | 'R0402'             | '(R0402-0201)'                 | '10'      | '1%'    | '1/16W'  | 'IO'       | 'RES CHIP 10 1/16W +-1%(0402)CYN'                  | 'CHIPR0402'    | ''          | ''            | '20221017'
 '10'         | '1%'      | '1/16W'  | '0402LF'  | 'CHIP'   | 'CS01002FB28'(!)        = ''              | ''                 | 'CS01002FB28'           | 'R0402'             | '(R0402-0201)'                 | '10'      | '1%'    | '1/16W'  | 'DISCRETE' | 'RES CHIP 10 1/16W +-1%(0402)WTC'                  | 'CHIPR0402'    | ''          | ''            | '20221017'
 '10'         | '1%'      | '1/16W'  | '0402LF'  | 'EMPTY'  | 'CS01002FB28'(!)        = ''              | ''                 | 'CS01002FB28'           | 'R0402'             | '(R0402-0201)'                 | '10'      | '1%'    | '1/16W'  | 'IO'       | 'RES CHIP 10 1/16W +-1%(0402)WTC'                  | 'CHIPR0402'    | ''          | ''            | '20221017'
 '1K'         | '1%'      | '1/16W'  | '0402LF'  | 'CHIP'   | 'CS21002FB27'(!)        = ''              | ''                 | 'CS21002FB27'           | 'R0402'             | '(R0402-0201)'                 | '1K'      | '1%'    | '1/16W'  | 'DISCRETE' | 'RES CHIP 1K 1/16W +-1% (0402)WTC'                 | 'CHIPR0402'    | ''          | ''            | '20221017'
 '1K'         | '1%'      | '1/16W'  | '0402LF'  | 'EMPTY'  | 'CS21002FB27'(!)        = ''              | ''                 | 'CS21002FB27'           | 'R0402'             | '(R0402-0201)'                 | '1K'      | '1%'    | '1/16W'  | 'IO'       | 'RES CHIP 1K 1/16W +-1% (0402)WTC'                 | 'CHIPR0402'    | ''          | ''            | '20221017'
 '6.81K'      | '1%'      | '1/16W'  | '0402LF'  | 'CHIP'   | 'CS26812FB10'(!)        = ''              | ''                 | 'CS26812FB10'           | 'R0402'             | '(R0402-0201)'                 | '6.81K'   | '1%'    | '1/16W'  | 'DISCRETE' | 'RES CHIP 6.81K 1/16W +-1% (0402)WTC'              | 'CHIPR0402'    | ''          | ''            | '20221017'
 '6.81K'      | '1%'      | '1/16W'  | '0402LF'  | 'EMPTY'  | 'CS26812FB10'(!)        = ''              | ''                 | 'CS26812FB10'           | 'R0402'             | '(R0402-0201)'                 | '6.81K'   | '1%'    | '1/16W'  | 'IO'       | 'RES CHIP 6.81K 1/16W +-1% (0402)WTC'              | 'CHIPR0402'    | ''          | ''            | '20221017'
 '13K'        | '1%'      | '1/16W'  | '0402LF'  | 'CHIP'   | 'CS31302FB10'(!)        = ''              | ''                 | 'CS31302FB10'           | 'R0402'             | '(R0402-0201)'                 | '13K'     | '1%'    | '1/16W'  | 'DISCRETE' | 'RES CHIP 13K 1/16W +-1%( 0402)WTC'                | 'CHIPR0402'    | ''          | ''            | '20221017'
 '13K'        | '1%'      | '1/16W'  | '0402LF'  | 'EMPTY'  | 'CS31302FB10'(!)        = ''              | ''                 | 'CS31302FB10'           | 'R0402'             | '(R0402-0201)'                 | '13K'     | '1%'    | '1/16W'  | 'IO'       | 'RES CHIP 13K 1/16W +-1%( 0402)WTC'                | 'CHIPR0402'    | ''          | ''            | '20221017'
 '100K'       | '1%'      | '1/16W'  | '0402LF'  | 'CHIP'   | 'CS41002FB14'(!)        = ''              | ''                 | 'CS41002FB14'           | 'R0402'             | '(R0402-0201)'                 | '100K'    | '1%'    | '1/16W'  | 'DISCRETE' | 'RES CHIP 100K(1%,1/16W,0402)WTC'                  | 'CHIPR0402'    | ''          | ''            | '20221017'
 '100K'       | '1%'      | '1/16W'  | '0402LF'  | 'EMPTY'  | 'CS41002FB14'(!)        = ''              | ''                 | 'CS41002FB14'           | 'R0402'             | '(R0402-0201)'                 | '100K'    | '1%'    | '1/16W'  | 'IO'       | 'RES CHIP 100K(1%,1/16W,0402)WTC'                  | 'CHIPR0402'    | ''          | ''            | '20221017'
 '33'         | '5%'      | '1/16W'  | '0402LF'  | 'CHIP'   | 'CS03302JB22'(!)        = ''              | ''                 | 'CS03302JB22'           | 'R0402'             | '(R0402-0201)'                 | '33'      | '5%'    | '1/16W'  | 'DISCRETE' | 'RES CHIP 33 1/16W +-5% (0402)WTC'                 | 'CHIPR0402'    | ''          | ''            | '20221017'
 '33'         | '5%'      | '1/16W'  | '0402LF'  | 'EMPTY'  | 'CS03302JB22'(!)        = ''              | ''                 | 'CS03302JB22'           | 'R0402'             | '(R0402-0201)'                 | '33'      | '5%'    | '1/16W'  | 'IO'       | 'RES CHIP 33 1/16W +-5% (0402)WTC'                 | 'CHIPR0402'    | ''          | ''            | '20221017'
 '60.4K'      | '1%'      | '1/16W'  | '0402LF'  | 'CHIP'   | 'CS36042FB11'(!)        = ''              | ''                 | 'CS36042FB11'           | 'R0402'             | '(R0402-0201)'                 | '60.4K'   | '1%'    | '1/16W'  | 'DISCRETE' | 'RES CHIP 60.4K 1/16W +-1%(0402)WTC'               | 'CHIPR0402'    | ''          | ''            | '20221017'
 '60.4K'      | '1%'      | '1/16W'  | '0402LF'  | 'EMPTY'  | 'CS36042FB11'(!)        = ''              | ''                 | 'CS36042FB11'           | 'R0402'             | '(R0402-0201)'                 | '60.4K'   | '1%'    | '1/16W'  | 'IO'       | 'RES CHIP 60.4K 1/16W +-1%(0402)WTC'               | 'CHIPR0402'    | ''          | ''            | '20221017'
 '6.81K'      | '1%'      | '1/16W'  | '0402LF'  | 'CHIP'   | 'CS26812FB11'(!)        = ''              | ''                 | 'CS26812FB11'           | 'R0402'             | '(R0402-0201)'                 | '6.81K'   | '1%'    | '1/16W'  | 'DISCRETE' | 'RES CHIP 6.81K 1/16W +-1% (0402)YGO'              | 'CHIPR0402'    | ''          | ''            | '20221017'
 '6.81K'      | '1%'      | '1/16W'  | '0402LF'  | 'EMPTY'  | 'CS26812FB11'(!)        = ''              | ''                 | 'CS26812FB11'           | 'R0402'             | '(R0402-0201)'                 | '6.81K'   | '1%'    | '1/16W'  | 'IO'       | 'RES CHIP 6.81K 1/16W +-1% (0402)YGO'              | 'CHIPR0402'    | ''          | ''            | '20221017'
 '13K'        | '1%'      | '1/16W'  | '0402LF'  | 'CHIP'   | 'CS31302FB09'(!)        = ''              | ''                 | 'CS31302FB09'           | 'R0402'             | '(R0402-0201)'                 | '13K'     | '1%'    | '1/16W'  | 'DISCRETE' | 'RES CHIP 13K 1/16W +-1%( 0402)YGO'                | 'CHIPR0402'    | ''          | ''            | '20221017'
 '13K'        | '1%'      | '1/16W'  | '0402LF'  | 'EMPTY'  | 'CS31302FB09'(!)        = ''              | ''                 | 'CS31302FB09'           | 'R0402'             | '(R0402-0201)'                 | '13K'     | '1%'    | '1/16W'  | 'IO'       | 'RES CHIP 13K 1/16W +-1%( 0402)YGO'                | 'CHIPR0402'    | ''          | ''            | '20221017'
 '48.7K'      | '1%'      | '1/16W'  | '0402LF'  | 'CHIP'   | 'CS34872FB13'(!)        = ''              | ''                 | 'CS34872FB13'           | 'R0402'             | '(R0402-0201)'                 | '48.7K'   | '1%'    | '1/16W'  | 'DISCRETE' | 'RES CHIP 48.7K 1/16W +-1% (0402)YGO'              | 'CHIPR0402'    | ''          | ''            | '20221017'
 '48.7K'      | '1%'      | '1/16W'  | '0402LF'  | 'EMPTY'  | 'CS34872FB13'(!)        = ''              | ''                 | 'CS34872FB13'           | 'R0402'             | '(R0402-0201)'                 | '48.7K'   | '1%'    | '1/16W'  | 'IO'       | 'RES CHIP 48.7K 1/16W +-1% (0402)YGO'              | 'CHIPR0402'    | ''          | ''            | '20221017'
 '54.9K'      | '1%'      | '1/16W'  | '0402LF'  | 'CHIP'   | 'CS35492FB12'(!)        = ''              | ''                 | 'CS35492FB12'           | 'R0402'             | '(R0402-0201)'                 | '54.9K'   | '1%'    | '1/16W'  | 'DISCRETE' | 'RES CHIP 54.9K 1/16W +-1%(0402)YGO'               | 'CHIPR0402'    | ''          | ''            | '20221017'
 '54.9K'      | '1%'      | '1/16W'  | '0402LF'  | 'EMPTY'  | 'CS35492FB12'(!)        = ''              | ''                 | 'CS35492FB12'           | 'R0402'             | '(R0402-0201)'                 | '54.9K'   | '1%'    | '1/16W'  | 'IO'       | 'RES CHIP 54.9K 1/16W +-1%(0402)YGO'               | 'CHIPR0402'    | ''          | ''            | '20221017'
 '0'          | '5%'      | '1/8W'   | '0805LF'  | 'CHIP'   | 'CS00004JA09'(!)        = ''              | ''                 | 'CS00004JA09'           | 'R0805'             | '(SMR0805AW)'                  | '0'       | '5%'    | '1/8W'   | 'DISCRETE' | 'RES CHIP 0 1/8W +-5%(0805)YGO'                    | 'CHIPR0805'    | ''          | ''            | '20221017'
 '0'          | '5%'      | '1/8W'   | '0805LF'  | 'EMPTY'  | 'CS00004JA09'(!)        = ''              | ''                 | 'CS00004JA09'           | 'R0805'             | '(SMR0805AW)'                  | '0'       | '5%'    | '1/8W'   | 'IO'       | 'RES CHIP 0 1/8W +-5%(0805)YGO'                    | 'CHIPR0805'    | ''          | ''            | '20221017'
 '10'         | '1%'      | '1/10W'  | '0603LF'  | 'CHIP'   | 'CS01003F912'(!)        = ''              | ''                 | 'CS01003F912'           | 'R0603'             | '(SMR0603AW)'                  | '10'      | '1%'    | '1/10W'  | 'DISCRETE' | 'RES CHIP 10 1/10W +-1%(0603)YGO'                  | 'CHIPR0603'    | ''          | ''            | '20221017'
 '10'         | '1%'      | '1/10W'  | '0603LF'  | 'EMPTY'  | 'CS01003F912'(!)        = ''              | ''                 | 'CS01003F912'           | 'R0603'             | '(SMR0603AW)'                  | '10'      | '1%'    | '1/10W'  | 'IO'       | 'RES CHIP 10 1/10W +-1%(0603)YGO'                  | 'CHIPR0603'    | ''          | ''            | '20221017'
 '33'         | '5%'      | '1/16W'  | '0402LF'  | 'CHIP'   | 'CS03302JB23'(!)        = ''              | ''                 | 'CS03302JB23'           | 'R0402'             | '(R0402-0201)'                 | '33'      | '5%'    | '1/16W'  | 'DISCRETE' | 'RES CHIP 33 1/16W +-5% (0402)YGO'                 | 'CHIPR0402'    | ''          | ''            | '20221017'
 '33'         | '5%'      | '1/16W'  | '0402LF'  | 'EMPTY'  | 'CS03302JB23'(!)        = ''              | ''                 | 'CS03302JB23'           | 'R0402'             | '(R0402-0201)'                 | '33'      | '5%'    | '1/16W'  | 'IO'       | 'RES CHIP 33 1/16W +-5% (0402)YGO'                 | 'CHIPR0402'    | ''          | ''            | '20221017'
 '60.4K'      | '1%'      | '1/16W'  | '0402LF'  | 'CHIP'   | 'CS36042FB09'(!)        = ''              | ''                 | 'CS36042FB09'           | 'R0402'             | '(R0402-0201)'                 | '60.4K'   | '1%'    | '1/16W'  | 'DISCRETE' | 'RES CHIP 60.4K 1/16W +-1%(0402)YGO'               | 'CHIPR0402'    | ''          | ''            | '20221017'
 '60.4K'      | '1%'      | '1/16W'  | '0402LF'  | 'EMPTY'  | 'CS36042FB09'(!)        = ''              | ''                 | 'CS36042FB09'           | 'R0402'             | '(R0402-0201)'                 | '60.4K'   | '1%'    | '1/16W'  | 'IO'       | 'RES CHIP 60.4K 1/16W +-1%(0402)YGO'               | 'CHIPR0402'    | ''          | ''            | '20221017'
 '0'          | ''        | '1/8W'   | '0805LF'  | 'CHIP'   | 'CS00004TA05'(!)        = ''              | ''                 | 'CS00004TA05'           | 'R0805_H26'         | '(SMR0805AW)'                  | '0'       | ''      | '1/8W'   | 'DISCRETE' | 'RES CHIP 0 1/8W(0805)WTC'                         | 'CHIPR0805'    | ''          | ''            | '20221018'
 '0'          | ''        | '1/8W'   | '0805LF'  | 'EMPTY'  | 'CS00004TA05'(!)        = ''              | ''                 | 'CS00004TA05'           | 'R0805_H26'         | '(SMR0805AW)'                  | '0'       | ''      | '1/8W'   | 'IO'       | 'RES CHIP 0 1/8W(0805)WTC'                         | 'CHIPR0805'    | ''          | ''            | '20221018'
 '330'        | '1%'      | '1/10W'  | '0603LF'  | 'CHIP'   | 'CS13303F906'(!)        = ''              | ''                 | 'CS13303F906'           | 'R0603_H24'         | '(SMR0603AW)'                  | '330'     | '1%'    | '1/10W'  | 'DISCRETE' | 'RES CHIP 330 1/10W +-1%(0603)WTC'                 | 'CHIPR0603'    | ''          | ''            | '20221018'
 '330'        | '1%'      | '1/10W'  | '0603LF'  | 'EMPTY'  | 'CS13303F906'(!)        = ''              | ''                 | 'CS13303F906'           | 'R0603_H24'         | '(SMR0603AW)'                  | '330'     | '1%'    | '1/10W'  | 'IO'       | 'RES CHIP 330 1/10W +-1%(0603)WTC'                 | 'CHIPR0603'    | ''          | ''            | '20221018'
 '10M'        | '5%'      | '1/16W'  | '0402LF'  | 'CHIP'   | 'CS61002JB17'(!)        = ''              | ''                 | 'CS61002JB17'           | 'R0402'             | '(R0402-0201)'                 | '10M'     | '5%'    | '1/16W'  | 'DISCRETE' | 'RES CHIP 10M 1/16W +-5% (0402)WTC'                | 'CHIPR0402'    | ''          | ''            | '20221019'
 '10M'        | '5%'      | '1/16W'  | '0402LF'  | 'EMPTY'  | 'CS61002JB17'(!)        = ''              | ''                 | 'CS61002JB17'           | 'R0402'             | '(R0402-0201)'                 | '10M'     | '5%'    | '1/16W'  | 'IO'       | 'RES CHIP 10M 1/16W +-5% (0402)WTC'                | 'CHIPR0402'    | ''          | ''            | '20221019'
 '49.9'       | '1%'      | '1/16W'  | '0402LF'  | 'CHIP'   | 'CS04992FB23'(!)        = ''              | ''                 | 'CS04992FB23'           | 'R0402'             | '(R0402-0201)'                 | '49.9'    | '1%'    | '1/16W'  | 'DISCRETE' | 'RES CHIP 49.9 1/16W +-1% (0402)WTC'               | 'CHIPR0402'    | ''          | ''            | '20221019'
 '49.9'       | '1%'      | '1/16W'  | '0402LF'  | 'EMPTY'  | 'CS04992FB23'(!)        = ''              | ''                 | 'CS04992FB23'           | 'R0402'             | '(R0402-0201)'                 | '49.9'    | '1%'    | '1/16W'  | 'IO'       | 'RES CHIP 49.9 1/16W +-1% (0402)WTC'               | 'CHIPR0402'    | ''          | ''            | '20221019'
 '1'          | '1%'      | '1/16W'  | '0402LF'  | 'CHIP'   | 'CS-1002FB26'(!)        = ''              | ''                 | 'CS-1002FB26'           | 'R0402'             | '(R0402-0201)'                 | '1'       | '1%'    | '1/16W'  | 'DISCRETE' | 'RES CHIP 1 1/16W +-1%(0402)WTC'                   | 'CHIPR0402'    | ''          | ''            | '20221019'
 '1'          | '1%'      | '1/16W'  | '0402LF'  | 'EMPTY'  | 'CS-1002FB26'(!)        = ''              | ''                 | 'CS-1002FB26'           | 'R0402'             | '(R0402-0201)'                 | '1'       | '1%'    | '1/16W'  | 'IO'       | 'RES CHIP 1 1/16W +-1%(0402)WTC'                   | 'CHIPR0402'    | ''          | ''            | '20221019'
 '4.53K'      | '1%'      | '1/16W'  | '0402LF'  | 'CHIP'   | 'CS24532FB06'(!)        = ''              | ''                 | 'CS24532FB06'           | 'R0402'             | '(R0402-0201)'                 | '4.53K'   | '1%'    | '1/16W'  | 'DISCRETE' | 'RES CHIP 4.53K 1/16W +-1%(0402)WTC'               | 'CHIPR0402'    | ''          | ''            | '20221019'
 '4.53K'      | '1%'      | '1/16W'  | '0402LF'  | 'EMPTY'  | 'CS24532FB06'(!)        = ''              | ''                 | 'CS24532FB06'           | 'R0402'             | '(R0402-0201)'                 | '4.53K'   | '1%'    | '1/16W'  | 'IO'       | 'RES CHIP 4.53K 1/16W +-1%(0402)WTC'               | 'CHIPR0402'    | ''          | ''            | '20221019'
 '10K'        | '1%'      | '1/16W'  | '0402LF'  | 'CHIP'   | 'CS31002FB20'(!)        = ''              | ''                 | 'CS31002FB20'           | 'R0402'             | '(R0402-0201)'                 | '10K'     | '1%'    | '1/16W'  | 'DISCRETE' | 'RES CHIP 10K 1/16W +-1%(0402)WTC'                 | 'CHIPR0402'    | ''          | ''            | '20221019'
 '10K'        | '1%'      | '1/16W'  | '0402LF'  | 'EMPTY'  | 'CS31002FB20'(!)        = ''              | ''                 | 'CS31002FB20'           | 'R0402'             | '(R0402-0201)'                 | '10K'     | '1%'    | '1/16W'  | 'IO'       | 'RES CHIP 10K 1/16W +-1%(0402)WTC'                 | 'CHIPR0402'    | ''          | ''            | '20221019'
 '24.9K'      | '1%'      | '1/16W'  | '0402LF'  | 'CHIP'   | 'CS32492FB13'(!)        = ''              | ''                 | 'CS32492FB13'           | 'R0402'             | '(R0402-0201)'                 | '24.9K'   | '1%'    | '1/16W'  | 'DISCRETE' | 'RES CHIP 24.9K 1/16W +-1%(0402)WTC'               | 'CHIPR0402'    | ''          | ''            | '20221019'
 '24.9K'      | '1%'      | '1/16W'  | '0402LF'  | 'EMPTY'  | 'CS32492FB13'(!)        = ''              | ''                 | 'CS32492FB13'           | 'R0402'             | '(R0402-0201)'                 | '24.9K'   | '1%'    | '1/16W'  | 'IO'       | 'RES CHIP 24.9K 1/16W +-1%(0402)WTC'               | 'CHIPR0402'    | ''          | ''            | '20221019'
 '40.2K'      | '1%'      | '1/16W'  | '0402LF'  | 'CHIP'   | 'CS34022FB14'(!)        = ''              | ''                 | 'CS34022FB14'           | 'R0402'             | '(R0402-0201)'                 | '40.2K'   | '1%'    | '1/16W'  | 'DISCRETE' | 'RES CHIP 40.2K 1/16W +-1%(0402)WTC'               | 'CHIPR0402'    | ''          | ''            | '20221019'
 '40.2K'      | '1%'      | '1/16W'  | '0402LF'  | 'EMPTY'  | 'CS34022FB14'(!)        = ''              | ''                 | 'CS34022FB14'           | 'R0402'             | '(R0402-0201)'                 | '40.2K'   | '1%'    | '1/16W'  | 'IO'       | 'RES CHIP 40.2K 1/16W +-1%(0402)WTC'               | 'CHIPR0402'    | ''          | ''            | '20221019'
 '1.13K'      | '1%'      | '1/16W'  | '0402LF'  | 'CHIP'   | 'CS21132FB03'(!)        = ''              | ''                 | 'CS21132FB03'           | 'R0402'             | '(R0402-0201)'                 | '1.13K'   | '1%'    | '1/16W'  | 'DISCRETE' | 'RES CHIP 1.13K 1/16W +-1% (0402)YGO'              | 'CHIPR0402'    | ''          | ''            | '20221019'
 '1.13K'      | '1%'      | '1/16W'  | '0402LF'  | 'EMPTY'  | 'CS21132FB03'(!)        = ''              | ''                 | 'CS21132FB03'           | 'R0402'             | '(R0402-0201)'                 | '1.13K'   | '1%'    | '1/16W'  | 'IO'       | 'RES CHIP 1.13K 1/16W +-1% (0402)YGO'              | 'CHIPR0402'    | ''          | ''            | '20221019'
 '1'          | '1%'      | '1/16W'  | '0402LF'  | 'CHIP'   | 'CS-1002FB06'(!)        = ''              | ''                 | 'CS-1002FB06'           | 'R0402'             | '(R0402-0201)'                 | '1'       | '1%'    | '1/16W'  | 'DISCRETE' | 'RES CHIP 1(+-1%,1/16W,0402)YGO'                   | 'CHIPR0402'    | ''          | ''            | '20221019'
 '1'          | '1%'      | '1/16W'  | '0402LF'  | 'EMPTY'  | 'CS-1002FB06'(!)        = ''              | ''                 | 'CS-1002FB06'           | 'R0402'             | '(R0402-0201)'                 | '1'       | '1%'    | '1/16W'  | 'IO'       | 'RES CHIP 1(+-1%,1/16W,0402)YGO'                   | 'CHIPR0402'    | ''          | ''            | '20221019'
 '4.53K'      | '1%'      | '1/16W'  | '0402LF'  | 'CHIP'   | 'CS24532FB07'(!)        = ''              | ''                 | 'CS24532FB07'           | 'R0402'             | '(R0402-0201)'                 | '4.53K'   | '1%'    | '1/16W'  | 'DISCRETE' | 'RES CHIP 4.53K 1/16W +-1%(0402)YGO'               | 'CHIPR0402'    | ''          | ''            | '20221019'
 '4.53K'      | '1%'      | '1/16W'  | '0402LF'  | 'EMPTY'  | 'CS24532FB07'(!)        = ''              | ''                 | 'CS24532FB07'           | 'R0402'             | '(R0402-0201)'                 | '4.53K'   | '1%'    | '1/16W'  | 'IO'       | 'RES CHIP 4.53K 1/16W +-1%(0402)YGO'               | 'CHIPR0402'    | ''          | ''            | '20221019'
 '11.8K'      | '1%'      | '1/16W'  | '0402LF'  | 'CHIP'   | 'CS31182FB10'(!)        = ''              | ''                 | 'CS31182FB10'           | 'R0402'             | '(R0402-0201)'                 | '11.8K'   | '1%'    | '1/16W'  | 'DISCRETE' | 'RES CHIP 11.8K 1/16W +-1% (0402)YGO'              | 'CHIPR0402'    | ''          | ''            | '20221019'
 '11.8K'      | '1%'      | '1/16W'  | '0402LF'  | 'EMPTY'  | 'CS31182FB10'(!)        = ''              | ''                 | 'CS31182FB10'           | 'R0402'             | '(R0402-0201)'                 | '11.8K'   | '1%'    | '1/16W'  | 'IO'       | 'RES CHIP 11.8K 1/16W +-1% (0402)YGO'              | 'CHIPR0402'    | ''          | ''            | '20221019'
 '24.9K'      | '1%'      | '1/16W'  | '0402LF'  | 'CHIP'   | 'CS32492FB12'(!)        = ''              | ''                 | 'CS32492FB12'           | 'R0402'             | '(R0402-0201)'                 | '24.9K'   | '1%'    | '1/16W'  | 'DISCRETE' | 'RES CHIP 24.9K 1/16W +-1%(0402)YGO'               | 'CHIPR0402'    | ''          | ''            | '20221019'
 '24.9K'      | '1%'      | '1/16W'  | '0402LF'  | 'EMPTY'  | 'CS32492FB12'(!)        = ''              | ''                 | 'CS32492FB12'           | 'R0402'             | '(R0402-0201)'                 | '24.9K'   | '1%'    | '1/16W'  | 'IO'       | 'RES CHIP 24.9K 1/16W +-1%(0402)YGO'               | 'CHIPR0402'    | ''          | ''            | '20221019'
 '40.2K'      | '1%'      | '1/16W'  | '0402LF'  | 'CHIP'   | 'CS34022FB13'(!)        = ''              | ''                 | 'CS34022FB13'           | 'R0402'             | '(R0402-0201)'                 | '40.2K'   | '1%'    | '1/16W'  | 'DISCRETE' | 'RES CHIP 40.2K 1/16W +-1% (0402)YGO'              | 'CHIPR0402'    | ''          | ''            | '20221019'
 '40.2K'      | '1%'      | '1/16W'  | '0402LF'  | 'EMPTY'  | 'CS34022FB13'(!)        = ''              | ''                 | 'CS34022FB13'           | 'R0402'             | '(R0402-0201)'                 | '40.2K'   | '1%'    | '1/16W'  | 'IO'       | 'RES CHIP 40.2K 1/16W +-1% (0402)YGO'              | 'CHIPR0402'    | ''          | ''            | '20221019'
 '80.6K'      | '1%'      | '1/16W'  | '0402LF'  | 'CHIP'   | 'CS38062FB13'(!)        = ''              | ''                 | 'CS38062FB13'           | 'R0402'             | '(R0402-0201)'                 | '80.6K'   | '1%'    | '1/16W'  | 'DISCRETE' | 'RES CHIP 80.6K 1/16W +-1% (0402)YGO'              | 'CHIPR0402'    | ''          | ''            | '20221019'
 '80.6K'      | '1%'      | '1/16W'  | '0402LF'  | 'EMPTY'  | 'CS38062FB13'(!)        = ''              | ''                 | 'CS38062FB13'           | 'R0402'             | '(R0402-0201)'                 | '80.6K'   | '1%'    | '1/16W'  | 'IO'       | 'RES CHIP 80.6K 1/16W +-1% (0402)YGO'              | 'CHIPR0402'    | ''          | ''            | '20221019'
 '15'         | '1%'      | '1/16W'  | '0402LF'  | 'CHIP'   | 'CS01502FB08'(!)        = ''              | ''                 | 'CS01502FB08'           | 'R0402'             | '(R0402-0201)'                 | '15'      | '1%'    | '1/16W'  | 'DISCRETE' | 'RES CHIP 15 1/16W +-1% (0402)YGO'                 | 'CHIPR0402'    | ''          | ''            | '20221019'
 '15'         | '1%'      | '1/16W'  | '0402LF'  | 'EMPTY'  | 'CS01502FB08'(!)        = ''              | ''                 | 'CS01502FB08'           | 'R0402'             | '(R0402-0201)'                 | '15'      | '1%'    | '1/16W'  | 'IO'       | 'RES CHIP 15 1/16W +-1% (0402)YGO'                 | 'CHIPR0402'    | ''          | ''            | '20221019'
 '10M'        | '5%'      | '1/16W'  | '0402LF'  | 'CHIP'   | 'CS61002JB16'(!)        = ''              | ''                 | 'CS61002JB16'           | 'R0402'             | '(R0402-0201)'                 | '10M'     | '5%'    | '1/16W'  | 'DISCRETE' | 'RES CHIP 10M 1/16W +-5% (0402)YGO'                | 'CHIPR0402'    | ''          | ''            | '20221019'
 '10M'        | '5%'      | '1/16W'  | '0402LF'  | 'EMPTY'  | 'CS61002JB16'(!)        = ''              | ''                 | 'CS61002JB16'           | 'R0402'             | '(R0402-0201)'                 | '10M'     | '5%'    | '1/16W'  | 'IO'       | 'RES CHIP 10M 1/16W +-5% (0402)YGO'                | 'CHIPR0402'    | ''          | ''            | '20221019'
 '49.9'       | '1%'      | '1/10W'  | '0603LF'  | 'CHIP'   | 'CS04993F918'(!)        = ''              | ''                 | 'CS04993F918'           | 'R0603'             | '(SMR0603AW)'                  | '49.9'    | '1%'    | '1/10W'  | 'DISCRETE' | 'RES CHIP 49.9 1/10W +-1%(0603)YGO'                | 'CHIPR0603'    | ''          | ''            | '20221019'
 '49.9'       | '1%'      | '1/10W'  | '0603LF'  | 'EMPTY'  | 'CS04993F918'(!)        = ''              | ''                 | 'CS04993F918'           | 'R0603'             | '(SMR0603AW)'                  | '49.9'    | '1%'    | '1/10W'  | 'IO'       | 'RES CHIP 49.9 1/10W +-1%(0603)YGO'                | 'CHIPR0603'    | ''          | ''            | '20221019'
 '330'        | '1%'      | '1/10W'  | '0603LF'  | 'CHIP'   | 'CS13303F903'(!)        = ''              | ''                 | 'CS13303F903'           | 'R0603'             | '(SMR0603AW)'                  | '330'     | '1%'    | '1/10W'  | 'DISCRETE' | 'RES CHIP 330 1/10W +-1%(0603)YGO'                 | 'CHIPR0603'    | ''          | ''            | '20221019'
 '330'        | '1%'      | '1/10W'  | '0603LF'  | 'EMPTY'  | 'CS13303F903'(!)        = ''              | ''                 | 'CS13303F903'           | 'R0603'             | '(SMR0603AW)'                  | '330'     | '1%'    | '1/10W'  | 'IO'       | 'RES CHIP 330 1/10W +-1%(0603)YGO'                 | 'CHIPR0603'    | ''          | ''            | '20221019'
 '5.6'        | '1%'      | '1/16W'  | '0402LF'  | 'CHIP'   | 'CS-5602FB01'(!)        = ''              | ''                 | 'CS-5602FB01'           | 'R0402'             | '(R0402-0201)'                 | '5.6'     | '1%'    | '1/16W'  | 'DISCRETE' | 'RES CHIP 5.6 1/16W 1%(0402)EF'                    | 'CHIPR0402'    | ''          | ''            | '20221018'
 '5.6'        | '1%'      | '1/16W'  | '0402LF'  | 'EMPTY'  | 'CS-5602FB01'(!)        = ''              | ''                 | 'CS-5602FB01'           | 'R0402'             | '(R0402-0201)'                 | '5.6'     | '1%'    | '1/16W'  | 'IO'       | 'RES CHIP 5.6 1/16W 1%(0402)EF'                    | 'CHIPR0402'    | ''          | ''            | '20221018'
 '10K'        | '5%'      | '1/16W'  | '0402LF'  | 'CHIP'   | 'CS31002JB26'(!)        = ''              | ''                 | 'CS31002JB26'           | 'R0402'             | '(R0402-0201)'                 | '10K'     | '5%'    | '1/16W'  | 'DISCRETE' | 'RES CHIP 10K 1/16W 5%(0402)WTC'                   | 'CHIPR0402'    | ''          | ''            | '20221021'
 '10K'        | '5%'      | '1/16W'  | '0402LF'  | 'EMPTY'  | 'CS31002JB26'(!)        = ''              | ''                 | 'CS31002JB26'           | 'R0402'             | '(R0402-0201)'                 | '10K'     | '5%'    | '1/16W'  | 'IO'       | 'RES CHIP 10K 1/16W 5%(0402)WTC'                   | 'CHIPR0402'    | ''          | ''            | '20221021'
 '11K'        | '1%'      | '1/16W'  | '0402LF'  | 'CHIP'   | 'CS31102FB16'(!)        = ''              | ''                 | 'CS31102FB16'           | 'R0402'             | '(R0402-0201)'                 | '11K'     | '1%'    | '1/16W'  | 'DISCRETE' | 'RES CHIP 11K 1/16W +-1% (0402)WTC'                | 'CHIPR0402'    | ''          | ''            | '20221021'
 '11K'        | '1%'      | '1/16W'  | '0402LF'  | 'EMPTY'  | 'CS31102FB16'(!)        = ''              | ''                 | 'CS31102FB16'           | 'R0402'             | '(R0402-0201)'                 | '11K'     | '1%'    | '1/16W'  | 'IO'       | 'RES CHIP 11K 1/16W +-1% (0402)WTC'                | 'CHIPR0402'    | ''          | ''            | '20221021'
 '562K'       | '1%'      | '1/16W'  | '0402LF'  | 'CHIP'   | 'CS45622FB13'(!)        = ''              | ''                 | 'CS45622FB13'           | 'R0402'             | '(R0402-0201)'                 | '562K'    | '1%'    | '1/16W'  | 'DISCRETE' | 'RES CHIP 562K 1/16W +-1%(0402)WTC'                | 'CHIPR0402'    | ''          | ''            | '20221021'
 '562K'       | '1%'      | '1/16W'  | '0402LF'  | 'EMPTY'  | 'CS45622FB13'(!)        = ''              | ''                 | 'CS45622FB13'           | 'R0402'             | '(R0402-0201)'                 | '562K'    | '1%'    | '1/16W'  | 'IO'       | 'RES CHIP 562K 1/16W +-1%(0402)WTC'                | 'CHIPR0402'    | ''          | ''            | '20221021'
 '1M'         | '5%'      | '1/16W'  | '0402LF'  | 'CHIP'   | 'CS51002JB10'(!)        = ''              | ''                 | 'CS51002JB10'           | 'R0402'             | '(R0402-0201)'                 | '1M'      | '5%'    | '1/16W'  | 'DISCRETE' | 'RES CHIP 1M 1/16W +-5% (0402)WTC'                 | 'CHIPR0402'    | ''          | ''            | '20221021'
 '1M'         | '5%'      | '1/16W'  | '0402LF'  | 'EMPTY'  | 'CS51002JB10'(!)        = ''              | ''                 | 'CS51002JB10'           | 'R0402'             | '(R0402-0201)'                 | '1M'      | '5%'    | '1/16W'  | 'IO'       | 'RES CHIP 1M 1/16W +-5% (0402)WTC'                 | 'CHIPR0402'    | ''          | ''            | '20221021'
 '100'        | '1%'      | '1/16W'  | '0402LF'  | 'CHIP'   | 'CS11002FB29'(!)        = ''              | ''                 | 'CS11002FB29'           | 'R0402'             | '(R0402-0201)'                 | '100'     | '1%'    | '1/16W'  | 'DISCRETE' | 'RES CHIP 100 1/16W +-1%(0402)WTC'                 | 'CHIPR0402'    | ''          | ''            | '20221021'
 '100'        | '1%'      | '1/16W'  | '0402LF'  | 'EMPTY'  | 'CS11002FB29'(!)        = ''              | ''                 | 'CS11002FB29'           | 'R0402'             | '(R0402-0201)'                 | '100'     | '1%'    | '1/16W'  | 'IO'       | 'RES CHIP 100 1/16W +-1%(0402)WTC'                 | 'CHIPR0402'    | ''          | ''            | '20221021'
 '220'        | '5%'      | '1/16W'  | '0402LF'  | 'CHIP'   | 'CS12202JB11'(!)        = ''              | ''                 | 'CS12202JB11'           | 'R0402'             | '(R0402-0201)'                 | '220'     | '5%'    | '1/16W'  | 'DISCRETE' | 'RES CHIP 220 1/16W +-5%(0402)WTC'                 | 'CHIPR0402'    | ''          | ''            | '20221021'
 '220'        | '5%'      | '1/16W'  | '0402LF'  | 'EMPTY'  | 'CS12202JB11'(!)        = ''              | ''                 | 'CS12202JB11'           | 'R0402'             | '(R0402-0201)'                 | '220'     | '5%'    | '1/16W'  | 'IO'       | 'RES CHIP 220 1/16W +-5%(0402)WTC'                 | 'CHIPR0402'    | ''          | ''            | '20221021'
 '2.7K'       | '5%'      | '1/16W'  | '0402LF'  | 'CHIP'   | 'CS22702JB09'(!)        = ''              | ''                 | 'CS22702JB09'           | 'R0402'             | '(R0402-0201)'                 | '2.7K'    | '5%'    | '1/16W'  | 'DISCRETE' | 'RES CHIP 2.7K 1/16W +-5%(0402)WTC'                | 'CHIPR0402'    | ''          | ''            | '20221021'
 '2.7K'       | '5%'      | '1/16W'  | '0402LF'  | 'EMPTY'  | 'CS22702JB09'(!)        = ''              | ''                 | 'CS22702JB09'           | 'R0402'             | '(R0402-0201)'                 | '2.7K'    | '5%'    | '1/16W'  | 'IO'       | 'RES CHIP 2.7K 1/16W +-5%(0402)WTC'                | 'CHIPR0402'    | ''          | ''            | '20221021'
 '100'        | '5%'      | '1/16W'  | '0402LF'  | 'CHIP'   | 'CS11002JB19'(!)        = ''              | ''                 | 'CS11002JB19'           | 'R0402'             | '(R0402-0201)'                 | '100'     | '5%'    | '1/16W'  | 'DISCRETE' | 'RES CHIP 100 1/16W +-5%(0402)EF YGO'              | 'CHIPR0402'    | ''          | ''            | '20221024'
 '100'        | '5%'      | '1/16W'  | '0402LF'  | 'EMPTY'  | 'CS11002JB19'(!)        = ''              | ''                 | 'CS11002JB19'           | 'R0402'             | '(R0402-0201)'                 | '100'     | '5%'    | '1/16W'  | 'IO'       | 'RES CHIP 100 1/16W +-5%(0402)EF YGO'              | 'CHIPR0402'    | ''          | ''            | '20221024'
 '100'        | '5%'      | '1/16W'  | '0402LF'  | 'CHIP'   | 'CS11002JB18'(!)        = ''              | ''                 | 'CS11002JB18'           | 'R0402'             | '(R0402-0201)'                 | '100'     | '5%'    | '1/16W'  | 'DISCRETE' | 'RES CHIP 100 1/16W +-5%(0402)EF WTC'              | 'CHIPR0402'    | ''          | ''            | '20221024'
 '100'        | '5%'      | '1/16W'  | '0402LF'  | 'EMPTY'  | 'CS11002JB18'(!)        = ''              | ''                 | 'CS11002JB18'           | 'R0402'             | '(R0402-0201)'                 | '100'     | '5%'    | '1/16W'  | 'IO'       | 'RES CHIP 100 1/16W +-5%(0402)EF WTC'              | 'CHIPR0402'    | ''          | ''            | '20221024'
 '22'         | '1%'      | '1/16W'  | '0402LF'  | 'CHIP'   | 'CS02202FB10'(!)        = ''              | ''                 | 'CS02202FB10'           | 'R0402'             | '(R0402-0201)'                 | '22'      | '1%'    | '1/16W'  | 'DISCRETE' | 'RES CHIP 22 1/16W +-1%(0402)WTC'                  | 'CHIPR0402'    | ''          | ''            | '20221024'
 '22'         | '1%'      | '1/16W'  | '0402LF'  | 'EMPTY'  | 'CS02202FB10'(!)        = ''              | ''                 | 'CS02202FB10'           | 'R0402'             | '(R0402-0201)'                 | '22'      | '1%'    | '1/16W'  | 'IO'       | 'RES CHIP 22 1/16W +-1%(0402)WTC'                  | 'CHIPR0402'    | ''          | ''            | '20221024'
 '22'         | '1%'      | '1/16W'  | '0402LF'  | 'CHIP'   | 'CS02202FB11'(!)        = ''              | ''                 | 'CS02202FB11'           | 'R0402'             | '(R0402-0201)'                 | '22'      | '1%'    | '1/16W'  | 'DISCRETE' | 'RES CHIP 22 1/16W +-1%(0402)YGO'                  | 'CHIPR0402'    | ''          | ''            | '20221024'
 '22'         | '1%'      | '1/16W'  | '0402LF'  | 'EMPTY'  | 'CS02202FB11'(!)        = ''              | ''                 | 'CS02202FB11'           | 'R0402'             | '(R0402-0201)'                 | '22'      | '1%'    | '1/16W'  | 'IO'       | 'RES CHIP 22 1/16W +-1%(0402)YGO'                  | 'CHIPR0402'    | ''          | ''            | '20221024'
 '69.8K'      | '1%'      | '1/16W'  | '0402LF'  | 'CHIP'   | 'CS36982FB10'(!)        = ''              | ''                 | 'CS36982FB10'           | 'R0402'             | '(R0402-0201)'                 | '69.8K'   | '1%'    | '1/16W'  | 'DISCRETE' | 'RES CHIP 69.8K 1/16W +-1% (0402)YGO'              | 'CHIPR0402'    | ''          | ''            | '20221024'
 '69.8K'      | '1%'      | '1/16W'  | '0402LF'  | 'EMPTY'  | 'CS36982FB10'(!)        = ''              | ''                 | 'CS36982FB10'           | 'R0402'             | '(R0402-0201)'                 | '69.8K'   | '1%'    | '1/16W'  | 'IO'       | 'RES CHIP 69.8K 1/16W +-1% (0402)YGO'              | 'CHIPR0402'    | ''          | ''            | '20221024'
 '47.5K'      | '1%'      | '1/16W'  | '0402LF'  | 'CHIP'   | 'CS34752FB11'(!)        = ''              | ''                 | 'CS34752FB11'           | 'R0402'             | '(R0402-0201)'                 | '47.5K'   | '1%'    | '1/16W'  | 'DISCRETE' | 'RES CHIP 47.5K 1/16W +-1% (0402)WTC'              | 'CHIPR0402'    | ''          | ''            | '20221025'
 '47.5K'      | '1%'      | '1/16W'  | '0402LF'  | 'EMPTY'  | 'CS34752FB11'(!)        = ''              | ''                 | 'CS34752FB11'           | 'R0402'             | '(R0402-0201)'                 | '47.5K'   | '1%'    | '1/16W'  | 'IO'       | 'RES CHIP 47.5K 1/16W +-1% (0402)WTC'              | 'CHIPR0402'    | ''          | ''            | '20221025'
 '10.5K'      | '1%'      | '1/16W'  | '0402LF'  | 'CHIP'   | 'CS31052FB07'(!)        = ''              | ''                 | 'CS31052FB07'           | 'R0402'             | '(R0402-0201)'                 | '10.5K'   | '1%'    | '1/16W'  | 'DISCRETE' | 'RES CHIP 10.5K 1/16W +-1%( 0402)YGO'              | 'CHIPR0402'    | ''          | ''            | '20221025'
 '10.5K'      | '1%'      | '1/16W'  | '0402LF'  | 'EMPTY'  | 'CS31052FB07'(!)        = ''              | ''                 | 'CS31052FB07'           | 'R0402'             | '(R0402-0201)'                 | '10.5K'   | '1%'    | '1/16W'  | 'IO'       | 'RES CHIP 10.5K 1/16W +-1%( 0402)YGO'              | 'CHIPR0402'    | ''          | ''            | '20221025'
 '1'          | '5%'      | '1/16W'  | '0402LF'  | 'CHIP'   | 'CS-1002JB16'(!)        = ''              | ''                 | 'CS-1002JB16'           | 'R0402'             | '(R0402-0201)'                 | '1'       | '5%'    | '1/16W'  | 'DISCRETE' | 'RES CHIP 1 1/16W +-5%(0402)WTC'                   | 'CHIPR0402'    | ''          | ''            | '20221025'
 '1'          | '5%'      | '1/16W'  | '0402LF'  | 'EMPTY'  | 'CS-1002JB16'(!)        = ''              | ''                 | 'CS-1002JB16'           | 'R0402'             | '(R0402-0201)'                 | '1'       | '5%'    | '1/16W'  | 'IO'       | 'RES CHIP 1 1/16W +-5%(0402)WTC'                   | 'CHIPR0402'    | ''          | ''            | '20221025'
 '1K'         | '5%'      | '1/16W'  | '0402LF'  | 'CHIP'   | 'CS21002JB27'(!)        = ''              | ''                 | 'CS21002JB27'           | 'R0402'             | '(R0402-0201)'                 | '1K'      | '5%'    | '1/16W'  | 'DISCRETE' | 'RES CHIP 1K 1/16W 5%(0402) YGO'                   | 'CHIPR0402'    | ''          | ''            | '20221017'
 '1K'         | '5%'      | '1/16W'  | '0402LF'  | 'EMPTY'  | 'CS21002JB27'(!)        = ''              | ''                 | 'CS21002JB27'           | 'R0402'             | '(R0402-0201)'                 | '1K'      | '5%'    | '1/16W'  | 'IO'       | 'RES CHIP 1K 1/16W 5%(0402) YGO'                   | 'CHIPR0402'    | ''          | ''            | '20221017'
 '4.7K'       | '5%'      | '1/16W'  | '0402LF'  | 'CHIP'   | 'CS24702JB19'(!)        = ''              | ''                 | 'CS24702JB19'           | 'R0402'             | '(R0402-0201)'                 | '4.7K'    | '5%'    | '1/16W'  | 'DISCRETE' | 'RES CHIP 4.7K 1/16W +-5% (0402)YGO'               | 'CHIPR0402'    | ''          | ''            | '20221103'
 '4.7K'       | '5%'      | '1/16W'  | '0402LF'  | 'EMPTY'  | 'CS24702JB19'(!)        = ''              | ''                 | 'CS24702JB19'           | 'R0402'             | '(R0402-0201)'                 | '4.7K'    | '5%'    | '1/16W'  | 'IO'       | 'RES CHIP 4.7K 1/16W +-5% (0402)YGO'               | 'CHIPR0402'    | ''          | ''            | '20221103'
 '1K'         | '1%'      | '1/16W'  | '0402LF'  | 'CHIP'   | 'CS21002FB28'(!)        = ''              | ''                 | 'CS21002FB28'           | 'R0402'             | '(R0402-0201)'                 | '1K'      | '1%'    | '1/16W'  | 'DISCRETE' | 'RES CHIP 1K 1/16W +-1% (0402)YGO'                 | 'CHIPR0402'    | ''          | ''            | '20221103'
 '1K'         | '1%'      | '1/16W'  | '0402LF'  | 'EMPTY'  | 'CS21002FB28'(!)        = ''              | ''                 | 'CS21002FB28'           | 'R0402'             | '(R0402-0201)'                 | '1K'      | '1%'    | '1/16W'  | 'IO'       | 'RES CHIP 1K 1/16W +-1% (0402)YGO'                 | 'CHIPR0402'    | ''          | ''            | '20221103'
 '10K'        | '1%'      | '1/16W'  | '0402LF'  | 'CHIP'   | 'CS31002FB28'(!)        = ''              | ''                 | 'CS31002FB28'           | 'R0402'             | '(R0402-0201)'                 | '10K'     | '1%'    | '1/16W'  | 'DISCRETE' | 'RES CHIP 10K 1/16W +-1% (0402)YGO'                | 'CHIPR0402'    | ''          | ''            | '20221103'
 '10K'        | '1%'      | '1/16W'  | '0402LF'  | 'EMPTY'  | 'CS31002FB28'(!)        = ''              | ''                 | 'CS31002FB28'           | 'R0402'             | '(R0402-0201)'                 | '10K'     | '1%'    | '1/16W'  | 'IO'       | 'RES CHIP 10K 1/16W +-1% (0402)YGO'                | 'CHIPR0402'    | ''          | ''            | '20221103'
 '15.4K'      | '1%'      | '1/16W'  | '0402LF'  | 'CHIP'   | 'CS31542FB10'(!)        = ''              | ''                 | 'CS31542FB10'           | 'R0402'             | '(R0402-0201)'                 | '15.4K'   | '1%'    | '1/16W'  | 'DISCRETE' | 'RES CHIP 15.4K 1/16W +-1%(0402)WTC'               | 'CHIPR0402'    | ''          | ''            | '20221114'
 '15.4K'      | '1%'      | '1/16W'  | '0402LF'  | 'EMPTY'  | 'CS31542FB10'(!)        = ''              | ''                 | 'CS31542FB10'           | 'R0402'             | '(R0402-0201)'                 | '15.4K'   | '1%'    | '1/16W'  | 'IO'       | 'RES CHIP 15.4K 1/16W +-1%(0402)WTC'               | 'CHIPR0402'    | ''          | ''            | '20221114'
 '20M'        | '5%'      | '1/16W'  | '0402LF'  | 'CHIP'   | 'CS62002JB03'(!)        = ''              | ''                 | 'CS62002JB03'           | 'R0402'             | '(R0402-0201)'                 | '20M'     | '5%'    | '1/16W'  | 'DISCRETE' | 'RES CHIP 20M 1/16W +-5%(0402)WTC'                 | 'CHIPR0402'    | ''          | ''            | '20221114'
 '20M'        | '5%'      | '1/16W'  | '0402LF'  | 'EMPTY'  | 'CS62002JB03'(!)        = ''              | ''                 | 'CS62002JB03'           | 'R0402'             | '(R0402-0201)'                 | '20M'     | '5%'    | '1/16W'  | 'IO'       | 'RES CHIP 20M 1/16W +-5%(0402)WTC'                 | 'CHIPR0402'    | ''          | ''            | '20221114'
 '2K'         | '5%'      | '1/16W'  | '0402LF'  | 'CHIP'   | 'CS22002JB09'(!)        = ''              | ''                 | 'CS22002JB09'           | 'R0402'             | '(R0402-0201)'                 | '2K'      | '5%'    | '1/16W'  | 'DISCRETE' | 'RES CHIP 2K 1/16W +-5% 0402)WTC'                  | 'CHIPR0402'    | ''          | ''            | '20221114'
 '2K'         | '5%'      | '1/16W'  | '0402LF'  | 'EMPTY'  | 'CS22002JB09'(!)        = ''              | ''                 | 'CS22002JB09'           | 'R0402'             | '(R0402-0201)'                 | '2K'      | '5%'    | '1/16W'  | 'IO'       | 'RES CHIP 2K 1/16W +-5% 0402)WTC'                  | 'CHIPR0402'    | ''          | ''            | '20221114'
 '8.2K'       | '5%'      | '1/16W'  | '0402LF'  | 'CHIP'   | 'CS28202JB10'(!)        = ''              | ''                 | 'CS28202JB10'           | 'R0402'             | '(R0402-0201)'                 | '8.2K'    | '5%'    | '1/16W'  | 'DISCRETE' | 'RES CHIP 8.2K 1/16W +-5% (0402)WTC'               | 'CHIPR0402'    | ''          | ''            | '20221114'
 '8.2K'       | '5%'      | '1/16W'  | '0402LF'  | 'EMPTY'  | 'CS28202JB10'(!)        = ''              | ''                 | 'CS28202JB10'           | 'R0402'             | '(R0402-0201)'                 | '8.2K'    | '5%'    | '1/16W'  | 'IO'       | 'RES CHIP 8.2K 1/16W +-5% (0402)WTC'               | 'CHIPR0402'    | ''          | ''            | '20221114'
 '12.1K'      | '1%'      | '1/16W'  | '0402LF'  | 'CHIP'   | 'CS31212FB12'(!)        = ''              | ''                 | 'CS31212FB12'           | 'R0402'             | '(R0402-0201)'                 | '12.1K'   | '1%'    | '1/16W'  | 'DISCRETE' | 'RES CHIP 12.1K 1/16W +-1%(0402)WTC'               | 'CHIPR0402'    | ''          | ''            | '20221114'
 '12.1K'      | '1%'      | '1/16W'  | '0402LF'  | 'EMPTY'  | 'CS31212FB12'(!)        = ''              | ''                 | 'CS31212FB12'           | 'R0402'             | '(R0402-0201)'                 | '12.1K'   | '1%'    | '1/16W'  | 'IO'       | 'RES CHIP 12.1K 1/16W +-1%(0402)WTC'               | 'CHIPR0402'    | ''          | ''            | '20221114'
 '20K'        | '1%'      | '1/16W'  | '0402LF'  | 'CHIP'   | 'CS32002FB25'(!)        = ''              | ''                 | 'CS32002FB25'           | 'R0402'             | '(R0402-0201)'                 | '20K'     | '1%'    | '1/16W'  | 'DISCRETE' | 'RES CHIP 20K 1/16W +-1%(0402)WTC'                 | 'CHIPR0402'    | ''          | ''            | '20221114'
 '20K'        | '1%'      | '1/16W'  | '0402LF'  | 'EMPTY'  | 'CS32002FB25'(!)        = ''              | ''                 | 'CS32002FB25'           | 'R0402'             | '(R0402-0201)'                 | '20K'     | '1%'    | '1/16W'  | 'IO'       | 'RES CHIP 20K 1/16W +-1%(0402)WTC'                 | 'CHIPR0402'    | ''          | ''            | '20221114'
 '25.5K'      | '1%'      | '1/16W'  | '0402LF'  | 'CHIP'   | 'CS32552FB13'(!)        = ''              | ''                 | 'CS32552FB13'           | 'R0402'             | '(R0402-0201)'                 | '25.5K'   | '1%'    | '1/16W'  | 'DISCRETE' | 'RES CHIP 25.5K 1/16W +-1%(0402)WTC'               | 'CHIPR0402'    | ''          | ''            | '20221114'
 '25.5K'      | '1%'      | '1/16W'  | '0402LF'  | 'EMPTY'  | 'CS32552FB13'(!)        = ''              | ''                 | 'CS32552FB13'           | 'R0402'             | '(R0402-0201)'                 | '25.5K'   | '1%'    | '1/16W'  | 'IO'       | 'RES CHIP 25.5K 1/16W +-1%(0402)WTC'               | 'CHIPR0402'    | ''          | ''            | '20221114'
 '86.6K'      | '1%'      | '1/16W'  | '0402LF'  | 'CHIP'   | 'CS38662FB07'(!)        = ''              | ''                 | 'CS38662FB07'           | 'R0402'             | '(R0402-0201)'                 | '86.6K'   | '1%'    | '1/16W'  | 'DISCRETE' | 'RES CHIP 86.6K 1/16W +-1% (0402)WTC'              | 'CHIPR0402'    | ''          | ''            | '20221114'
 '86.6K'      | '1%'      | '1/16W'  | '0402LF'  | 'EMPTY'  | 'CS38662FB07'(!)        = ''              | ''                 | 'CS38662FB07'           | 'R0402'             | '(R0402-0201)'                 | '86.6K'   | '1%'    | '1/16W'  | 'IO'       | 'RES CHIP 86.6K 1/16W +-1% (0402)WTC'              | 'CHIPR0402'    | ''          | ''            | '20221114'
 '1'          | '1%'      | '1/10W'  | '0603LF'  | 'CHIP'   | 'CS-1003F907'(!)        = ''              | ''                 | 'CS-1003F907'           | 'R0603_H24'         | '(SMR0603AW)'                  | '1'       | '1%'    | '1/10W'  | 'DISCRETE' | 'RES CHIP 1 1/10W +-1%(0603)WTC'                   | 'CHIPR0603'    | ''          | ''            | '20221114'
 '1'          | '1%'      | '1/10W'  | '0603LF'  | 'EMPTY'  | 'CS-1003F907'(!)        = ''              | ''                 | 'CS-1003F907'           | 'R0603_H24'         | '(SMR0603AW)'                  | '1'       | '1%'    | '1/10W'  | 'IO'       | 'RES CHIP 1 1/10W +-1%(0603)WTC'                   | 'CHIPR0603'    | ''          | ''            | '20221114'
 '2.2K'       | '5%'      | '1/16W'  | '0402LF'  | 'CHIP'   | 'CS22202JB26'(!)        = ''              | ''                 | 'CS22202JB26'           | 'R0402'             | '(R0402-0201)'                 | '2.2K'    | '5%'    | '1/16W'  | 'DISCRETE' | 'RES CHIP 2.2K 1/16W +-5%(0402)WTC'                | 'CHIPR0402'    | ''          | ''            | '20221115'
 '2.2K'       | '5%'      | '1/16W'  | '0402LF'  | 'EMPTY'  | 'CS22202JB26'(!)        = ''              | ''                 | 'CS22202JB26'           | 'R0402'             | '(R0402-0201)'                 | '2.2K'    | '5%'    | '1/16W'  | 'IO'       | 'RES CHIP 2.2K 1/16W +-5%(0402)WTC'                | 'CHIPR0402'    | ''          | ''            | '20221115'
 '12.7K'      | '1%'      | '1/16W'  | '0402LF'  | 'CHIP'   | 'CS31272FB11'(!)        = ''              | ''                 | 'CS31272FB11'           | 'R0402'             | '(R0402-0201)'                 | '12.7K'   | '1%'    | '1/16W'  | 'DISCRETE' | 'RES CHIP 12.7K 1/16W +-1% (0402)WTC'              | 'CHIPR0402'    | ''          | ''            | '20221125'
 '12.7K'      | '1%'      | '1/16W'  | '0402LF'  | 'EMPTY'  | 'CS31272FB11'(!)        = ''              | ''                 | 'CS31272FB11'           | 'R0402'             | '(R0402-0201)'                 | '12.7K'   | '1%'    | '1/16W'  | 'IO'       | 'RES CHIP 12.7K 1/16W +-1% (0402)WTC'              | 'CHIPR0402'    | ''          | ''            | '20221125'
 '82K'        | '1%'      | '1/16W'  | '0402LF'  | 'CHIP'   | 'CS38202FB05'(!)        = ''              | ''                 | 'CS38202FB05'           | 'R0402'             | '(R0402-0201)'                 | '82K'     | '1%'    | '1/16W'  | 'DISCRETE' | 'RES CHIP 82K  1/16W +-1% (0402)WTC'               | 'CHIPR0402'    | ''          | ''            | '20221125'
 '82K'        | '1%'      | '1/16W'  | '0402LF'  | 'EMPTY'  | 'CS38202FB05'(!)        = ''              | ''                 | 'CS38202FB05'           | 'R0402'             | '(R0402-0201)'                 | '82K'     | '1%'    | '1/16W'  | 'IO'       | 'RES CHIP 82K  1/16W +-1% (0402)WTC'               | 'CHIPR0402'    | ''          | ''            | '20221125'
 '3.3K'       | '5%'      | '1/16W'  | '0402LF'  | 'CHIP'   | 'CS23302JB11'(!)        = ''              | ''                 | 'CS23302JB11'           | 'R0402'             | '(R0402-0201)'                 | '3.3K'    | '5%'    | '1/16W'  | 'DISCRETE' | 'RES CHIP 3.3K 1/16W +-5%(0402)WTC'                | 'CHIPR0402'    | ''          | ''            | '20221125'
 '3.3K'       | '5%'      | '1/16W'  | '0402LF'  | 'EMPTY'  | 'CS23302JB11'(!)        = ''              | ''                 | 'CS23302JB11'           | 'R0402'             | '(R0402-0201)'                 | '3.3K'    | '5%'    | '1/16W'  | 'IO'       | 'RES CHIP 3.3K 1/16W +-5%(0402)WTC'                | 'CHIPR0402'    | ''          | ''            | '20221125'
 '3.9K'       | '1%'      | '1/16W'  | '0402LF'  | 'CHIP'   | 'CS23902FB09'(!)        = ''              | ''                 | 'CS23902FB09'           | 'R0402'             | '(R0402-0201)'                 | '3.9K'    | '1%'    | '1/16W'  | 'DISCRETE' | 'RES CHIP 3.9K 1/16W+-1%(0402)WTC'                 | 'CHIPR0402'    | ''          | ''            | '20221125'
 '3.9K'       | '1%'      | '1/16W'  | '0402LF'  | 'EMPTY'  | 'CS23902FB09'(!)        = ''              | ''                 | 'CS23902FB09'           | 'R0402'             | '(R0402-0201)'                 | '3.9K'    | '1%'    | '1/16W'  | 'IO'       | 'RES CHIP 3.9K 1/16W+-1%(0402)WTC'                 | 'CHIPR0402'    | ''          | ''            | '20221125'
 '8.06K'      | '1%'      | '1/16W'  | '0402LF'  | 'CHIP'   | 'CS28062FB13'(!)        = ''              | ''                 | 'CS28062FB13'           | 'R0402'             | '(R0402-0201)'                 | '8.06K'   | '1%'    | '1/16W'  | 'DISCRETE' | 'RES CHIP 8.06K 1/16W +-1%(0402)WTC'               | 'CHIPR0402'    | ''          | ''            | '20221125'
 '8.06K'      | '1%'      | '1/16W'  | '0402LF'  | 'EMPTY'  | 'CS28062FB13'(!)        = ''              | ''                 | 'CS28062FB13'           | 'R0402'             | '(R0402-0201)'                 | '8.06K'   | '1%'    | '1/16W'  | 'IO'       | 'RES CHIP 8.06K 1/16W +-1%(0402)WTC'               | 'CHIPR0402'    | ''          | ''            | '20221125'
 '8.25K'      | '1%'      | '1/16W'  | '0402LF'  | 'CHIP'   | 'CS28252FB13'(!)        = ''              | ''                 | 'CS28252FB13'           | 'R0402'             | '(R0402-0201)'                 | '8.25K'   | '1%'    | '1/16W'  | 'DISCRETE' | 'RES CHIP 8.25K 1/16W+-1%(0402)WTC'                | 'CHIPR0402'    | ''          | ''            | '20221125'
 '8.25K'      | '1%'      | '1/16W'  | '0402LF'  | 'EMPTY'  | 'CS28252FB13'(!)        = ''              | ''                 | 'CS28252FB13'           | 'R0402'             | '(R0402-0201)'                 | '8.25K'   | '1%'    | '1/16W'  | 'IO'       | 'RES CHIP 8.25K 1/16W+-1%(0402)WTC'                | 'CHIPR0402'    | ''          | ''            | '20221125'
 '9.09K'      | '1%'      | '1/16W'  | '0402LF'  | 'CHIP'   | 'CS29092FB11'(!)        = ''              | ''                 | 'CS29092FB11'           | 'R0402'             | '(R0402-0201)'                 | '9.09K'   | '1%'    | '1/16W'  | 'DISCRETE' | 'RES CHIP 9.09K 1/16W +-1%(0402)WTC'               | 'CHIPR0402'    | ''          | ''            | '20221125'
 '9.09K'      | '1%'      | '1/16W'  | '0402LF'  | 'EMPTY'  | 'CS29092FB11'(!)        = ''              | ''                 | 'CS29092FB11'           | 'R0402'             | '(R0402-0201)'                 | '9.09K'   | '1%'    | '1/16W'  | 'IO'       | 'RES CHIP 9.09K 1/16W +-1%(0402)WTC'               | 'CHIPR0402'    | ''          | ''            | '20221125'
 '9.31K'      | '1%'      | '1/16W'  | '0402LF'  | 'CHIP'   | 'CS29312FB09'(!)        = ''              | ''                 | 'CS29312FB09'           | 'R0402'             | '(R0402-0201)'                 | '9.31K'   | '1%'    | '1/16W'  | 'DISCRETE' | 'RES CHIP 9.31K 1/16W +-1%(0402)WTC'               | 'CHIPR0402'    | ''          | ''            | '20221125'
 '9.31K'      | '1%'      | '1/16W'  | '0402LF'  | 'EMPTY'  | 'CS29312FB09'(!)        = ''              | ''                 | 'CS29312FB09'           | 'R0402'             | '(R0402-0201)'                 | '9.31K'   | '1%'    | '1/16W'  | 'IO'       | 'RES CHIP 9.31K 1/16W +-1%(0402)WTC'               | 'CHIPR0402'    | ''          | ''            | '20221125'
 '11.5K'      | '1%'      | '1/16W'  | '0402LF'  | 'CHIP'   | 'CS31152FB12'(!)        = ''              | ''                 | 'CS31152FB12'           | 'R0402'             | '(R0402-0201)'                 | '11.5K'   | '1%'    | '1/16W'  | 'DISCRETE' | 'RES CHIP 11.5K 1/16W +-1%( 0402)WTC'              | 'CHIPR0402'    | ''          | ''            | '20221125'
 '11.5K'      | '1%'      | '1/16W'  | '0402LF'  | 'EMPTY'  | 'CS31152FB12'(!)        = ''              | ''                 | 'CS31152FB12'           | 'R0402'             | '(R0402-0201)'                 | '11.5K'   | '1%'    | '1/16W'  | 'IO'       | 'RES CHIP 11.5K 1/16W +-1%( 0402)WTC'              | 'CHIPR0402'    | ''          | ''            | '20221125'
 '56K'        | '1%'      | '1/16W'  | '0402LF'  | 'CHIP'   | 'CS35602FB07'(!)        = ''              | ''                 | 'CS35602FB07'           | 'R0402'             | '(R0402-0201)'                 | '56K'     | '1%'    | '1/16W'  | 'DISCRETE' | 'RES CHIP 56K 1/16W +-1%(0402)WTC'                 | 'CHIPR0402'    | ''          | ''            | '20221125'
 '56K'        | '1%'      | '1/16W'  | '0402LF'  | 'EMPTY'  | 'CS35602FB07'(!)        = ''              | ''                 | 'CS35602FB07'           | 'R0402'             | '(R0402-0201)'                 | '56K'     | '1%'    | '1/16W'  | 'IO'       | 'RES CHIP 56K 1/16W +-1%(0402)WTC'                 | 'CHIPR0402'    | ''          | ''            | '20221125'
 '68.1K'      | '1%'      | '1/16W'  | '0402LF'  | 'CHIP'   | 'CS36812FB09'(!)        = ''              | ''                 | 'CS36812FB09'           | 'R0402'             | '(R0402-0201)'                 | '68.1K'   | '1%'    | '1/16W'  | 'DISCRETE' | 'RES CHIP 68.1K 1/16W +-1%(0402)WTC'               | 'CHIPR0402'    | ''          | ''            | '20221125'
 '68.1K'      | '1%'      | '1/16W'  | '0402LF'  | 'EMPTY'  | 'CS36812FB09'(!)        = ''              | ''                 | 'CS36812FB09'           | 'R0402'             | '(R0402-0201)'                 | '68.1K'   | '1%'    | '1/16W'  | 'IO'       | 'RES CHIP 68.1K 1/16W +-1%(0402)WTC'               | 'CHIPR0402'    | ''          | ''            | '20221125'
 '4.99K'      | '1%'      | '1/16W'  | '0402LF'  | 'CHIP'   | 'CS24992FB17'(!)        = ''              | ''                 | 'CS24992FB17'           | 'R0402'             | '(R0402-0201)'                 | '4.99K'   | '1%'    | '1/16W'  | 'DISCRETE' | 'RES CHIP 4.99K 1/16W +-1% (0402)WTC'              | 'CHIPR0402'    | ''          | ''            | '20221125'
 '4.99K'      | '1%'      | '1/16W'  | '0402LF'  | 'EMPTY'  | 'CS24992FB17'(!)        = ''              | ''                 | 'CS24992FB17'           | 'R0402'             | '(R0402-0201)'                 | '4.99K'   | '1%'    | '1/16W'  | 'IO'       | 'RES CHIP 4.99K 1/16W +-1% (0402)WTC'              | 'CHIPR0402'    | ''          | ''            | '20221125'
 '402'        | '1%'      | '1/16W'  | '0402LF'  | 'CHIP'   | 'CS14022FB14'(!)        = ''              | ''                 | 'CS14022FB14'           | 'R0402'             | '(R0402-0201)'                 | '402'     | '1%'    | '1/16W'  | 'DISCRETE' | 'RES CHIP 402 1/16W +-1%( 0402)WTC'                | 'CHIPR0402'    | ''          | ''            | '20221129'
 '402'        | '1%'      | '1/16W'  | '0402LF'  | 'EMPTY'  | 'CS14022FB14'(!)        = ''              | ''                 | 'CS14022FB14'           | 'R0402'             | '(R0402-0201)'                 | '402'     | '1%'    | '1/16W'  | 'IO'       | 'RES CHIP 402 1/16W +-1%( 0402)WTC'                | 'CHIPR0402'    | ''          | ''            | '20221129'
 '150K'       | '1%'      | '1/16W'  | '0402LF'  | 'CHIP'   | 'CS41502FB16'(!)        = ''              | ''                 | 'CS41502FB16'           | 'R0402'             | '(R0402-0201)'                 | '150K'    | '1%'    | '1/16W'  | 'DISCRETE' | 'RES CHIP 150K 1/16W +-1%(0402)WTC'                | 'CHIPR0402'    | ''          | ''            | '20221129'
 '150K'       | '1%'      | '1/16W'  | '0402LF'  | 'EMPTY'  | 'CS41502FB16'(!)        = ''              | ''                 | 'CS41502FB16'           | 'R0402'             | '(R0402-0201)'                 | '150K'    | '1%'    | '1/16W'  | 'IO'       | 'RES CHIP 150K 1/16W +-1%(0402)WTC'                | 'CHIPR0402'    | ''          | ''            | '20221129'
 '442'        | '1%'      | '1/16W'  | '0402LF'  | 'CHIP'   | 'CS14422FB03'(!)        = ''              | ''                 | 'CS14422FB03'           | 'R0402'             | '(R0402-0201)'                 | '442'     | '1%'    | '1/16W'  | 'DISCRETE' | 'RES CHIP 442 1/16W +-1% (0402)YGO'                | 'CHIPR0402'    | ''          | ''            | '20221129'
 '442'        | '1%'      | '1/16W'  | '0402LF'  | 'EMPTY'  | 'CS14422FB03'(!)        = ''              | ''                 | 'CS14422FB03'           | 'R0402'             | '(R0402-0201)'                 | '442'     | '1%'    | '1/16W'  | 'IO'       | 'RES CHIP 442 1/16W +-1% (0402)YGO'                | 'CHIPR0402'    | ''          | ''            | '20221129'
 '2K'         | '1%'      | '1/16W'  | '0402LF'  | 'CHIP'   | 'CS22002FB15'(!)        = ''              | ''                 | 'CS22002FB15'           | 'R0402'             | '(R0402-0201)'                 | '2K'      | '1%'    | '1/16W'  | 'DISCRETE' | 'RES CHIP 2K 1/16W +-1%(0402)WTC'                  | 'CHIPR0402'    | ''          | ''            | '20221129'
 '2K'         | '1%'      | '1/16W'  | '0402LF'  | 'EMPTY'  | 'CS22002FB15'(!)        = ''              | ''                 | 'CS22002FB15'           | 'R0402'             | '(R0402-0201)'                 | '2K'      | '1%'    | '1/16W'  | 'IO'       | 'RES CHIP 2K 1/16W +-1%(0402)WTC'                  | 'CHIPR0402'    | ''          | ''            | '20221129'
 '0.003'      | '1%'      | '3W'     | '2512LF'  | 'CHIP'   | 'CS+003DFR04'(!)        = ''              | ''                 | 'CS+003DFR04'           | 'R2512XF'           | '(SMR2512AW)'                  | '0.003'   | '1%'    | '3W'     | 'DISCRETE' | 'RES CHIP 0.003 3W +-1%(2512)TAI'                  | 'CHIPR2512'    | ''          | ''            | '20221201'
 '0.003'      | '1%'      | '3W'     | '2512LF'  | 'EMPTY'  | 'CS+003DFR04'(!)        = ''              | ''                 | 'CS+003DFR04'           | 'R2512XF'           | '(SMR2512AW)'                  | '0.003'   | '1%'    | '3W'     | 'IO'       | 'RES CHIP 0.003 3W +-1%(2512)TAI'                  | 'CHIPR2512'    | ''          | ''            | '20221201'
 '200'        | '1%'      | '1/20W'  | '0201LF'  | 'CHIP'   | 'CS12001FE12'(!)        = ''              | ''                 | 'CS12001FE12'           | 'R0201'             | '(SMR0201AW)'                  | '200'     | '1%'    | '1/20W'  | 'DISCRETE' | 'RES CHIP 200 1/20W +-1%(0201)EF'                  | 'CHIPR0201'    | ''          | ''            | '20221202'
 '200'        | '1%'      | '1/20W'  | '0201LF'  | 'EMPTY'  | 'CS12001FE12'(!)        = ''              | ''                 | 'CS12001FE12'           | 'R0201'             | '(SMR0201AW)'                  | '200'     | '1%'    | '1/20W'  | 'IO'       | 'RES CHIP 200 1/20W +-1%(0201)EF'                  | 'CHIPR0201'    | ''          | ''            | '20221202'
 '33.2'       | '1%'      | '1/20W'  | '0201LF'  | 'CHIP'   | 'CS03321FE09'(!)        = ''              | ''                 | 'CS03321FE09'           | 'R0201'             | '(SMR0201AW)'                  | '33.2'    | '1%'    | '1/20W'  | 'DISCRETE' | 'RES CHIP 33.2 1/20W +-1%(0201)EF'                 | 'CHIPR0201'    | ''          | ''            | '20221202'
 '33.2'       | '1%'      | '1/20W'  | '0201LF'  | 'EMPTY'  | 'CS03321FE09'(!)        = ''              | ''                 | 'CS03321FE09'           | 'R0201'             | '(SMR0201AW)'                  | '33.2'    | '1%'    | '1/20W'  | 'IO'       | 'RES CHIP 33.2 1/20W +-1%(0201)EF'                 | 'CHIPR0201'    | ''          | ''            | '20221202'
 '0.002'      | '1%'      | '3W'     | '2512LF'  | 'CHIP'   | 'CS+002DFR08'(!)        = ''              | ''                 | 'CS+002DFR08'           | 'R2512XJ'           | '(SMR2512AW)'                  | '0.002'   | '1%'    | '3W'     | 'DISCRETE' | 'RES CHIP 0.002 3W +-1%(2512)RLC'                  | 'CHIPR2512'    | ''          | ''            | '20221215'
 '0.002'      | '1%'      | '3W'     | '2512LF'  | 'EMPTY'  | 'CS+002DFR08'(!)        = ''              | ''                 | 'CS+002DFR08'           | 'R2512XJ'           | '(SMR2512AW)'                  | '0.002'   | '1%'    | '3W'     | 'IO'       | 'RES CHIP 0.002 3W +-1%(2512)RLC'                  | 'CHIPR2512'    | ''          | ''            | '20221215'
 '0.002'      | '1%'      | '3W'     | '2512LF'  | 'CHIP'   | 'CS+002DFR09'(!)        = ''              | ''                 | 'CS+002DFR09'           | 'R2512XF'           | '(SMR2512AW)'                  | '0.002'   | '1%'    | '3W'     | 'DISCRETE' | 'RES CHIP 0.002 3W +-1%(2512)TAI'                  | 'CHIPR2512'    | ''          | ''            | '20221215'
 '0.002'      | '1%'      | '3W'     | '2512LF'  | 'EMPTY'  | 'CS+002DFR09'(!)        = ''              | ''                 | 'CS+002DFR09'           | 'R2512XF'           | '(SMR2512AW)'                  | '0.002'   | '1%'    | '3W'     | 'IO'       | 'RES CHIP 0.002 3W +-1%(2512)TAI'                  | 'CHIPR2512'    | ''          | ''            | '20221215'
 '0.002'      | '1%'      | '3W'     | '2512LF'  | 'CHIP'   | 'CS+002DFR10'(!)        = ''              | ''                 | 'CS+002DFR10'           | 'R2512XAC'          | '(SMR2512AW)'                  | '0.002'   | '1%'    | '3W'     | 'DISCRETE' | 'RES CHIP 0.002 3W +-1%(2512)ERO'                  | 'CHIPR2512'    | ''          | ''            | '20221215'
 '0.002'      | '1%'      | '3W'     | '2512LF'  | 'EMPTY'  | 'CS+002DFR10'(!)        = ''              | ''                 | 'CS+002DFR10'           | 'R2512XAC'          | '(SMR2512AW)'                  | '0.002'   | '1%'    | '3W'     | 'IO'       | 'RES CHIP 0.002 3W +-1%(2512)ERO'                  | 'CHIPR2512'    | ''          | ''            | '20221215'
 '0.003'      | '1%'      | '3W'     | '2512LF'  | 'CHIP'   | 'CS+003DFR05'(!)        = ''              | ''                 | 'CS+003DFR05'           | 'R2512XAD'          | '(SMR2512AW)'                  | '0.003'   | '1%'    | '3W'     | 'DISCRETE' | 'RES CHIP 0.003 3W +-1%(2512)ERO'                  | 'CHIPR2512'    | ''          | ''            | '20221216'
 '0.003'      | '1%'      | '3W'     | '2512LF'  | 'EMPTY'  | 'CS+003DFR05'(!)        = ''              | ''                 | 'CS+003DFR05'           | 'R2512XAD'          | '(SMR2512AW)'                  | '0.003'   | '1%'    | '3W'     | 'IO'       | 'RES CHIP 0.003 3W +-1%(2512)ERO'                  | 'CHIPR2512'    | ''          | ''            | '20221216'
 '56K'        | '0.1%'    | '1/16W'  | '0402LF'  | 'CHIP'   | 'CS35602BB01'(!)        = 'End of Design' | 'Comp-Approve'     | 'CS35602BB01'           | 'R0402'             | '(R0402-0201)'                 | '56K'     | '0.1%'  | '1/16W'  | 'DISCRETE' | 'RES CHIP 56K 1/16W +-0.1%(0402)EF'                | 'CHIPR0402'    | ''          | ''            | '20221214'
 '56K'        | '0.1%'    | '1/16W'  | '0402LF'  | 'EMPTY'  | 'CS35602BB01'(!)        = 'End of Design' | 'Comp-Approve'     | 'CS35602BB01'           | 'R0402'             | '(R0402-0201)'                 | '56K'     | '0.1%'  | '1/16W'  | 'IO'       | 'RES CHIP 56K 1/16W +-0.1%(0402)EF'                | 'CHIPR0402'    | ''          | ''            | '20221214'
 '549'        | '1%'      | '1/16W'  | '0402LF'  | 'CHIP'   | 'CS15492FB09'(!)        = ''              | ''                 | 'CS15492FB09'           | 'R0402'             | '(R0402-0201)'                 | '549'     | '1%'    | '1/16W'  | 'DISCRETE' | 'RES CHIP 549 1/16W +-1%(0402)WTC'                 | 'CHIPR0402'    | ''          | ''            | '20221219'
 '549'        | '1%'      | '1/16W'  | '0402LF'  | 'EMPTY'  | 'CS15492FB09'(!)        = ''              | ''                 | 'CS15492FB09'           | 'R0402'             | '(R0402-0201)'                 | '549'     | '1%'    | '1/16W'  | 'IO'       | 'RES CHIP 549 1/16W +-1%(0402)WTC'                 | 'CHIPR0402'    | ''          | ''            | '20221219'
 '14.7K'      | '1%'      | '1/16W'  | '0402LF'  | 'CHIP'   | 'CS31472FB02'(!)        = 'End of Design' | 'Comp-Approve'     | 'CS31472FB02'           | 'R0402'             | '(R0402-0201)'                 | '14.7K'   | '1%'    | '1/16W'  | 'DISCRETE' | 'RES CHIP 14.7K 1/16W +-1%(0402)EF'                | 'CHIPR0402'    | ''          | ''            | '20221220'
 '14.7K'      | '1%'      | '1/16W'  | '0402LF'  | 'EMPTY'  | 'CS31472FB02'(!)        = 'End of Design' | 'Comp-Approve'     | 'CS31472FB02'           | 'R0402'             | '(R0402-0201)'                 | '14.7K'   | '1%'    | '1/16W'  | 'IO'       | 'RES CHIP 14.7K 1/16W +-1%(0402)EF'                | 'CHIPR0402'    | ''          | ''            | '20221220'
 '1.05K'      | '1%'      | '1/16W'  | '0402LF'  | 'CHIP'   | 'CS21052FB06'(!)        = ''              | ''                 | 'CS21052FB06'           | 'R0402'             | '(R0402-0201)'                 | '1.05K'   | '1%'    | '1/16W'  | 'DISCRETE' | 'RES CHIP 1.05K 1/16W +-1%(0402)EF'                | 'CHIPR0402'    | ''          | ''            | '20221221'
 '1.05K'      | '1%'      | '1/16W'  | '0402LF'  | 'EMPTY'  | 'CS21052FB06'(!)        = ''              | ''                 | 'CS21052FB06'           | 'R0402'             | '(R0402-0201)'                 | '1.05K'   | '1%'    | '1/16W'  | 'IO'       | 'RES CHIP 1.05K 1/16W +-1%(0402)EF'                | 'CHIPR0402'    | ''          | ''            | '20221221'
 '27'         | '1%'      | '1/16W'  | '0402LF'  | 'CHIP'   | 'CS02702FB01'(!)        = ''              | ''                 | 'CS02702FB01'           | 'R0402'             | '(R0402-0201)'                 | '27'      | '1%'    | '1/16W'  | 'DISCRETE' | 'RES CHIP 27 1/16W +-1%(0402)EF'                   | 'CHIPR0402'    | ''          | ''            | '20221222'
 '27'         | '1%'      | '1/16W'  | '0402LF'  | 'EMPTY'  | 'CS02702FB01'(!)        = ''              | ''                 | 'CS02702FB01'           | 'R0402'             | '(R0402-0201)'                 | '27'      | '1%'    | '1/16W'  | 'IO'       | 'RES CHIP 27 1/16W +-1%(0402)EF'                   | 'CHIPR0402'    | ''          | ''            | '20221222'
 '301'        | '1%'      | '1/16W'  | '0402LF'  | 'CHIP'   | 'CS13012FB10'(!)        = ''              | ''                 | 'CS13012FB10'           | 'R0402'             | '(R0402-0201)'                 | '301'     | '1%'    | '1/16W'  | 'DISCRETE' | 'RES CHIP 301 1/16W +-1%(0402)WTC'                 | 'CHIPR0402'    | ''          | ''            | '20221226'
 '301'        | '1%'      | '1/16W'  | '0402LF'  | 'EMPTY'  | 'CS13012FB10'(!)        = ''              | ''                 | 'CS13012FB10'           | 'R0402'             | '(R0402-0201)'                 | '301'     | '1%'    | '1/16W'  | 'IO'       | 'RES CHIP 301 1/16W +-1%(0402)WTC'                 | 'CHIPR0402'    | ''          | ''            | '20221226'
 '0.015'      | '0.5%'    | '7W'     | '2818LF'  | 'CHIP'   | 'CS+015LDX00'(!)        = ''              | ''                 | 'CS+015LDX00'           | 'R2818XA'           | '(SMR2818AW)'                  | '0.015'   | '0.5%'  | '7W'     | 'DISCRETE' | 'RES CHIP 0.015 7W +-0.5%(2818)SIL AEC'            | 'CHIPR2818'    | ''          | ''            | '20230118'
 '0.015'      | '0.5%'    | '7W'     | '2818LF'  | 'EMPTY'  | 'CS+015LDX00'(!)        = ''              | ''                 | 'CS+015LDX00'           | 'R2818XA'           | '(SMR2818AW)'                  | '0.015'   | '0.5%'  | '7W'     | 'IO'       | 'RES CHIP 0.015 7W +-0.5%(2818)SIL AEC'            | 'CHIPR2818'    | ''          | ''            | '20230118'
 '174K'       | '0.1%'    | '1/8W'   | '0805LF'  | 'CHIP'   | 'CS41744BA00'(!)        = ''              | ''                 | 'CS41744BA00'           | 'R0805_H26'         | '(SMR0805AW)'                  | '174K'    | '0.1%'  | '1/8W'   | 'DISCRETE' | 'RES CHIP 174K 1/8W +-0.1%(0805)EF'                | 'CHIPR0805'    | ''          | ''            | '20230218'
 '174K'       | '0.1%'    | '1/8W'   | '0805LF'  | 'EMPTY'  | 'CS41744BA00'(!)        = ''              | ''                 | 'CS41744BA00'           | 'R0805_H26'         | '(SMR0805AW)'                  | '174K'    | '0.1%'  | '1/8W'   | 'IO'       | 'RES CHIP 174K 1/8W +-0.1%(0805)EF'                | 'CHIPR0805'    | ''          | ''            | '20230218'
 '82K'        | '0.1%'    | '1/8W'   | '0805LF'  | 'CHIP'   | 'CS38204BA00'(!)        = ''              | ''                 | 'CS38204BA00'           | 'R0805_H26'         | '(SMR0805AW)'                  | '82K'     | '0.1%'  | '1/8W'   | 'DISCRETE' | 'RES CHIP 82K 1/8W +-0.1%(0805)EF'                 | 'CHIPR0805'    | ''          | ''            | '20230218'
 '82K'        | '0.1%'    | '1/8W'   | '0805LF'  | 'EMPTY'  | 'CS38204BA00'(!)        = ''              | ''                 | 'CS38204BA00'           | 'R0805_H26'         | '(SMR0805AW)'                  | '82K'     | '0.1%'  | '1/8W'   | 'IO'       | 'RES CHIP 82K 1/8W +-0.1%(0805)EF'                 | 'CHIPR0805'    | ''          | ''            | '20230218'
 '11.5K'      | '0.1%'    | '1/16W'  | '0402LF'  | 'CHIP'   | 'CS31152BB05'(!)        = ''              | ''                 | 'CS31152BB05'           | 'R0402'             | '(R0402-0201)'                 | '11.5K'   | '0.1%'  | '1/16W'  | 'DISCRETE' | 'RES CHIP 11.5K 1/16W +-0.1%(0402)EF'              | 'CHIPR0402'    | ''          | ''            | '20230218'
 '11.5K'      | '0.1%'    | '1/16W'  | '0402LF'  | 'EMPTY'  | 'CS31152BB05'(!)        = ''              | ''                 | 'CS31152BB05'           | 'R0402'             | '(R0402-0201)'                 | '11.5K'   | '0.1%'  | '1/16W'  | 'IO'       | 'RES CHIP 11.5K 1/16W +-0.1%(0402)EF'              | 'CHIPR0402'    | ''          | ''            | '20230218'
 '5.49K'      | '0.1%'    | '1/16W'  | '0402LF'  | 'CHIP'   | 'CS25492BB00'(!)        = ''              | ''                 | 'CS25492BB00'           | 'R0402'             | '(R0402-0201)'                 | '5.49K'   | '0.1%'  | '1/16W'  | 'DISCRETE' | 'RES CHIP 5.49K 1/16W +-0.1%(0402)EF'              | 'CHIPR0402'    | ''          | ''            | '20230218'
 '5.49K'      | '0.1%'    | '1/16W'  | '0402LF'  | 'EMPTY'  | 'CS25492BB00'(!)        = ''              | ''                 | 'CS25492BB00'           | 'R0402'             | '(R0402-0201)'                 | '5.49K'   | '0.1%'  | '1/16W'  | 'IO'       | 'RES CHIP 5.49K 1/16W +-0.1%(0402)EF'              | 'CHIPR0402'    | ''          | ''            | '20230218'
 '120K'       | '0.1%'    | '1/16W'  | '0402LF'  | 'CHIP'   | 'CS41202BB01'(!)        = ''              | ''                 | 'CS41202BB01'           | 'R0402'             | '(R0402-0201)'                 | '120K'    | '0.1%'  | '1/16W'  | 'DISCRETE' | 'RES CHIP 120K 1/16W +-0.1%(0402)EF'               | 'CHIPR0402'    | ''          | ''            | '20230218'
 '120K'       | '0.1%'    | '1/16W'  | '0402LF'  | 'EMPTY'  | 'CS41202BB01'(!)        = ''              | ''                 | 'CS41202BB01'           | 'R0402'             | '(R0402-0201)'                 | '120K'    | '0.1%'  | '1/16W'  | 'IO'       | 'RES CHIP 120K 1/16W +-0.1%(0402)EF'               | 'CHIPR0402'    | ''          | ''            | '20230218'
 '10.5K'      | '0.1%'    | '1/16W'  | '0402LF'  | 'CHIP'   | 'CS31052BB05'(!)        = ''              | ''                 | 'CS31052BB05'           | 'R0402'             | '(R0402-0201)'                 | '10.5K'   | '0.1%'  | '1/16W'  | 'DISCRETE' | 'RES CHIP 10.5K 1/16W +-0.1%(0402)EF'              | 'CHIPR0402'    | ''          | ''            | '20230218'
 '10.5K'      | '0.1%'    | '1/16W'  | '0402LF'  | 'EMPTY'  | 'CS31052BB05'(!)        = ''              | ''                 | 'CS31052BB05'           | 'R0402'             | '(R0402-0201)'                 | '10.5K'   | '0.1%'  | '1/16W'  | 'IO'       | 'RES CHIP 10.5K 1/16W +-0.1%(0402)EF'              | 'CHIPR0402'    | ''          | ''            | '20230218'
 '324K'       | '1%'      | '1/16W'  | '0402LF'  | 'CHIP'   | 'CS43242FB11'(!)        = 'End of Design' | 'Comp-Release Qty' | 'CS43242FB11'           | 'R0402'             | '(R0402-0201)'                 | '324K'    | '1%'    | '1/16W'  | 'DISCRETE' | 'RES CHIP 324K 1/16W +-1% (0402)'                  | 'CHIPR0402'    | ''          | ''            | '20230307'
 '324K'       | '1%'      | '1/16W'  | '0402LF'  | 'EMPTY'  | 'CS43242FB11'(!)        = 'End of Design' | 'Comp-Release Qty' | 'CS43242FB11'           | 'R0402'             | '(R0402-0201)'                 | '324K'    | '1%'    | '1/16W'  | 'IO'       | 'RES CHIP 324K 1/16W +-1% (0402)'                  | 'CHIPR0402'    | ''          | ''            | '20230307'
 '49.9'       | '1%'      | '1/20W'  | '0201LF'  | 'CHIP'   | 'CS04991FE06'(!)        = 'End of Design' | 'Comp-Approve'     | 'CS04991FE06'           | 'R0201'             | '(SMR0201AW)'                  | '49.9'    | '1%'    | '1/20W'  | 'DISCRETE' | 'RES CHIP 49.9 1/20W +-1%(0201)EF'                 | 'CHIPR0201'    | ''          | ''            | '20230307'
 '49.9'       | '1%'      | '1/20W'  | '0201LF'  | 'EMPTY'  | 'CS04991FE06'(!)        = 'End of Design' | 'Comp-Approve'     | 'CS04991FE06'           | 'R0201'             | '(SMR0201AW)'                  | '49.9'    | '1%'    | '1/20W'  | 'IO'       | 'RES CHIP 49.9 1/20W +-1%(0201)EF'                 | 'CHIPR0201'    | ''          | ''            | '20230307'
 '4.64K'      | '1%'      | '1/16W'  | '0402LF'  | 'CHIP'   | 'CS24642FB14'(!)        = 'End of Design' | 'Comp-Approve'     | 'CS24642FB14'           | 'R0402'             | '(R0402-0201)'                 | '4.64K'   | '1%'    | '1/16W'  | 'DISCRETE' | 'RES CHIP 4.64K 1/16W +-1% (0402)'                 | 'CHIPR0402'    | ''          | ''            | '20230316'
 '4.64K'      | '1%'      | '1/16W'  | '0402LF'  | 'EMPTY'  | 'CS24642FB14'(!)        = 'End of Design' | 'Comp-Approve'     | 'CS24642FB14'           | 'R0402'             | '(R0402-0201)'                 | '4.64K'   | '1%'    | '1/16W'  | 'IO'       | 'RES CHIP 4.64K 1/16W +-1% (0402)'                 | 'CHIPR0402'    | ''          | ''            | '20230316'
 '16.9'       | '1%'      | '1/16W'  | '0402LF'  | 'CHIP'   | 'CS01692FB07'(!)        = 'End of Design' | 'Comp-Approve'     | 'CS01692FB07'           | 'R0402'             | '(R0402-0201)'                 | '16.9'    | '1%'    | '1/16W'  | 'DISCRETE' | 'RES CHIP 16.9 1/16W +-1%(0402)'                   | 'CHIPR0402'    | ''          | ''            | '20230330'
 '16.9'       | '1%'      | '1/16W'  | '0402LF'  | 'EMPTY'  | 'CS01692FB07'(!)        = 'End of Design' | 'Comp-Approve'     | 'CS01692FB07'           | 'R0402'             | '(R0402-0201)'                 | '16.9'    | '1%'    | '1/16W'  | 'IO'       | 'RES CHIP 16.9 1/16W +-1%(0402)'                   | 'CHIPR0402'    | ''          | ''            | '20230330'
 '402K'       | '1%'      | '1/8W'   | '0805LF'  | 'CHIP'   | 'CS44024FA00'(!)        = ''              | ''                 | 'CS44024FA00'           | 'R0805'             | '(SMR0805AW)'                  | '402K'    | '1%'    | '1/8W'   | 'DISCRETE' | 'RES CHIP 402K 1/8W +-1%(0805)EF'                  | 'CHIPR0805'    | ''          | ''            | '20230426'
 '402K'       | '1%'      | '1/8W'   | '0805LF'  | 'EMPTY'  | 'CS44024FA00'(!)        = ''              | ''                 | 'CS44024FA00'           | 'R0805'             | '(SMR0805AW)'                  | '402K'    | '1%'    | '1/8W'   | 'IO'       | 'RES CHIP 402K 1/8W +-1%(0805)EF'                  | 'CHIPR0805'    | ''          | ''            | '20230426'
 '422K'       | '1%'      | '1/8W'   | '0805LF'  | 'CHIP'   | 'CS44224FA00'(!)        = ''              | ''                 | 'CS44224FA00'           | 'R0805'             | '(SMR0805AW)'                  | '422K'    | '1%'    | '1/8W'   | 'DISCRETE' | 'RES CHIP 422K 1/8W +-1%(0805)EF'                  | 'CHIPR0805'    | ''          | ''            | '20230426'
 '422K'       | '1%'      | '1/8W'   | '0805LF'  | 'EMPTY'  | 'CS44224FA00'(!)        = ''              | ''                 | 'CS44224FA00'           | 'R0805'             | '(SMR0805AW)'                  | '422K'    | '1%'    | '1/8W'   | 'IO'       | 'RES CHIP 422K 1/8W +-1%(0805)EF'                  | 'CHIPR0805'    | ''          | ''            | '20230426'
 '0'          | '1%'      | '1/8W'   | '0805LF'  | 'CHIP'   | 'CS00004FA00'(!)        = 'End of Design' | 'Comp-Approve'     | 'CS00004FA00'           | 'R0805'             | '(SMR0805AW)'                  | '0'       | '1%'    | '1/8W'   | 'DISCRETE' | 'RES CHIP 0 1/8W +-1% ( 0805 )'                    | 'CHIPR0805 '   | ''          | ''            | '20230509'
 '0'          | '1%'      | '1/8W'   | '0805LF'  | 'EMPTY'  | 'CS00004FA00'(!)        = 'End of Design' | 'Comp-Approve'     | 'CS00004FA00'           | 'R0805'             | '(SMR0805AW)'                  | '0'       | '1%'    | '1/8W'   | 'IO'       | 'RES CHIP 0 1/8W +-1% ( 0805 )'                    | 'CHIPR0805 '   | ''          | ''            | '20230509'
 '29.4K'      | '1%'      | '1/4W'   | '1206LF'  | 'CHIP'   | 'CS32946F200'(!)        = 'End of Design' | 'Comp-Approve'     | 'CS32946F200'           | 'R1206XN'           | '(SMR1206AW)'                  | '29.4K'   | '1%'    | '1/4W'   | 'DISCRETE' | 'RES CHIP 29.4K 1/4W +-1%(1206)'                   | 'CHIPR1206'    | ''          | ''            | '20230518'
 '29.4K'      | '1%'      | '1/4W'   | '1206LF'  | 'EMPTY'  | 'CS32946F200'(!)        = 'End of Design' | 'Comp-Approve'     | 'CS32946F200'           | 'R1206XN'           | '(SMR1206AW)'                  | '29.4K'   | '1%'    | '1/4W'   | 'IO'       | 'RES CHIP 29.4K 1/4W +-1%(1206)'                   | 'CHIPR1206'    | ''          | ''            | '20230518'
 '22'         | '1%'      | '1/20W'  | '0201LF'  | 'CHIP'   | 'CS02201FE11'(!)        = ''              | ''                 | 'CS02201FE11'           | 'R0201'             | '(SMR0201AW)'                  | '22'      | '1%'    | '1/20W'  | 'DISCRETE' | 'RES CHIP 22 1/20W +-1%(0201)EF'                   | 'CHIPR0201'    | ''          | ''            | '20230530'
 '22'         | '1%'      | '1/20W'  | '0201LF'  | 'EMPTY'  | 'CS02201FE11'(!)        = ''              | ''                 | 'CS02201FE11'           | 'R0201'             | '(SMR0201AW)'                  | '22'      | '1%'    | '1/20W'  | 'IO'       | 'RES CHIP 22 1/20W +-1%(0201)EF'                   | 'CHIPR0201'    | ''          | ''            | '20230530'
 '6.2K'       | '5%'      | '4W'     | '2512LF'  | 'CHIP'   | 'CS2620FJR00'(!)        = ''              | ''                 | 'CS2620FJR00'           | 'R2512XAE'          | '(SMR2512AW)'                  | '6.2K'    | '5%'    | '4W'     | 'DISCRETE' | 'RES CHIP 6.2K 4W +-5%(2512)'                      | 'CHIPR2512'    | ''          | ''            | '20230609'
 '6.2K'       | '5%'      | '4W'     | '2512LF'  | 'EMPTY'  | 'CS2620FJR00'(!)        = ''              | ''                 | 'CS2620FJR00'           | 'R2512XAE'          | '(SMR2512AW)'                  | '6.2K'    | '5%'    | '4W'     | 'IO'       | 'RES CHIP 6.2K 4W +-5%(2512)'                      | 'CHIPR2512'    | ''          | ''            | '20230609'
 '4.7K'       | '5%'      | '4W'     | '2512LF'  | 'CHIP'   | 'CS2470FJR00'(!)        = ''              | ''                 | 'CS2470FJR00'           | 'R2512XAE'          | '(SMR2512AW)'                  | '4.7K'    | '5%'    | '4W'     | 'DISCRETE' | 'RES CHIP 4.7K 4W +-5%(2512)'                      | 'CHIPR2512'    | ''          | ''            | '20230609'
 '4.7K'       | '5%'      | '4W'     | '2512LF'  | 'EMPTY'  | 'CS2470FJR00'(!)        = ''              | ''                 | 'CS2470FJR00'           | 'R2512XAE'          | '(SMR2512AW)'                  | '4.7K'    | '5%'    | '4W'     | 'IO'       | 'RES CHIP 4.7K 4W +-5%(2512)'                      | 'CHIPR2512'    | ''          | ''            | '20230609'
 '3.6K'       | '5%'      | '4W'     | '2512LF'  | 'CHIP'   | 'CS2360FJR00'(!)        = ''              | ''                 | 'CS2360FJR00'           | 'R2512XAE'          | '(SMR2512AW)'                  | '3.6K'    | '5%'    | '4W'     | 'DISCRETE' | 'RES CHIP 3.6K 4W +-5%(2512)'                      | 'CHIPR2512'    | ''          | ''            | '20230609'
 '3.6K'       | '5%'      | '4W'     | '2512LF'  | 'EMPTY'  | 'CS2360FJR00'(!)        = ''              | ''                 | 'CS2360FJR00'           | 'R2512XAE'          | '(SMR2512AW)'                  | '3.6K'    | '5%'    | '4W'     | 'IO'       | 'RES CHIP 3.6K 4W +-5%(2512)'                      | 'CHIPR2512'    | ''          | ''            | '20230609'
 '2K'         | '5%'      | '4W'     | '2512LF'  | 'CHIP'   | 'CS2200FJR00'(!)        = ''              | ''                 | 'CS2200FJR00'           | 'R2512XAE'          | '(SMR2512AW)'                  | '2K'      | '5%'    | '4W'     | 'DISCRETE' | 'RES CHIP 2K 4W +-5%(2512)'                        | 'CHIPR2512'    | ''          | ''            | '20230612'
 '2K'         | '5%'      | '4W'     | '2512LF'  | 'EMPTY'  | 'CS2200FJR00'(!)        = ''              | ''                 | 'CS2200FJR00'           | 'R2512XAE'          | '(SMR2512AW)'                  | '2K'      | '5%'    | '4W'     | 'IO'       | 'RES CHIP 2K 4W +-5%(2512)'                        | 'CHIPR2512'    | ''          | ''            | '20230612'
 '1.8K'       | '5%'      | '4W'     | '2512LF'  | 'CHIP'   | 'CS2180FJR00'(!)        = ''              | ''                 | 'CS2180FJR00'           | 'R2512XAE'          | '(SMR2512AW)'                  | '1.8K'    | '5%'    | '4W'     | 'DISCRETE' | 'RES CHIP 1.8K 4W +-5%(2512)'                      | 'CHIPR2512'    | ''          | ''            | '20230612'
 '1.8K'       | '5%'      | '4W'     | '2512LF'  | 'EMPTY'  | 'CS2180FJR00'(!)        = ''              | ''                 | 'CS2180FJR00'           | 'R2512XAE'          | '(SMR2512AW)'                  | '1.8K'    | '5%'    | '4W'     | 'IO'       | 'RES CHIP 1.8K 4W +-5%(2512)'                      | 'CHIPR2512'    | ''          | ''            | '20230612'
 '750'        | '5%'      | '4W'     | '2512LF'  | 'CHIP'   | 'CS1750FJR00'(!)        = ''              | ''                 | 'CS1750FJR00'           | 'R2512XAE'          | '(SMR2512AW)'                  | '750'     | '5%'    | '4W'     | 'DISCRETE' | 'RES CHIP 750 4W +-5%(2512)'                       | 'CHIPR2512'    | ''          | ''            | '20230612'
 '750'        | '5%'      | '4W'     | '2512LF'  | 'EMPTY'  | 'CS1750FJR00'(!)        = ''              | ''                 | 'CS1750FJR00'           | 'R2512XAE'          | '(SMR2512AW)'                  | '750'     | '5%'    | '4W'     | 'IO'       | 'RES CHIP 750 4W +-5%(2512)'                       | 'CHIPR2512'    | ''          | ''            | '20230612'
 '560'        | '5%'      | '4W'     | '2512LF'  | 'CHIP'   | 'CS1560FJR00'(!)        = ''              | ''                 | 'CS1560FJR00'           | 'R2512XAE'          | '(SMR2512AW)'                  | '560'     | '5%'    | '4W'     | 'DISCRETE' | 'RES CHIP 560 4W +-5%(2512)'                       | 'CHIPR2512'    | ''          | ''            | '20230612'
 '560'        | '5%'      | '4W'     | '2512LF'  | 'EMPTY'  | 'CS1560FJR00'(!)        = ''              | ''                 | 'CS1560FJR00'           | 'R2512XAE'          | '(SMR2512AW)'                  | '560'     | '5%'    | '4W'     | 'IO'       | 'RES CHIP 560 4W +-5%(2512)'                       | 'CHIPR2512'    | ''          | ''            | '20230612'
 '620'        | '5%'      | '4W'     | '2512LF'  | 'CHIP'   | 'CS1620FJR00'(!)        = ''              | ''                 | 'CS1620FJR00'           | 'R2512XAE'          | '(SMR2512AW)'                  | '620'     | '5%'    | '4W'     | 'DISCRETE' | 'RES CHIP 620 4W +-5%(2512)'                       | 'CHIPR2512'    | ''          | ''            | '20230612'
 '620'        | '5%'      | '4W'     | '2512LF'  | 'EMPTY'  | 'CS1620FJR00'(!)        = ''              | ''                 | 'CS1620FJR00'           | 'R2512XAE'          | '(SMR2512AW)'                  | '620'     | '5%'    | '4W'     | 'IO'       | 'RES CHIP 620 4W +-5%(2512)'                       | 'CHIPR2512'    | ''          | ''            | '20230612'
 '1.2K'       | '5%'      | '4W'     | '2512LF'  | 'CHIP'   | 'CS2120FJR00'(!)        = ''              | ''                 | 'CS2120FJR00'           | 'R2512XAE'          | '(SMR2512AW)'                  | '1.2K'    | '5%'    | '4W'     | 'DISCRETE' | 'RES CHIP 1.2K 4W +-5%(2512)'                      | 'CHIPR2512'    | ''          | ''            | '20230612'
 '1.2K'       | '5%'      | '4W'     | '2512LF'  | 'EMPTY'  | 'CS2120FJR00'(!)        = ''              | ''                 | 'CS2120FJR00'           | 'R2512XAE'          | '(SMR2512AW)'                  | '1.2K'    | '5%'    | '4W'     | 'IO'       | 'RES CHIP 1.2K 4W +-5%(2512)'                      | 'CHIPR2512'    | ''          | ''            | '20230612'
 '1.3K'       | '5%'      | '4W'     | '2512LF'  | 'CHIP'   | 'CS2130FJR00'(!)        = ''              | ''                 | 'CS2130FJR00'           | 'R2512XAE'          | '(SMR2512AW)'                  | '1.3K'    | '5%'    | '4W'     | 'DISCRETE' | 'RES CHIP 1.3K 4W +-5%(2512)'                      | 'CHIPR2512'    | ''          | ''            | '20230612'
 '1.3K'       | '5%'      | '4W'     | '2512LF'  | 'EMPTY'  | 'CS2130FJR00'(!)        = ''              | ''                 | 'CS2130FJR00'           | 'R2512XAE'          | '(SMR2512AW)'                  | '1.3K'    | '5%'    | '4W'     | 'IO'       | 'RES CHIP 1.3K 4W +-5%(2512)'                      | 'CHIPR2512'    | ''          | ''            | '20230612'
 '1.5K'       | '5%'      | '4W'     | '2512LF'  | 'CHIP'   | 'CS2150FJR00'(!)        = ''              | ''                 | 'CS2150FJR00'           | 'R2512XAE'          | '(SMR2512AW)'                  | '1.5K'    | '5%'    | '4W'     | 'DISCRETE' | 'RES CHIP 1.5K 4W +-5%(2512)'                      | 'CHIPR2512'    | ''          | ''            | '20230612'
 '1.5K'       | '5%'      | '4W'     | '2512LF'  | 'EMPTY'  | 'CS2150FJR00'(!)        = ''              | ''                 | 'CS2150FJR00'           | 'R2512XAE'          | '(SMR2512AW)'                  | '1.5K'    | '5%'    | '4W'     | 'IO'       | 'RES CHIP 1.5K 4W +-5%(2512)'                      | 'CHIPR2512'    | ''          | ''            | '20230612'
 '680'        | '5%'      | '4W'     | '2512LF'  | 'CHIP'   | 'CS1680FJR00'(!)        = ''              | ''                 | 'CS1680FJR00'           | 'R2512XAE'          | '(SMR2512AW)'                  | '680'     | '5%'    | '4W'     | 'DISCRETE' | 'RES CHIP 680 4W +-5%(2512)'                       | 'CHIPR2512'    | ''          | ''            | '20230614'
 '680'        | '5%'      | '4W'     | '2512LF'  | 'EMPTY'  | 'CS1680FJR00'(!)        = ''              | ''                 | 'CS1680FJR00'           | 'R2512XAE'          | '(SMR2512AW)'                  | '680'     | '5%'    | '4W'     | 'IO'       | 'RES CHIP 680 4W +-5%(2512)'                       | 'CHIPR2512'    | ''          | ''            | '20230614'
 '10'         | '1%'      | '1W'     | '2512LF'  | 'CHIP'   | 'CS01008FR02'(!)        = ''              | ''                 | 'CS01008FR02'           | 'R2512XAA'          | '(SMR2512AW)'                  | '10'      | '1%'    | '1W'     | 'DISCRETE' | 'RES CHIP 10 1W +-1%(2512)EF'                      | 'CHIPR2512'    | ''          | ''            | '20230728'
 '10'         | '1%'      | '1W'     | '2512LF'  | 'EMPTY'  | 'CS01008FR02'(!)        = ''              | ''                 | 'CS01008FR02'           | 'R2512XAA'          | '(SMR2512AW)'                  | '10'      | '1%'    | '1W'     | 'IO'       | 'RES CHIP 10 1W +-1%(2512)EF'                      | 'CHIPR2512'    | ''          | ''            | '20230728'
 '10'         | '1%'      | '2W'     | '2512LF'  | 'CHIP'   | 'CS0100AFR02'(!)        = ''              | ''                 | 'CS0100AFR02'           | 'R2512XAE'          | '(SMR2512AW)'                  | '10'      | '1%'    | '2W'     | 'DISCRETE' | 'RES CHIP 10 2W +-1%(2512)EF'                      | 'CHIPR2512'    | ''          | ''            | '20230728'
 '10'         | '1%'      | '2W'     | '2512LF'  | 'EMPTY'  | 'CS0100AFR02'(!)        = ''              | ''                 | 'CS0100AFR02'           | 'R2512XAE'          | '(SMR2512AW)'                  | '10'      | '1%'    | '2W'     | 'IO'       | 'RES CHIP 10 2W +-1%(2512)EF'                      | 'CHIPR2512'    | ''          | ''            | '20230728'
 '0.25'       | '1%'      | '1/2W'   | '1206LF'  | 'CHIP'   | 'CS+2507F202'(!)        = ''              | ''                 | 'CS+2507F202'           | 'R1206XU'           | '(SMR1206AW)'                  | '0.25'    | '1%'    | '1/2W'   | 'DISCRETE' | 'RES CHIP 0.25 1/2W +-1%(1206)EF'                  | 'CHIPR1206'    | ''          | ''            | '20230728'
 '0.25'       | '1%'      | '1/2W'   | '1206LF'  | 'EMPTY'  | 'CS+2507F202'(!)        = ''              | ''                 | 'CS+2507F202'           | 'R1206XU'           | '(SMR1206AW)'                  | '0.25'    | '1%'    | '1/2W'   | 'IO'       | 'RES CHIP 0.25 1/2W +-1%(1206)EF'                  | 'CHIPR1206'    | ''          | ''            | '20230728'
 '0.25'       | '1%'      | '1/8W'   | '0805LF'  | 'CHIP'   | 'CS+2504FA00'(!)        = ''              | ''                 | 'CS+2504FA00'           | 'R0805'             | '(SMR0805AW)'                  | '0.25'    | '1%'    | '1/8W'   | 'DISCRETE' | 'RES CHIP 0.25 1/8W +-1%(0805)EF'                  | 'CHIPR0805'    | ''          | ''            | '20230728'
 '0.25'       | '1%'      | '1/8W'   | '0805LF'  | 'EMPTY'  | 'CS+2504FA00'(!)        = ''              | ''                 | 'CS+2504FA00'           | 'R0805'             | '(SMR0805AW)'                  | '0.25'    | '1%'    | '1/8W'   | 'IO'       | 'RES CHIP 0.25 1/8W +-1%(0805)EF'                  | 'CHIPR0805'    | ''          | ''            | '20230728'
 '0.25'       | '1%'      | '1/4W'   | '0805LF'  | 'CHIP'   | 'CS+2506FA01'(!)        = ''              | ''                 | 'CS+2506FA01'           | 'R0805'             | '(SMR0805AW)'                  | '0.25'    | '1%'    | '1/4W'   | 'DISCRETE' | 'RES CHIP 0.25 1/4W +-1%(0805)EF'                  | 'CHIPR0805'    | ''          | ''            | '20230728'
 '0.25'       | '1%'      | '1/4W'   | '0805LF'  | 'EMPTY'  | 'CS+2506FA01'(!)        = ''              | ''                 | 'CS+2506FA01'           | 'R0805'             | '(SMR0805AW)'                  | '0.25'    | '1%'    | '1/4W'   | 'IO'       | 'RES CHIP 0.25 1/4W +-1%(0805)EF'                  | 'CHIPR0805'    | ''          | ''            | '20230728'
 '84.5'       | '1%'      | '1/10W'  | '0603LF'  | 'CHIP'   | 'CS08453F900'(!)        = ''              | ''                 | 'CS08453F900'           | 'R0603_W0-95'       | '(SMR0603AW)'                  | '84.5'    | '1%'    | '1/10W'  | 'DISCRETE' | 'RES CHIP 84.5 1/10W +-1%(0603)EF'                 | 'CHIPR0603'    | ''          | ''            | '20230728'
 '84.5'       | '1%'      | '1/10W'  | '0603LF'  | 'EMPTY'  | 'CS08453F900'(!)        = ''              | ''                 | 'CS08453F900'           | 'R0603_W0-95'       | '(SMR0603AW)'                  | '84.5'    | '1%'    | '1/10W'  | 'IO'       | 'RES CHIP 84.5 1/10W +-1%(0603)EF'                 | 'CHIPR0603'    | ''          | ''            | '20230728'
 '5.1'        | '1%'      | '1/10W'  | '0603LF'  | 'CHIP'   | 'CS-5103F904'(!)        = ''              | ''                 | 'CS-5103F904'           | 'R0603_W0-95'       | '(SMR0603AW)'                  | '5.1'     | '1%'    | '1/10W'  | 'DISCRETE' | 'RES CHIP 5.1 1/10W +-1%(0603)EF'                  | 'CHIPR0603'    | ''          | ''            | '20230728'
 '5.1'        | '1%'      | '1/10W'  | '0603LF'  | 'EMPTY'  | 'CS-5103F904'(!)        = ''              | ''                 | 'CS-5103F904'           | 'R0603_W0-95'       | '(SMR0603AW)'                  | '5.1'     | '1%'    | '1/10W'  | 'IO'       | 'RES CHIP 5.1 1/10W +-1%(0603)EF'                  | 'CHIPR0603'    | ''          | ''            | '20230728'
 '124'        | '1%'      | '1/10W'  | '0603LF'  | 'CHIP'   | 'CS11243F900'(!)        = ''              | ''                 | 'CS11243F900'           | 'R0603_W0-95'       | '(SMR0603AW)'                  | '124'     | '1%'    | '1/10W'  | 'DISCRETE' | 'RES CHIP 124 1/10W +-1%(0603)EF'                  | 'CHIPR0603'    | ''          | ''            | '20230731'
 '124'        | '1%'      | '1/10W'  | '0603LF'  | 'EMPTY'  | 'CS11243F900'(!)        = ''              | ''                 | 'CS11243F900'           | 'R0603_W0-95'       | '(SMR0603AW)'                  | '124'     | '1%'    | '1/10W'  | 'IO'       | 'RES CHIP 124 1/10W +-1%(0603)EF'                  | 'CHIPR0603'    | ''          | ''            | '20230731'
 '768'        | '1%'      | '1/16W'  | '0402LF'  | 'CHIP'   | 'CS17682FB00'(!)        = 'End of Design' | 'Comp-Approve'     | 'CS17682FB00'           | 'R0402'             | '(R0402-0201)'                 | '768'     | '1%'    | '1/16W'  | 'DISCRETE' | 'RES CHIP 768 1/16W +-1%(0402)'                    | 'CHIPR0402'    | ''          | ''            | '20230821'
 '768'        | '1%'      | '1/16W'  | '0402LF'  | 'EMPTY'  | 'CS17682FB00'(!)        = 'End of Design' | 'Comp-Approve'     | 'CS17682FB00'           | 'R0402'             | '(R0402-0201)'                 | '768'     | '1%'    | '1/16W'  | 'IO'       | 'RES CHIP 768 1/16W +-1%(0402)'                    | 'CHIPR0402'    | ''          | ''            | '20230821'
 '0.03'       | '1%'      | '1/2W'   | '1206LF'  | 'CHIP'   | 'CS+0307F202'(!)        = ''              | ''                 | 'CS+0307F202'           | 'R1206'             | '(SMR1206AW)'                  | '0.03'    | '1%'    | '1/2W'   | 'DISCRETE' | 'RES CHIP 0.03 1/2W +-1%(1206)RLC'                 | 'CHIPR1206'    | ''          | ''            | '20191030'
 '0.03'       | '1%'      | '1/2W'   | '1206LF'  | 'EMPTY'  | 'CS+0307F202'(!)        = ''              | ''                 | 'CS+0307F202'           | 'R1206'             | '(SMR1206AW)'                  | '0.03'    | '1%'    | '1/2W'   | 'IO'       | 'RES CHIP 0.03 1/2W +-1%(1206)RLC'                 | 'CHIPR1206'    | ''          | ''            | '20191030'
 '0.03'       | '1%'      | '1/2W'   | '1206LF'  | 'CHIP'   | 'CS+0307F202SEL1'(!)    = ''              | ''                 | 'CS+0307F202SEL1'       | 'R1206'             | '(SMR1206AW)'                  | '0.03'    | '1%'    | '1/2W'   | 'DISCRETE' | 'RES CHIP 0.03 1/2W +-1%(1206)RLCSELA'             | 'CHIPR1206'    | ''          | ''            | '20191030'
 '0.03'       | '1%'      | '1/2W'   | '1206LF'  | 'EMPTY'  | 'CS+0307F202SEL1'(!)    = ''              | ''                 | 'CS+0307F202SEL1'       | 'R1206'             | '(SMR1206AW)'                  | '0.03'    | '1%'    | '1/2W'   | 'IO'       | 'RES CHIP 0.03 1/2W +-1%(1206)RLCSELA'             | 'CHIPR1206'    | ''          | ''            | '20191030'
 '0.03'       | '1%'      | '1/2W'   | '0805LF'  | 'CHIP'   | 'CS+0307FA03'(!)        = ''              | ''                 | 'CS+0307FA03'           | 'R0805_H26'         | '(SMR0805AW)'                  | '0.03'    | '1%'    | '1/2W'   | 'DISCRETE' | 'RES CHIP 0.03 1/2W 1%(0805)H0.55 CYN'             | 'CHIPR0805'    | ''          | ''            | '20220818'
 '0.03'       | '1%'      | '1/2W'   | '0805LF'  | 'EMPTY'  | 'CS+0307FA03'(!)        = ''              | ''                 | 'CS+0307FA03'           | 'R0805_H26'         | '(SMR0805AW)'                  | '0.03'    | '1%'    | '1/2W'   | 'IO'       | 'RES CHIP 0.03 1/2W 1%(0805)H0.55 CYN'             | 'CHIPR0805'    | ''          | ''            | '20220818'
 '0.03'       | '1%'      | '1/2W'   | '0805LF'  | 'CHIP'   | 'CS+0307FA03SEL1'(!)    = ''              | ''                 | 'CS+0307FA03SEL1'       | 'R0805_H26'         | '(SMR0805AW)'                  | '0.03'    | '1%'    | '1/2W'   | 'DISCRETE' | 'RES CHIP 0.03 1/2W 1%(0805)H0.55 CYNSELA'         | 'CHIPR0805'    | ''          | ''            | '20220818'
 '0.03'       | '1%'      | '1/2W'   | '0805LF'  | 'EMPTY'  | 'CS+0307FA03SEL1'(!)    = ''              | ''                 | 'CS+0307FA03SEL1'       | 'R0805_H26'         | '(SMR0805AW)'                  | '0.03'    | '1%'    | '1/2W'   | 'IO'       | 'RES CHIP 0.03 1/2W 1%(0805)H0.55 CYNSELA'         | 'CHIPR0805'    | ''          | ''            | '20220818'
 '0.22'       | '1%'      | '1/2W'   | '1206LF'  | 'CHIP'   | 'CS+2207F201'(!)        = ''              | ''                 | 'CS+2207F201'           | 'R1206XJ'           | '(SMR1206AW)'                  | '0.22'    | '1%'    | '1/2W'   | 'DISCRETE' | 'RES CHIP 0.22 1/2W +-1%(1206)TAI'                 | 'CHIPR1206'    | ''          | ''            | '20200304'
 '0.22'       | '1%'      | '1/2W'   | '1206LF'  | 'EMPTY'  | 'CS+2207F201'(!)        = ''              | ''                 | 'CS+2207F201'           | 'R1206XJ'           | '(SMR1206AW)'                  | '0.22'    | '1%'    | '1/2W'   | 'IO'       | 'RES CHIP 0.22 1/2W +-1%(1206)TAI'                 | 'CHIPR1206'    | ''          | ''            | '20200304'
 '0.22'       | '1%'      | '1/2W'   | '1206LF'  | 'CHIP'   | 'CS+2207F201SEL1'(!)    = ''              | ''                 | 'CS+2207F201SEL1'       | 'R1206XJ'           | '(SMR1206AW)'                  | '0.22'    | '1%'    | '1/2W'   | 'DISCRETE' | 'RES CHIP 0.22 1/2W +-1%(1206)TAISELA'             | 'CHIPR1206'    | ''          | ''            | '20200304'
 '0.22'       | '1%'      | '1/2W'   | '1206LF'  | 'EMPTY'  | 'CS+2207F201SEL1'(!)    = ''              | ''                 | 'CS+2207F201SEL1'       | 'R1206XJ'           | '(SMR1206AW)'                  | '0.22'    | '1%'    | '1/2W'   | 'IO'       | 'RES CHIP 0.22 1/2W +-1%(1206)TAISELA'             | 'CHIPR1206'    | ''          | ''            | '20200304'
 '0'          | '5%'      | '1/20W'  | '0201LF'  | 'CHIP'   | 'CS00001JE25'(!)        = ''              | ''                 | 'CS00001JE25'           | 'R0201'             | '(SMR0201AW)'                  | '0'       | '5%'    | '1/20W'  | 'DISCRETE' | 'RES CHIP 0 1/20W +-5%(0201)YGO'                   | 'CHIP0201'     | ''          | ''            | '20151228'
 '0'          | '5%'      | '1/20W'  | '0201LF'  | 'EMPTY'  | 'CS00001JE25'(!)        = ''              | ''                 | 'CS00001JE25'           | 'R0201'             | '(SMR0201AW)'                  | '0'       | '5%'    | '1/20W'  | 'IO'       | 'RES CHIP 0 1/20W +-5%(0201)YGO'                   | 'CHIP0201'     | ''          | ''            | '20151228'
 '0'          | '5%'      | '1/20W'  | '0201LF'  | 'CHIP'   | 'CS00001JE25SEL1'(!)    = ''              | ''                 | 'CS00001JE25SEL1'       | 'R0201'             | '(SMR0201AW)'                  | '0'       | '5%'    | '1/20W'  | 'DISCRETE' | 'RES CHIP 0 1/20W +-5%(0201)YGOSELA'               | 'CHIP0201'     | ''          | ''            | '20151228'
 '0'          | '5%'      | '1/20W'  | '0201LF'  | 'EMPTY'  | 'CS00001JE25SEL1'(!)    = ''              | ''                 | 'CS00001JE25SEL1'       | 'R0201'             | '(SMR0201AW)'                  | '0'       | '5%'    | '1/20W'  | 'IO'       | 'RES CHIP 0 1/20W +-5%(0201)YGOSELA'               | 'CHIP0201'     | ''          | ''            | '20151228'
 '0'          | '1%'      | '1/16W'  | '0402LF'  | 'CHIP'   | 'CS00002FB05'(!)        = ''              | ''                 | 'CS00002FB05'           | 'R0402'             | '(R0402-0201)'                 | '0'       | '1%'    | '1/16W'  | 'DISCRETE' | 'RES CHIP 0 1/16W +-1%(0402)YGO'                   | 'CHIP0402'     | ''          | ''            | '20230825'
 '0'          | '1%'      | '1/16W'  | '0402LF'  | 'EMPTY'  | 'CS00002FB05'(!)        = ''              | ''                 | 'CS00002FB05'           | 'R0402'             | '(R0402-0201)'                 | '0'       | '1%'    | '1/16W'  | 'IO'       | 'RES CHIP 0 1/16W +-1%(0402)YGO'                   | 'CHIP0402'     | ''          | ''            | '20230825'
 '0'          | '1%'      | '1/16W'  | '0402LF'  | 'CHIP'   | 'CS00002FB05SEL1'(!)    = ''              | ''                 | 'CS00002FB05SEL1'       | 'R0402'             | '(R0402-0201)'                 | '0'       | '1%'    | '1/16W'  | 'DISCRETE' | 'RES CHIP 0 1/16W +-1%(0402)YGOSELA'               | 'CHIP0402'     | ''          | ''            | '20230825'
 '0'          | '1%'      | '1/16W'  | '0402LF'  | 'EMPTY'  | 'CS00002FB05SEL1'(!)    = ''              | ''                 | 'CS00002FB05SEL1'       | 'R0402'             | '(R0402-0201)'                 | '0'       | '1%'    | '1/16W'  | 'IO'       | 'RES CHIP 0 1/16W +-1%(0402)YGOSELA'               | 'CHIP0402'     | ''          | ''            | '20230825'
 '0'          | ''        | '1/16W'  | '0402LF'  | 'CHIP'   | 'CS00002TB14'(!)        = ''              | ''                 | 'CS00002TB14'           | 'R0402'             | '(R0402-0201)'                 | '0'       | ''      | '1/16W'  | 'DISCRETE' | 'RES CHIP 0 1/16W JUMPER(0402)EF WTC'              | 'CHIPR0402'    | ''          | ''            | '20180208'
 '0'          | ''        | '1/16W'  | '0402LF'  | 'EMPTY'  | 'CS00002TB14'(!)        = ''              | ''                 | 'CS00002TB14'           | 'R0402'             | '(R0402-0201)'                 | '0'       | ''      | '1/16W'  | 'IO'       | 'RES CHIP 0 1/16W JUMPER(0402)EF WTC'              | 'CHIPR0402'    | ''          | ''            | '20180208'
 '0'          | ''        | '1/16W'  | '0402LF'  | 'CHIP'   | 'CS00002TB14SEL1'(!)    = ''              | ''                 | 'CS00002TB14SEL1'       | 'R0402'             | '(R0402-0201)'                 | '0'       | ''      | '1/16W'  | 'DISCRETE' | 'RES CHIP 0 1/16W JUMPER(0402)EF WTCSELA'          | 'CHIPR0402'    | ''          | ''            | '20180208'
 '0'          | ''        | '1/16W'  | '0402LF'  | 'EMPTY'  | 'CS00002TB14SEL1'(!)    = ''              | ''                 | 'CS00002TB14SEL1'       | 'R0402'             | '(R0402-0201)'                 | '0'       | ''      | '1/16W'  | 'IO'       | 'RES CHIP 0 1/16W JUMPER(0402)EF WTCSELA'          | 'CHIPR0402'    | ''          | ''            | '20180208'
 '0'          | ''        | '1/16W'  | '0402LF'  | 'CHIP'   | 'CS00002TB08'(!)        = ''              | ''                 | 'CS00002TB08'           | 'R0402'             | '(R0402-0201)'                 | '0'       | ''      | '1/16W'  | 'DISCRETE' | 'RES CHIP 0 1/16W (0402)CYN'                       | 'CHIP0402'     | ''          | ''            | '20100618'
 '0'          | ''        | '1/16W'  | '0402LF'  | 'EMPTY'  | 'CS00002TB08'(!)        = ''              | ''                 | 'CS00002TB08'           | 'R0402'             | '(R0402-0201)'                 | '0'       | ''      | '1/16W'  | 'IO'       | 'RES CHIP 0 1/16W (0402)CYN'                       | 'CHIP0402'     | ''          | ''            | '20100618'
 '0'          | ''        | '1/16W'  | '0402LF'  | 'CHIP'   | 'CS00002TB08SEL1'(!)    = ''              | ''                 | 'CS00002TB08SEL1'       | 'R0402'             | '(R0402-0201)'                 | '0'       | ''      | '1/16W'  | 'DISCRETE' | 'RES CHIP 0 1/16W (0402)CYNSELA'                   | 'CHIP0402'     | ''          | ''            | '20100618'
 '0'          | ''        | '1/16W'  | '0402LF'  | 'EMPTY'  | 'CS00002TB08SEL1'(!)    = ''              | ''                 | 'CS00002TB08SEL1'       | 'R0402'             | '(R0402-0201)'                 | '0'       | ''      | '1/16W'  | 'IO'       | 'RES CHIP 0 1/16W (0402)CYNSELA'                   | 'CHIP0402'     | ''          | ''            | '20100618'
 '0'          | ''        | '1/8W'   | '0805LF'  | 'CHIP'   | 'CS00004TA06'(!)        = ''              | ''                 | 'CS00004TA06'           | 'R0805'             | '(SMR0805AW)'                  | '0'       | ''      | '1/8W'   | 'DISCRETE' | 'RES CHIP 0 1/8W(0805)MAT AEC'                     | 'CHIP0805'     | ''          | ''            | '20100713'
 '0'          | ''        | '1/8W'   | '0805LF'  | 'EMPTY'  | 'CS00004TA06'(!)        = ''              | ''                 | 'CS00004TA06'           | 'R0805'             | '(SMR0805AW)'                  | '0'       | ''      | '1/8W'   | 'IO'       | 'RES CHIP 0 1/8W(0805)MAT AEC'                     | 'CHIP0805'     | ''          | ''            | '20100713'
 '0'          | ''        | '1/8W'   | '0805LF'  | 'CHIP'   | 'CS00004TA06SEL1'(!)    = ''              | ''                 | 'CS00004TA06SEL1'       | 'R0805'             | '(SMR0805AW)'                  | '0'       | ''      | '1/8W'   | 'DISCRETE' | 'RES CHIP 0 1/8W(0805)MAT AECSELA'                 | 'CHIP0805'     | ''          | ''            | '20100713'
 '0'          | ''        | '1/8W'   | '0805LF'  | 'EMPTY'  | 'CS00004TA06SEL1'(!)    = ''              | ''                 | 'CS00004TA06SEL1'       | 'R0805'             | '(SMR0805AW)'                  | '0'       | ''      | '1/8W'   | 'IO'       | 'RES CHIP 0 1/8W(0805)MAT AECSELA'                 | 'CHIP0805'     | ''          | ''            | '20100713'
 '10'         | '1%'      | '1/16W'  | '0402LF'  | 'CHIP'   | 'CS01002FB25'(!)        = ''              | ''                 | 'CS01002FB25'           | 'R0402'             | '(R0402-0201)'                 | '10'      | '1%'    | '1/16W'  | 'DISCRETE' | 'RES CHIP 10 1/16W +-1%(0402)TAI'                  | 'CHIP0402'     | ''          | ''            | '20230825'
 '10'         | '1%'      | '1/16W'  | '0402LF'  | 'EMPTY'  | 'CS01002FB25'(!)        = ''              | ''                 | 'CS01002FB25'           | 'R0402'             | '(R0402-0201)'                 | '10'      | '1%'    | '1/16W'  | 'IO'       | 'RES CHIP 10 1/16W +-1%(0402)TAI'                  | 'CHIP0402'     | ''          | ''            | '20230825'
 '10'         | '1%'      | '1/16W'  | '0402LF'  | 'CHIP'   | 'CS01002FB25SEL1'(!)    = ''              | ''                 | 'CS01002FB25SEL1'       | 'R0402'             | '(R0402-0201)'                 | '10'      | '1%'    | '1/16W'  | 'DISCRETE' | 'RES CHIP 10 1/16W +-1%(0402)TAISELA'              | 'CHIP0402'     | ''          | ''            | '20230825'
 '10'         | '1%'      | '1/16W'  | '0402LF'  | 'EMPTY'  | 'CS01002FB25SEL1'(!)    = ''              | ''                 | 'CS01002FB25SEL1'       | 'R0402'             | '(R0402-0201)'                 | '10'      | '1%'    | '1/16W'  | 'IO'       | 'RES CHIP 10 1/16W +-1%(0402)TAISELA'              | 'CHIP0402'     | ''          | ''            | '20230825'
 '10'         | '5%'      | '1/16W'  | '0402LF'  | 'CHIP'   | 'CS01002JB20'(!)        = ''              | ''                 | 'CS01002JB20'           | 'R0402'             | '(R0402-0201)'                 | '10'      | '5%'    | '1/16W'  | 'DISCRETE' | 'RES CHIP 10 1/16W +-5%(0402)CYN'                  | 'CHIP0402'     | ''          | ''            | '20230825'
 '10'         | '5%'      | '1/16W'  | '0402LF'  | 'EMPTY'  | 'CS01002JB20'(!)        = ''              | ''                 | 'CS01002JB20'           | 'R0402'             | '(R0402-0201)'                 | '10'      | '5%'    | '1/16W'  | 'IO'       | 'RES CHIP 10 1/16W +-5%(0402)CYN'                  | 'CHIP0402'     | ''          | ''            | '20230825'
 '10'         | '5%'      | '1/16W'  | '0402LF'  | 'CHIP'   | 'CS01002JB20SEL1'(!)    = ''              | ''                 | 'CS01002JB20SEL1'       | 'R0402'             | '(R0402-0201)'                 | '10'      | '5%'    | '1/16W'  | 'DISCRETE' | 'RES CHIP 10 1/16W +-5%(0402)CYNSELA'              | 'CHIP0402'     | ''          | ''            | '20230825'
 '10'         | '5%'      | '1/16W'  | '0402LF'  | 'EMPTY'  | 'CS01002JB20SEL1'(!)    = ''              | ''                 | 'CS01002JB20SEL1'       | 'R0402'             | '(R0402-0201)'                 | '10'      | '5%'    | '1/16W'  | 'IO'       | 'RES CHIP 10 1/16W +-5%(0402)CYNSELA'              | 'CHIP0402'     | ''          | ''            | '20230825'
 '15'         | '1%'      | '1/16W'  | '0402LF'  | 'CHIP'   | 'CS01502FB08SEL1'(!)    = ''              | ''                 | 'CS01502FB08SEL1'       | 'R0402'             | '(R0402-0201)'                 | '15'      | '1%'    | '1/16W'  | 'DISCRETE' | 'RES CHIP 15 1/16W +-1% (0402)YGOSELA'             | 'CHIP0402'     | ''          | ''            | '20100715'
 '15'         | '1%'      | '1/16W'  | '0402LF'  | 'EMPTY'  | 'CS01502FB08SEL1'(!)    = ''              | ''                 | 'CS01502FB08SEL1'       | 'R0402'             | '(R0402-0201)'                 | '15'      | '1%'    | '1/16W'  | 'IO'       | 'RES CHIP 15 1/16W +-1% (0402)YGOSELA'             | 'CHIP0402'     | ''          | ''            | '20100715'
 '20'         | '1%'      | '1/16W'  | '0402LF'  | 'CHIP'   | 'CS02002FB17'(!)        = ''              | ''                 | 'CS02002FB17'           | 'R0402'             | '(R0402-0201)'                 | '20'      | '1%'    | '1/16W'  | 'DISCRETE' | 'RES CHIP 20 1/16W +-1% (0402)CYN'                 | 'CHIP0402'     | ''          | ''            | '20100601'
 '20'         | '1%'      | '1/16W'  | '0402LF'  | 'EMPTY'  | 'CS02002FB17'(!)        = ''              | ''                 | 'CS02002FB17'           | 'R0402'             | '(R0402-0201)'                 | '20'      | '1%'    | '1/16W'  | 'IO'       | 'RES CHIP 20 1/16W +-1% (0402)CYN'                 | 'CHIP0402'     | ''          | ''            | '20100601'
 '20'         | '1%'      | '1/16W'  | '0402LF'  | 'CHIP'   | 'CS02002FB17SEL1'(!)    = ''              | ''                 | 'CS02002FB17SEL1'       | 'R0402'             | '(R0402-0201)'                 | '20'      | '1%'    | '1/16W'  | 'DISCRETE' | 'RES CHIP 20 1/16W +-1% (0402)CYNSELA'             | 'CHIP0402'     | ''          | ''            | '20100601'
 '20'         | '1%'      | '1/16W'  | '0402LF'  | 'EMPTY'  | 'CS02002FB17SEL1'(!)    = ''              | ''                 | 'CS02002FB17SEL1'       | 'R0402'             | '(R0402-0201)'                 | '20'      | '1%'    | '1/16W'  | 'IO'       | 'RES CHIP 20 1/16W +-1% (0402)CYNSELA'             | 'CHIP0402'     | ''          | ''            | '20100601'
 '20'         | '5%'      | '1/16W'  | '0402LF'  | 'CHIP'   | 'CS02002JB11'(!)        = ''              | ''                 | 'CS02002JB11'           | 'R0402'             | '(R0402-0201)'                 | '20'      | '5%'    | '1/16W'  | 'DISCRETE' | 'RES CHIP 20 1/16W +-5%(0402)WTC'                  | 'CHIP0402'     | ''          | ''            | '20100831'
 '20'         | '5%'      | '1/16W'  | '0402LF'  | 'EMPTY'  | 'CS02002JB11'(!)        = ''              | ''                 | 'CS02002JB11'           | 'R0402'             | '(R0402-0201)'                 | '20'      | '5%'    | '1/16W'  | 'IO'       | 'RES CHIP 20 1/16W +-5%(0402)WTC'                  | 'CHIP0402'     | ''          | ''            | '20100831'
 '20'         | '5%'      | '1/16W'  | '0402LF'  | 'CHIP'   | 'CS02002JB11SEL1'(!)    = ''              | ''                 | 'CS02002JB11SEL1'       | 'R0402'             | '(R0402-0201)'                 | '20'      | '5%'    | '1/16W'  | 'DISCRETE' | 'RES CHIP 20 1/16W +-5%(0402)WTCSELA'              | 'CHIP0402'     | ''          | ''            | '20100831'
 '20'         | '5%'      | '1/16W'  | '0402LF'  | 'EMPTY'  | 'CS02002JB11SEL1'(!)    = ''              | ''                 | 'CS02002JB11SEL1'       | 'R0402'             | '(R0402-0201)'                 | '20'      | '5%'    | '1/16W'  | 'IO'       | 'RES CHIP 20 1/16W +-5%(0402)WTCSELA'              | 'CHIP0402'     | ''          | ''            | '20100831'
 '22'         | '1%'      | '1/20W'  | '0201LF'  | 'CHIP'   | 'CS02201FE13'(!)        = ''              | ''                 | 'CS02201FE13'           | 'R0201'             | '(SMR0201AW)'                  | '22'      | '1%'    | '1/20W'  | 'DISCRETE' | 'RES CHIP 22 1/20W +-1%(0201)YGO'                  | 'CHIPR0201'    | ''          | ''            | '20150324'
 '22'         | '1%'      | '1/20W'  | '0201LF'  | 'EMPTY'  | 'CS02201FE13'(!)        = ''              | ''                 | 'CS02201FE13'           | 'R0201'             | '(SMR0201AW)'                  | '22'      | '1%'    | '1/20W'  | 'IO'       | 'RES CHIP 22 1/20W +-1%(0201)YGO'                  | 'CHIPR0201'    | ''          | ''            | '20150324'
 '22'         | '1%'      | '1/20W'  | '0201LF'  | 'CHIP'   | 'CS02201FE13SEL1'(!)    = ''              | ''                 | 'CS02201FE13SEL1'       | 'R0201'             | '(SMR0201AW)'                  | '22'      | '1%'    | '1/20W'  | 'DISCRETE' | 'RES CHIP 22 1/20W +-1%(0201)YGOSELA'              | 'CHIPR0201'    | ''          | ''            | '20150324'
 '22'         | '1%'      | '1/20W'  | '0201LF'  | 'EMPTY'  | 'CS02201FE13SEL1'(!)    = ''              | ''                 | 'CS02201FE13SEL1'       | 'R0201'             | '(SMR0201AW)'                  | '22'      | '1%'    | '1/20W'  | 'IO'       | 'RES CHIP 22 1/20W +-1%(0201)YGOSELA'              | 'CHIPR0201'    | ''          | ''            | '20150324'
 '22.1'       | '1%'      | '1/16W'  | '0402LF'  | 'CHIP'   | 'CS02212FB14'(!)        = ''              | ''                 | 'CS02212FB14'           | 'R0402'             | '(R0402-0201)'                 | '22.1'    | '1%'    | '1/16W'  | 'DISCRETE' | 'RES CHIP 22.1 1/16W +-1%(0402)WTC'                | 'CHIP0402'     | ''          | ''            | '20100811'
 '22.1'       | '1%'      | '1/16W'  | '0402LF'  | 'EMPTY'  | 'CS02212FB14'(!)        = ''              | ''                 | 'CS02212FB14'           | 'R0402'             | '(R0402-0201)'                 | '22.1'    | '1%'    | '1/16W'  | 'IO'       | 'RES CHIP 22.1 1/16W +-1%(0402)WTC'                | 'CHIP0402'     | ''          | ''            | '20100811'
 '22.1'       | '1%'      | '1/16W'  | '0402LF'  | 'CHIP'   | 'CS02212FB14SEL1'(!)    = ''              | ''                 | 'CS02212FB14SEL1'       | 'R0402'             | '(R0402-0201)'                 | '22.1'    | '1%'    | '1/16W'  | 'DISCRETE' | 'RES CHIP 22.1 1/16W +-1%(0402)WTCSELA'            | 'CHIP0402'     | ''          | ''            | '20100811'
 '22.1'       | '1%'      | '1/16W'  | '0402LF'  | 'EMPTY'  | 'CS02212FB14SEL1'(!)    = ''              | ''                 | 'CS02212FB14SEL1'       | 'R0402'             | '(R0402-0201)'                 | '22.1'    | '1%'    | '1/16W'  | 'IO'       | 'RES CHIP 22.1 1/16W +-1%(0402)WTCSELA'            | 'CHIP0402'     | ''          | ''            | '20100811'
 '24.9'       | '1%'      | '1/20W'  | '0201LF'  | 'CHIP'   | 'CS02491FE09'(!)        = ''              | ''                 | 'CS02491FE09'           | 'R0201'             | '(SMR0201AW)'                  | '24.9'    | '1%'    | '1/20W'  | 'DISCRETE' | 'RES CHIP 24.9 1/20W +-1%(0201)YGO'                | 'CHIPR0201'    | ''          | ''            | '20180806'
 '24.9'       | '1%'      | '1/20W'  | '0201LF'  | 'EMPTY'  | 'CS02491FE09'(!)        = ''              | ''                 | 'CS02491FE09'           | 'R0201'             | '(SMR0201AW)'                  | '24.9'    | '1%'    | '1/20W'  | 'IO'       | 'RES CHIP 24.9 1/20W +-1%(0201)YGO'                | 'CHIPR0201'    | ''          | ''            | '20180806'
 '24.9'       | '1%'      | '1/20W'  | '0201LF'  | 'CHIP'   | 'CS02491FE09SEL1'(!)    = ''              | ''                 | 'CS02491FE09SEL1'       | 'R0201'             | '(SMR0201AW)'                  | '24.9'    | '1%'    | '1/20W'  | 'DISCRETE' | 'RES CHIP 24.9 1/20W +-1%(0201)YGOSELA'            | 'CHIPR0201'    | ''          | ''            | '20180806'
 '24.9'       | '1%'      | '1/20W'  | '0201LF'  | 'EMPTY'  | 'CS02491FE09SEL1'(!)    = ''              | ''                 | 'CS02491FE09SEL1'       | 'R0201'             | '(SMR0201AW)'                  | '24.9'    | '1%'    | '1/20W'  | 'IO'       | 'RES CHIP 24.9 1/20W +-1%(0201)YGOSELA'            | 'CHIPR0201'    | ''          | ''            | '20180806'
 '24.9'       | '1%'      | '1/16W'  | '0402LF'  | 'CHIP'   | 'CS02492FB18'(!)        = ''              | ''                 | 'CS02492FB18'           | 'R0402'             | '(R0402-0201)'                 | '24.9'    | '1%'    | '1/16W'  | 'DISCRETE' | 'RES CHIP 24.9 1/16W +-1%(0402)CYN'                | 'CHIP0402'     | ''          | ''            | '20100930'
 '24.9'       | '1%'      | '1/16W'  | '0402LF'  | 'EMPTY'  | 'CS02492FB18'(!)        = ''              | ''                 | 'CS02492FB18'           | 'R0402'             | '(R0402-0201)'                 | '24.9'    | '1%'    | '1/16W'  | 'IO'       | 'RES CHIP 24.9 1/16W +-1%(0402)CYN'                | 'CHIP0402'     | ''          | ''            | '20100930'
 '24.9'       | '1%'      | '1/16W'  | '0402LF'  | 'CHIP'   | 'CS02492FB18SEL1'(!)    = ''              | ''                 | 'CS02492FB18SEL1'       | 'R0402'             | '(R0402-0201)'                 | '24.9'    | '1%'    | '1/16W'  | 'DISCRETE' | 'RES CHIP 24.9 1/16W +-1%(0402)CYNSELA'            | 'CHIP0402'     | ''          | ''            | '20100930'
 '24.9'       | '1%'      | '1/16W'  | '0402LF'  | 'EMPTY'  | 'CS02492FB18SEL1'(!)    = ''              | ''                 | 'CS02492FB18SEL1'       | 'R0402'             | '(R0402-0201)'                 | '24.9'    | '1%'    | '1/16W'  | 'IO'       | 'RES CHIP 24.9 1/16W +-1%(0402)CYNSELA'            | 'CHIP0402'     | ''          | ''            | '20100930'
 '33'         | '5%'      | '1/20W'  | '0201LF'  | 'CHIP'   | 'CS03301JE05'(!)        = ''              | ''                 | 'CS03301JE05'           | 'R0201'             | '(SMR0201AW)'                  | '33'      | '5%'    | '1/20W'  | 'DISCRETE' | 'RES CHIP 33 1/20W +-5%(0201)WTC'                  | 'CHIPR0201'    | ''          | ''            | '20180803'
 '33'         | '5%'      | '1/20W'  | '0201LF'  | 'EMPTY'  | 'CS03301JE05'(!)        = ''              | ''                 | 'CS03301JE05'           | 'R0201'             | '(SMR0201AW)'                  | '33'      | '5%'    | '1/20W'  | 'IO'       | 'RES CHIP 33 1/20W +-5%(0201)WTC'                  | 'CHIPR0201'    | ''          | ''            | '20180803'
 '33'         | '5%'      | '1/20W'  | '0201LF'  | 'CHIP'   | 'CS03301JE05SEL1'(!)    = ''              | ''                 | 'CS03301JE05SEL1'       | 'R0201'             | '(SMR0201AW)'                  | '33'      | '5%'    | '1/20W'  | 'DISCRETE' | 'RES CHIP 33 1/20W +-5%(0201)WTCSELA'              | 'CHIPR0201'    | ''          | ''            | '20180803'
 '33'         | '5%'      | '1/20W'  | '0201LF'  | 'EMPTY'  | 'CS03301JE05SEL1'(!)    = ''              | ''                 | 'CS03301JE05SEL1'       | 'R0201'             | '(SMR0201AW)'                  | '33'      | '5%'    | '1/20W'  | 'IO'       | 'RES CHIP 33 1/20W +-5%(0201)WTCSELA'              | 'CHIPR0201'    | ''          | ''            | '20180803'
 '33'         | '1%'      | '1/16W'  | '0402LF'  | 'CHIP'   | 'CS03302FB14'(!)        = ''              | ''                 | 'CS03302FB14'           | 'R0402'             | '(R0402-0201)'                 | '33'      | '1%'    | '1/16W'  | 'DISCRETE' | 'RES CHIP 33 1/16W +-1%(0402)WTC'                  | 'CHIP0402'     | ''          | ''            | '20100811'
 '33'         | '1%'      | '1/16W'  | '0402LF'  | 'EMPTY'  | 'CS03302FB14'(!)        = ''              | ''                 | 'CS03302FB14'           | 'R0402'             | '(R0402-0201)'                 | '33'      | '1%'    | '1/16W'  | 'IO'       | 'RES CHIP 33 1/16W +-1%(0402)WTC'                  | 'CHIP0402'     | ''          | ''            | '20100811'
 '33'         | '1%'      | '1/16W'  | '0402LF'  | 'CHIP'   | 'CS03302FB14SEL1'(!)    = ''              | ''                 | 'CS03302FB14SEL1'       | 'R0402'             | '(R0402-0201)'                 | '33'      | '1%'    | '1/16W'  | 'DISCRETE' | 'RES CHIP 33 1/16W +-1%(0402)WTCSELA'              | 'CHIP0402'     | ''          | ''            | '20100811'
 '33'         | '1%'      | '1/16W'  | '0402LF'  | 'EMPTY'  | 'CS03302FB14SEL1'(!)    = ''              | ''                 | 'CS03302FB14SEL1'       | 'R0402'             | '(R0402-0201)'                 | '33'      | '1%'    | '1/16W'  | 'IO'       | 'RES CHIP 33 1/16W +-1%(0402)WTCSELA'              | 'CHIP0402'     | ''          | ''            | '20100811'
 '33'         | '5%'      | '1/16W'  | '0402LF'  | 'CHIP'   | 'CS03302JB19'(!)        = ''              | ''                 | 'CS03302JB19'           | 'R0402'             | '(R0402-0201)'                 | '33'      | '5%'    | '1/16W'  | 'DISCRETE' | 'RES CHIP 33 1/16W +-5% (0402)CYN'                 | 'CHIP0402'     | ''          | ''            | '20100708'
 '33'         | '5%'      | '1/16W'  | '0402LF'  | 'EMPTY'  | 'CS03302JB19'(!)        = ''              | ''                 | 'CS03302JB19'           | 'R0402'             | '(R0402-0201)'                 | '33'      | '5%'    | '1/16W'  | 'IO'       | 'RES CHIP 33 1/16W +-5% (0402)CYN'                 | 'CHIP0402'     | ''          | ''            | '20100708'
 '33'         | '5%'      | '1/16W'  | '0402LF'  | 'CHIP'   | 'CS03302JB19SEL1'(!)    = ''              | ''                 | 'CS03302JB19SEL1'       | 'R0402'             | '(R0402-0201)'                 | '33'      | '5%'    | '1/16W'  | 'DISCRETE' | 'RES CHIP 33 1/16W +-5% (0402)CYNSELA'             | 'CHIP0402'     | ''          | ''            | '20100708'
 '33'         | '5%'      | '1/16W'  | '0402LF'  | 'EMPTY'  | 'CS03302JB19SEL1'(!)    = ''              | ''                 | 'CS03302JB19SEL1'       | 'R0402'             | '(R0402-0201)'                 | '33'      | '5%'    | '1/16W'  | 'IO'       | 'RES CHIP 33 1/16W +-5% (0402)CYNSELA'             | 'CHIP0402'     | ''          | ''            | '20100708'
 '33.2'       | '1%'      | '1/20W'  | '0201LF'  | 'CHIP'   | 'CS03321FE10'(!)        = ''              | ''                 | 'CS03321FE10'           | 'R0201'             | '(SMR0201AW)'                  | '33.2'    | '1%'    | '1/20W'  | 'DISCRETE' | 'RES CHIP 33.2 1/20W +-1%(0201)YGO'                | 'CHIPR0201'    | ''          | ''            | '20180803'
 '33.2'       | '1%'      | '1/20W'  | '0201LF'  | 'EMPTY'  | 'CS03321FE10'(!)        = ''              | ''                 | 'CS03321FE10'           | 'R0201'             | '(SMR0201AW)'                  | '33.2'    | '1%'    | '1/20W'  | 'IO'       | 'RES CHIP 33.2 1/20W +-1%(0201)YGO'                | 'CHIPR0201'    | ''          | ''            | '20180803'
 '33.2'       | '1%'      | '1/20W'  | '0201LF'  | 'CHIP'   | 'CS03321FE10SEL1'(!)    = ''              | ''                 | 'CS03321FE10SEL1'       | 'R0201'             | '(SMR0201AW)'                  | '33.2'    | '1%'    | '1/20W'  | 'DISCRETE' | 'RES CHIP 33.2 1/20W +-1%(0201)YGO SELA'           | 'CHIPR0201'    | ''          | ''            | '20180803'
 '33.2'       | '1%'      | '1/20W'  | '0201LF'  | 'EMPTY'  | 'CS03321FE10SEL1'(!)    = ''              | ''                 | 'CS03321FE10SEL1'       | 'R0201'             | '(SMR0201AW)'                  | '33.2'    | '1%'    | '1/20W'  | 'IO'       | 'RES CHIP 33.2 1/20W +-1%(0201)YGO SELA'           | 'CHIPR0201'    | ''          | ''            | '20180803'
 '0.001'      | '1%'      | '1W'     | '2512LF'  | 'CHIP'   | 'CS+0018FR07SEL1'(!)    = ''              | ''                 | 'CS+0018FR07SEL1'       | 'R2512A'            | '(SMR2512AW)'                  | '0.001'   | '1%'    | '1W'     | 'DISCRETE' | 'RES CHIP 0.001 1W +-1%(2512)YGO AECSELA'          | 'CHIPR2512'    | ''          | ''            | '20230825'
 '0.001'      | '1%'      | '1W'     | '2512LF'  | 'EMPTY'  | 'CS+0018FR07SEL1'(!)    = ''              | ''                 | 'CS+0018FR07SEL1'       | 'R2512A'            | '(SMR2512AW)'                  | '0.001'   | '1%'    | '1W'     | 'IO'       | 'RES CHIP 0.001 1W +-1%(2512)YGO AECSELA'          | 'CHIPR2512'    | ''          | ''            | '20230825'
 '0.001'      | '1%'      | '1W'     | '2512LF'  | 'CHIP'   | 'CS+0018FR07'(!)        = ''              | ''                 | 'CS+0018FR07'           | 'R2512A'            | '(SMR2512AW)'                  | '0.001'   | '1%'    | '1W'     | 'DISCRETE' | 'RES CHIP 0.001 1W +-1%(2512)YGO_AEC'              | 'CHIPR2512'    | ''          | ''            | '20230825'
 '0.001'      | '1%'      | '1W'     | '2512LF'  | 'EMPTY'  | 'CS+0018FR07'(!)        = ''              | ''                 | 'CS+0018FR07'           | 'R2512A'            | '(SMR2512AW)'                  | '0.001'   | '1%'    | '1W'     | 'IO'       | 'RES CHIP 0.001 1W +-1%(2512)YGO_AEC'              | 'CHIPR2512'    | ''          | ''            | '20230825'
 '0.001'      | '1%'      | '3W'     | '2512LF'  | 'CHIP'   | 'CS+001DFR10SEL1'(!)    = ''              | ''                 | 'CS+001DFR10SEL1'       | 'R2512XJ'           | '(SMR2512AW)'                  | '0.001'   | '1%'    | '3W'     | 'DISCRETE' | 'RES CHIP 0.001 3W +-1%(2512)RLCSELA'              | 'CHIPR2512'    | ''          | ''            | '20230825'
 '0.001'      | '1%'      | '3W'     | '2512LF'  | 'EMPTY'  | 'CS+001DFR10SEL1'(!)    = ''              | ''                 | 'CS+001DFR10SEL1'       | 'R2512XJ'           | '(SMR2512AW)'                  | '0.001'   | '1%'    | '3W'     | 'IO'       | 'RES CHIP 0.001 3W +-1%(2512)RLCSELA'              | 'CHIPR2512'    | ''          | ''            | '20230825'
 '0.0005'     | '1%'      | '3W'     | '2512LF'  | 'CHIP'   | 'CS0000DFR18SEL1'(!)    = ''              | ''                 | 'CS0000DFR18SEL1'       | 'R2512XG'           | '(SMR2512AW)'                  | '0.0005'  | '1%'    | '3W'     | 'DISCRETE' | 'RES CHIP 0.0005 3W +-1%(2512)RLCSELA'             | 'CHIPR2512'    | ''          | ''            | '20230825'
 '0.0005'     | '1%'      | '3W'     | '2512LF'  | 'EMPTY'  | 'CS0000DFR18SEL1'(!)    = ''              | ''                 | 'CS0000DFR18SEL1'       | 'R2512XG'           | '(SMR2512AW)'                  | '0.0005'  | '1%'    | '3W'     | 'IO'       | 'RES CHIP 0.0005 3W +-1%(2512)RLCSELA'             | 'CHIPR2512'    | ''          | ''            | '20230825'
 '33.2'       | '1%'      | '1/16W'  | '0402LF'  | 'CHIP'   | 'CS03322FB15'(!)        = ''              | ''                 | 'CS03322FB15'           | 'R0402'             | '(R0402-0201)'                 | '33.2'    | '1%'    | '1/16W'  | 'DISCRETE' | 'RES CHIP 33.2 1/16W +-1%(0402)CYN'                | 'CHIP0402'     | ''          | ''            | '20111213'
 '33.2'       | '1%'      | '1/16W'  | '0402LF'  | 'EMPTY'  | 'CS03322FB15'(!)        = ''              | ''                 | 'CS03322FB15'           | 'R0402'             | '(R0402-0201)'                 | '33.2'    | '1%'    | '1/16W'  | 'IO'       | 'RES CHIP 33.2 1/16W +-1%(0402)CYN'                | 'CHIP0402'     | ''          | ''            | '20111213'
 '33.2'       | '1%'      | '1/16W'  | '0402LF'  | 'CHIP'   | 'CS03322FB15SEL1'(!)    = ''              | ''                 | 'CS03322FB15SEL1'       | 'R0402'             | '(R0402-0201)'                 | '33.2'    | '1%'    | '1/16W'  | 'DISCRETE' | 'RES CHIP 33.2 1/16W +-1%(0402)CYNSELA'            | 'CHIP0402'     | ''          | ''            | '20111213'
 '33.2'       | '1%'      | '1/16W'  | '0402LF'  | 'EMPTY'  | 'CS03322FB15SEL1'(!)    = ''              | ''                 | 'CS03322FB15SEL1'       | 'R0402'             | '(R0402-0201)'                 | '33.2'    | '1%'    | '1/16W'  | 'IO'       | 'RES CHIP 33.2 1/16W +-1%(0402)CYNSELA'            | 'CHIP0402'     | ''          | ''            | '20111213'
 '40.2'       | '1%'      | '1/16W'  | '0402LF'  | 'CHIP'   | 'CS04022FB12'(!)        = ''              | ''                 | 'CS04022FB12'           | 'R0402'             | '(R0402-0201)'                 | '40.2'    | '1%'    | '1/16W'  | 'DISCRETE' | 'RES CHIP 40.2 1/16W +-1%(0402)CYN'                | 'CHIP0402'     | ''          | ''            | '20140630'
 '40.2'       | '1%'      | '1/16W'  | '0402LF'  | 'EMPTY'  | 'CS04022FB12'(!)        = ''              | ''                 | 'CS04022FB12'           | 'R0402'             | '(R0402-0201)'                 | '40.2'    | '1%'    | '1/16W'  | 'IO'       | 'RES CHIP 40.2 1/16W +-1%(0402)CYN'                | 'CHIP0402'     | ''          | ''            | '20140630'
 '40.2'       | '1%'      | '1/16W'  | '0402LF'  | 'CHIP'   | 'CS04022FB12SEL1'(!)    = ''              | ''                 | 'CS04022FB12SEL1'       | 'R0402'             | '(R0402-0201)'                 | '40.2'    | '1%'    | '1/16W'  | 'DISCRETE' | 'RES CHIP 40.2 1/16W +-1%(0402)CYNSELA'            | 'CHIP0402'     | ''          | ''            | '20140630'
 '40.2'       | '1%'      | '1/16W'  | '0402LF'  | 'EMPTY'  | 'CS04022FB12SEL1'(!)    = ''              | ''                 | 'CS04022FB12SEL1'       | 'R0402'             | '(R0402-0201)'                 | '40.2'    | '1%'    | '1/16W'  | 'IO'       | 'RES CHIP 40.2 1/16W +-1%(0402)CYNSELA'            | 'CHIP0402'     | ''          | ''            | '20140630'
 '49.9'       | '1%'      | '1/20W'  | '0201LF'  | 'CHIP'   | 'CS04991FE19'(!)        = ''              | ''                 | 'CS04991FE19'           | 'R0201'             | '(SMR0201AW)'                  | '49.9'    | '1%'    | '1/20W'  | 'DISCRETE' | 'RES CHIP 49.9 1/20W +-1%(0201)CYN'                | 'CHIP0201'     | ''          | ''            | '20120528'
 '49.9'       | '1%'      | '1/20W'  | '0201LF'  | 'EMPTY'  | 'CS04991FE19'(!)        = ''              | ''                 | 'CS04991FE19'           | 'R0201'             | '(SMR0201AW)'                  | '49.9'    | '1%'    | '1/20W'  | 'IO'       | 'RES CHIP 49.9 1/20W +-1%(0201)CYN'                | 'CHIP0201'     | ''          | ''            | '20120528'
 '49.9'       | '1%'      | '1/20W'  | '0201LF'  | 'CHIP'   | 'CS04991FE19SEL1'(!)    = ''              | ''                 | 'CS04991FE19SEL1'       | 'R0201'             | '(SMR0201AW)'                  | '49.9'    | '1%'    | '1/20W'  | 'DISCRETE' | 'RES CHIP 49.9 1/20W +-1%(0201)CYNSELA'            | 'CHIP0201'     | ''          | ''            | '20120528'
 '49.9'       | '1%'      | '1/20W'  | '0201LF'  | 'EMPTY'  | 'CS04991FE19SEL1'(!)    = ''              | ''                 | 'CS04991FE19SEL1'       | 'R0201'             | '(SMR0201AW)'                  | '49.9'    | '1%'    | '1/20W'  | 'IO'       | 'RES CHIP 49.9 1/20W +-1%(0201)CYNSELA'            | 'CHIP0201'     | ''          | ''            | '20120528'
 '49.9'       | '1%'      | '1/16W'  | '0402LF'  | 'CHIP'   | 'CS04992FB27'(!)        = ''              | ''                 | 'CS04992FB27'           | 'R0402'             | '(R0402_OCTAGONXA,R0402-0201)' | '49.9'    | '1%'    | '1/16W ' | 'DISCRETE' | 'RES CHIP 49.9 1/16W +-1% (0402)CYN'               | 'CHIP0402'     | ''          | ''            | '20100716'
 '49.9'       | '1%'      | '1/16W'  | '0402LF'  | 'EMPTY'  | 'CS04992FB27'(!)        = ''              | ''                 | 'CS04992FB27'           | 'R0402'             | '(R0402_OCTAGONXA,R0402-0201)' | '49.9'    | '1%'    | '1/16W ' | 'IO'       | 'RES CHIP 49.9 1/16W +-1% (0402)CYN'               | 'CHIP0402'     | ''          | ''            | '20100716'
 '49.9'       | '1%'      | '1/16W'  | '0402LF'  | 'CHIP'   | 'CS04992FB27SEL1'(!)    = ''              | ''                 | 'CS04992FB27SEL1'       | 'R0402'             | '(R0402_OCTAGONXA,R0402-0201)' | '49.9'    | '1%'    | '1/16W ' | 'DISCRETE' | 'RES CHIP 49.9 1/16W +-1% (0402)CYN SELA'          | 'CHIP0402'     | ''          | ''            | '20100716'
 '49.9'       | '1%'      | '1/16W'  | '0402LF'  | 'EMPTY'  | 'CS04992FB27SEL1'(!)    = ''              | ''                 | 'CS04992FB27SEL1'       | 'R0402'             | '(R0402_OCTAGONXA,R0402-0201)' | '49.9'    | '1%'    | '1/16W ' | 'IO'       | 'RES CHIP 49.9 1/16W +-1% (0402)CYN SELA'          | 'CHIP0402'     | ''          | ''            | '20100716'
 '51.1'       | '1%'      | '1/16W'  | '0402LF'  | 'CHIP'   | 'CS05112FB12'(!)        = ''              | ''                 | 'CS05112FB12'           | 'R0402'             | '(R0402-0201)'                 | '51.1'    | '1%'    | '1/16W'  | 'DISCRETE' | 'RES CHIP 51.1 1/16W +-1%(0402)YGO'                | 'CHIP0402'     | ''          | ''            | '20111213'
 '51.1'       | '1%'      | '1/16W'  | '0402LF'  | 'EMPTY'  | 'CS05112FB12'(!)        = ''              | ''                 | 'CS05112FB12'           | 'R0402'             | '(R0402-0201)'                 | '51.1'    | '1%'    | '1/16W'  | 'IO'       | 'RES CHIP 51.1 1/16W +-1%(0402)YGO'                | 'CHIP0402'     | ''          | ''            | '20111213'
 '51.1'       | '1%'      | '1/16W'  | '0402LF'  | 'CHIP'   | 'CS05112FB12SEL1'(!)    = ''              | ''                 | 'CS05112FB12SEL1'       | 'R0402'             | '(R0402-0201)'                 | '51.1'    | '1%'    | '1/16W'  | 'DISCRETE' | 'RES CHIP 51.1 1/16W +-1%(0402)YGOSELA'            | 'CHIP0402'     | ''          | ''            | '20111213'
 '51.1'       | '1%'      | '1/16W'  | '0402LF'  | 'EMPTY'  | 'CS05112FB12SEL1'(!)    = ''              | ''                 | 'CS05112FB12SEL1'       | 'R0402'             | '(R0402-0201)'                 | '51.1'    | '1%'    | '1/16W'  | 'IO'       | 'RES CHIP 51.1 1/16W +-1%(0402)YGOSELA'            | 'CHIP0402'     | ''          | ''            | '20111213'
 '60.4'       | '1%'      | '1/16W'  | '0402LF'  | 'CHIP'   | 'CS06042FB16'(!)        = ''              | ''                 | 'CS06042FB16'           | 'R0402'             | '(R0402-0201)'                 | '60.4'    | '1%'    | '1/16W'  | 'DISCRETE' | 'RES CHIP 60.4 1/16W +-1%(0402)EF RLC'             | 'CHIPR0402'    | ''          | ''            | '20180221'
 '60.4'       | '1%'      | '1/16W'  | '0402LF'  | 'EMPTY'  | 'CS06042FB16'(!)        = ''              | ''                 | 'CS06042FB16'           | 'R0402'             | '(R0402-0201)'                 | '60.4'    | '1%'    | '1/16W'  | 'IO'       | 'RES CHIP 60.4 1/16W +-1%(0402)EF RLC'             | 'CHIPR0402'    | ''          | ''            | '20180221'
 '60.4'       | '1%'      | '1/16W'  | '0402LF'  | 'CHIP'   | 'CS06042FB16SEL1'(!)    = ''              | ''                 | 'CS06042FB16SEL1'       | 'R0402'             | '(R0402-0201)'                 | '60.4'    | '1%'    | '1/16W'  | 'DISCRETE' | 'RES CHIP 60.4 1/16W 1%(0402)EF RLC SELA'          | 'CHIPR0402'    | ''          | ''            | '20180221'
 '60.4'       | '1%'      | '1/16W'  | '0402LF'  | 'EMPTY'  | 'CS06042FB16SEL1'(!)    = ''              | ''                 | 'CS06042FB16SEL1'       | 'R0402'             | '(R0402-0201)'                 | '60.4'    | '1%'    | '1/16W'  | 'IO'       | 'RES CHIP 60.4 1/16W 1%(0402)EF RLC SELA'          | 'CHIPR0402'    | ''          | ''            | '20180221'
 '75'         | '1%'      | '1/16W'  | '0402LF'  | 'CHIP'   | 'CS07502FB15'(!)        = ''              | ''                 | 'CS07502FB15'           | 'R0402'             | '(R0402-0201)'                 | '75'      | '1%'    | '1/16W'  | 'DISCRETE' | 'RES CHIP 75 1/16W +-1% (0402)CYN'                 | 'CHIP0402'     | ''          | ''            | '20100811'
 '75'         | '1%'      | '1/16W'  | '0402LF'  | 'EMPTY'  | 'CS07502FB15'(!)        = ''              | ''                 | 'CS07502FB15'           | 'R0402'             | '(R0402-0201)'                 | '75'      | '1%'    | '1/16W'  | 'IO'       | 'RES CHIP 75 1/16W +-1% (0402)CYN'                 | 'CHIP0402'     | ''          | ''            | '20100811'
 '75'         | '1%'      | '1/16W'  | '0402LF'  | 'CHIP'   | 'CS07502FB15SEL1'(!)    = ''              | ''                 | 'CS07502FB15SEL1'       | 'R0402'             | '(R0402-0201)'                 | '75'      | '1%'    | '1/16W'  | 'DISCRETE' | 'RES CHIP 75 1/16W +-1% (0402)CYNSELA'             | 'CHIP0402'     | ''          | ''            | '20100811'
 '75'         | '1%'      | '1/16W'  | '0402LF'  | 'EMPTY'  | 'CS07502FB15SEL1'(!)    = ''              | ''                 | 'CS07502FB15SEL1'       | 'R0402'             | '(R0402-0201)'                 | '75'      | '1%'    | '1/16W'  | 'IO'       | 'RES CHIP 75 1/16W +-1% (0402)CYNSELA'             | 'CHIP0402'     | ''          | ''            | '20100811'
 '75'         | '5%'      | '1/16W'  | '0402LF'  | 'CHIP'   | 'CS07502JB12'(!)        = ''              | ''                 | 'CS07502JB12'           | 'R0402'             | '(R0402-0201)'                 | '75'      | '5%'    | '1/16W'  | 'DISCRETE' | 'RES CHIP 75 1/16W +-5%(0402)WTC'                  | 'CHIP0402'     | ''          | ''            | '20100831'
 '75'         | '5%'      | '1/16W'  | '0402LF'  | 'EMPTY'  | 'CS07502JB12'(!)        = ''              | ''                 | 'CS07502JB12'           | 'R0402'             | '(R0402-0201)'                 | '75'      | '5%'    | '1/16W'  | 'IO'       | 'RES CHIP 75 1/16W +-5%(0402)WTC'                  | 'CHIP0402'     | ''          | ''            | '20100831'
 '75'         | '5%'      | '1/16W'  | '0402LF'  | 'CHIP'   | 'CS07502JB12SEL1'(!)    = ''              | ''                 | 'CS07502JB12SEL1'       | 'R0402'             | '(R0402-0201)'                 | '75'      | '5%'    | '1/16W'  | 'DISCRETE' | 'RES CHIP 75 1/16W +-5%(0402)WTC SELA'             | 'CHIP0402'     | ''          | ''            | '20100831'
 '75'         | '5%'      | '1/16W'  | '0402LF'  | 'EMPTY'  | 'CS07502JB12SEL1'(!)    = ''              | ''                 | 'CS07502JB12SEL1'       | 'R0402'             | '(R0402-0201)'                 | '75'      | '5%'    | '1/16W'  | 'IO'       | 'RES CHIP 75 1/16W +-5%(0402)WTC SELA'             | 'CHIP0402'     | ''          | ''            | '20100831'
 '1'          | '1%'      | '1/16W'  | '0402LF'  | 'CHIP'   | 'CS-1002FB28'(!)        = ''              | ''                 | 'CS-1002FB28'           | 'R0402'             | '(R0402-0201)'                 | '1'       | '1%'    | '1/16W'  | 'DISCRETE' | 'RES CHIP 1 1/16W +-1%(0402)CYN'                   | 'CHIP0402'     | ''          | ''            | '20140818'
 '1'          | '1%'      | '1/16W'  | '0402LF'  | 'EMPTY'  | 'CS-1002FB28'(!)        = ''              | ''                 | 'CS-1002FB28'           | 'R0402'             | '(R0402-0201)'                 | '1'       | '1%'    | '1/16W'  | 'IO'       | 'RES CHIP 1 1/16W +-1%(0402)CYN'                   | 'CHIP0402'     | ''          | ''            | '20140818'
 '1'          | '1%'      | '1/16W'  | '0402LF'  | 'CHIP'   | 'CS-1002FB28SEL1'(!)    = ''              | ''                 | 'CS-1002FB28SEL1'       | 'R0402'             | '(R0402-0201)'                 | '1'       | '1%'    | '1/16W'  | 'DISCRETE' | 'RES CHIP 1 1/16W 1%(0402)CYNSELA'                 | 'CHIP0402'     | ''          | ''            | '20140818'
 '1'          | '1%'      | '1/16W'  | '0402LF'  | 'EMPTY'  | 'CS-1002FB28SEL1'(!)    = ''              | ''                 | 'CS-1002FB28SEL1'       | 'R0402'             | '(R0402-0201)'                 | '1'       | '1%'    | '1/16W'  | 'IO'       | 'RES CHIP 1 1/16W 1%(0402)CYNSELA'                 | 'CHIP0402'     | ''          | ''            | '20140818'
 '1'          | '5%'      | '1/16W'  | '0402LF'  | 'CHIP'   | 'CS-1002JB21'(!)        = ''              | ''                 | 'CS-1002JB21'           | 'R0402'             | '(R0402-0201)'                 | '1'       | '5%'    | '1/16W'  | 'DISCRETE' | 'RES CHIP 1 1/16W +-5%(0402)CYN'                   | 'CHIP0402'     | ''          | ''            | '20120114'
 '1'          | '5%'      | '1/16W'  | '0402LF'  | 'EMPTY'  | 'CS-1002JB21'(!)        = ''              | ''                 | 'CS-1002JB21'           | 'R0402'             | '(R0402-0201)'                 | '1'       | '5%'    | '1/16W'  | 'IO'       | 'RES CHIP 1 1/16W +-5%(0402)CYN'                   | 'CHIP0402'     | ''          | ''            | '20120114'
 '1'          | '5%'      | '1/16W'  | '0402LF'  | 'CHIP'   | 'CS-1002JB21SEL1'(!)    = ''              | ''                 | 'CS-1002JB21SEL1'       | 'R0402'             | '(R0402-0201)'                 | '1'       | '5%'    | '1/16W'  | 'DISCRETE' | 'RES CHIP 1 1/16W +-5%(0402)CYNSELA'               | 'CHIP0402'     | ''          | ''            | '20120114'
 '1'          | '5%'      | '1/16W'  | '0402LF'  | 'EMPTY'  | 'CS-1002JB21SEL1'(!)    = ''              | ''                 | 'CS-1002JB21SEL1'       | 'R0402'             | '(R0402-0201)'                 | '1'       | '5%'    | '1/16W'  | 'IO'       | 'RES CHIP 1 1/16W +-5%(0402)CYNSELA'               | 'CHIP0402'     | ''          | ''            | '20120114'
 '1'          | '1%'      | '1/10W'  | '0603LF'  | 'CHIP'   | 'CS-1003F909'(!)        = ''              | ''                 | 'CS-1003F909'           | 'R0603'             | '(SMR0603AW)'                  | '1'       | '1%'    | '1/10W'  | 'DISCRETE' | 'RES CHIP 1 1/10W +-1%(0603)YGO'                   | 'CHIP0603'     | ''          | ''            | '20131007'
 '1'          | '1%'      | '1/10W'  | '0603LF'  | 'EMPTY'  | 'CS-1003F909'(!)        = ''              | ''                 | 'CS-1003F909'           | 'R0603'             | '(SMR0603AW)'                  | '1'       | '1%'    | '1/10W'  | 'IO'       | 'RES CHIP 1 1/10W +-1%(0603)YGO'                   | 'CHIP0603'     | ''          | ''            | '20131007'
 '1'          | '1%'      | '1/10W'  | '0603LF'  | 'CHIP'   | 'CS-1003F909SEL1'(!)    = ''              | ''                 | 'CS-1003F909SEL1'       | 'R0603'             | '(SMR0603AW)'                  | '1'       | '1%'    | '1/10W'  | 'DISCRETE' | 'RES CHIP 1 1/10W +-1%(0603)YGOSELA'               | 'CHIP0603'     | ''          | ''            | '20131007'
 '1'          | '1%'      | '1/10W'  | '0603LF'  | 'EMPTY'  | 'CS-1003F909SEL1'(!)    = ''              | ''                 | 'CS-1003F909SEL1'       | 'R0603'             | '(SMR0603AW)'                  | '1'       | '1%'    | '1/10W'  | 'IO'       | 'RES CHIP 1 1/10W +-1%(0603)YGOSELA'               | 'CHIP0603'     | ''          | ''            | '20131007'
 '1'          | '1%'      | '1/8W'   | '0402LF'  | 'CHIP'   | 'CS-1004FB06'(!)        = ''              | ''                 | 'CS-1004FB06'           | 'R0402'             | '(R0402-0201)'                 | '1'       | '1%'    | '1/8W'   | 'DISCRETE' | 'RES CHIP 1 1/8W +-1%(0402)WTC'                    | 'CHIPR0402'    | ''          | ''            | '20180523'
 '1'          | '1%'      | '1/8W'   | '0402LF'  | 'EMPTY'  | 'CS-1004FB06'(!)        = ''              | ''                 | 'CS-1004FB06'           | 'R0402'             | '(R0402-0201)'                 | '1'       | '1%'    | '1/8W'   | 'IO'       | 'RES CHIP 1 1/8W +-1%(0402)WTC'                    | 'CHIPR0402'    | ''          | ''            | '20180523'
 '1'          | '1%'      | '1/8W'   | '0402LF'  | 'CHIP'   | 'CS-1004FB06SEL1'(!)    = ''              | ''                 | 'CS-1004FB06SEL1'       | 'R0402'             | '(R0402-0201)'                 | '1'       | '1%'    | '1/8W'   | 'DISCRETE' | 'RES CHIP 1 1/8W +-1%(0402)WTCSELA'                | 'CHIPR0402'    | ''          | ''            | '20180523'
 '1'          | '1%'      | '1/8W'   | '0402LF'  | 'EMPTY'  | 'CS-1004FB06SEL1'(!)    = ''              | ''                 | 'CS-1004FB06SEL1'       | 'R0402'             | '(R0402-0201)'                 | '1'       | '1%'    | '1/8W'   | 'IO'       | 'RES CHIP 1 1/8W +-1%(0402)WTCSELA'                | 'CHIPR0402'    | ''          | ''            | '20180523'
 '1'          | '1%'      | '1/4W'   | '1206LF'  | 'CHIP'   | 'CS-1006F208'(!)        = ''              | ''                 | 'CS-1006F208'           | 'R1206'             | '(SMR1206AW)'                  | '1'       | '1%'    | '1/4W'   | 'DISCRETE' | 'RES CHIP 1 1/4W +-1%(1206)YGO'                    | 'CHIP1206'     | ''          | ''            | '20130611'
 '1'          | '1%'      | '1/4W'   | '1206LF'  | 'EMPTY'  | 'CS-1006F208'(!)        = ''              | ''                 | 'CS-1006F208'           | 'R1206'             | '(SMR1206AW)'                  | '1'       | '1%'    | '1/4W'   | 'IO'       | 'RES CHIP 1 1/4W +-1%(1206)YGO'                    | 'CHIP1206'     | ''          | ''            | '20130611'
 '1'          | '1%'      | '1/4W'   | '1206LF'  | 'CHIP'   | 'CS-1006F208SEL1'(!)    = ''              | ''                 | 'CS-1006F208SEL1'       | 'R1206'             | '(SMR1206AW)'                  | '1'       | '1%'    | '1/4W'   | 'DISCRETE' | 'RES CHIP 1 1/4W +-1%(1206)YGOSELA'                | 'CHIP1206'     | ''          | ''            | '20130611'
 '1'          | '1%'      | '1/4W'   | '1206LF'  | 'EMPTY'  | 'CS-1006F208SEL1'(!)    = ''              | ''                 | 'CS-1006F208SEL1'       | 'R1206'             | '(SMR1206AW)'                  | '1'       | '1%'    | '1/4W'   | 'IO'       | 'RES CHIP 1 1/4W +-1%(1206)YGOSELA'                | 'CHIP1206'     | ''          | ''            | '20130611'
 '1'          | '1%'      | '1/2W'   | '1206LF'  | 'CHIP'   | 'CS-1007F204'(!)        = ''              | ''                 | 'CS-1007F204'           | 'R1206XJ'           | '(SMRR1206AW)'                 | '1'       | '1%'    | '1/2W'   | 'DISCRETE' | 'RES CHIP 1 1/2W +-1%(1206)TAI'                    | 'CHIPR1206'    | ''          | ''            | '20170725'
 '1'          | '1%'      | '1/2W'   | '1206LF'  | 'EMPTY'  | 'CS-1007F204'(!)        = ''              | ''                 | 'CS-1007F204'           | 'R1206XJ'           | '(SMRR1206AW)'                 | '1'       | '1%'    | '1/2W'   | 'IO'       | 'RES CHIP 1 1/2W +-1%(1206)TAI'                    | 'CHIPR1206'    | ''          | ''            | '20170725'
 '1'          | '1%'      | '1/2W'   | '1206LF'  | 'CHIP'   | 'CS-1007F204SEL1'(!)    = ''              | ''                 | 'CS-1007F204SEL1'       | 'R1206XJ'           | '(SMRR1206AW)'                 | '1'       | '1%'    | '1/2W'   | 'DISCRETE' | 'RES CHIP 1 1/2W +-1%(1206)TAISELA'                | 'CHIPR1206'    | ''          | ''            | '20170725'
 '1'          | '1%'      | '1/2W'   | '1206LF'  | 'EMPTY'  | 'CS-1007F204SEL1'(!)    = ''              | ''                 | 'CS-1007F204SEL1'       | 'R1206XJ'           | '(SMRR1206AW)'                 | '1'       | '1%'    | '1/2W'   | 'IO'       | 'RES CHIP 1 1/2W +-1%(1206)TAISELA'                | 'CHIPR1206'    | ''          | ''            | '20170725'
 '1'          | '5%'      | '1/2W'   | '1206LF'  | 'CHIP'   | 'CS-1007J202'(!)        = ''              | ''                 | 'CS-1007J202'           | 'R1206XN'           | '(SMR1206AW)'                  | '1'       | '5%'    | '1/2W'   | 'DISCRETE' | 'RES CHIP 1 1/2W +-5%(1206)SR RLC'                 | 'CHIPR1206'    | ''          | ''            | '20200715'
 '1'          | '5%'      | '1/2W'   | '1206LF'  | 'EMPTY'  | 'CS-1007J202'(!)        = ''              | ''                 | 'CS-1007J202'           | 'R1206XN'           | '(SMR1206AW)'                  | '1'       | '5%'    | '1/2W'   | 'IO'       | 'RES CHIP 1 1/2W +-5%(1206)SR RLC'                 | 'CHIPR1206'    | ''          | ''            | '20200715'
 '1'          | '5%'      | '1/2W'   | '1206LF'  | 'CHIP'   | 'CS-1007J202SEL1'(!)    = ''              | ''                 | 'CS-1007J202SEL1'       | 'R1206XN'           | '(SMR1206AW)'                  | '1'       | '5%'    | '1/2W'   | 'DISCRETE' | 'RES CHIP 1 1/2W +-5%(1206)SR RLCSELA'             | 'CHIPR1206'    | ''          | ''            | '20200715'
 '1'          | '5%'      | '1/2W'   | '1206LF'  | 'EMPTY'  | 'CS-1007J202SEL1'(!)    = ''              | ''                 | 'CS-1007J202SEL1'       | 'R1206XN'           | '(SMR1206AW)'                  | '1'       | '5%'    | '1/2W'   | 'IO'       | 'RES CHIP 1 1/2W +-5%(1206)SR RLCSELA'             | 'CHIPR1206'    | ''          | ''            | '20200715'
 '100'        | '1%'      | '1/20W'  | '0201LF'  | 'CHIP'   | 'CS11001FE13'(!)        = ''              | ''                 | 'CS11001FE13'           | 'R0201'             | '(SMR0201AW)'                  | '100'     | '1%'    | '1/20W'  | 'DISCRETE' | 'RES CHIP 100 1/20W +-1%(0201)CYN'                 | 'CHIP0201'     | ''          | ''            | '20120528'
 '100'        | '1%'      | '1/20W'  | '0201LF'  | 'EMPTY'  | 'CS11001FE13'(!)        = ''              | ''                 | 'CS11001FE13'           | 'R0201'             | '(SMR0201AW)'                  | '100'     | '1%'    | '1/20W'  | 'IO'       | 'RES CHIP 100 1/20W +-1%(0201)CYN'                 | 'CHIP0201'     | ''          | ''            | '20120528'
 '100'        | '1%'      | '1/20W'  | '0201LF'  | 'CHIP'   | 'CS11001FE13SEL1'(!)    = ''              | ''                 | 'CS11001FE13SEL1'       | 'R0201'             | '(SMR0201AW)'                  | '100'     | '1%'    | '1/20W'  | 'DISCRETE' | 'RES CHIP 100 1/20W +-1%(0201)CYNSELA'             | 'CHIP0201'     | ''          | ''            | '20120528'
 '100'        | '1%'      | '1/20W'  | '0201LF'  | 'EMPTY'  | 'CS11001FE13SEL1'(!)    = ''              | ''                 | 'CS11001FE13SEL1'       | 'R0201'             | '(SMR0201AW)'                  | '100'     | '1%'    | '1/20W'  | 'IO'       | 'RES CHIP 100 1/20W +-1%(0201)CYNSELA'             | 'CHIP0201'     | ''          | ''            | '20120528'
 '100'        | '1%'      | '1/16W'  | '0402LF'  | 'CHIP'   | 'CS11002FB31'(!)        = ''              | ''                 | 'CS11002FB31'           | 'R0402'             | '(R0402-0201)'                 | '100'     | '1%'    | '1/16W'  | 'DISCRETE' | 'RES CHIP 100 1/16W +-1%(0402)CYN'                 | 'CHIP0402'     | ''          | ''            | '20120528'
 '100'        | '1%'      | '1/16W'  | '0402LF'  | 'EMPTY'  | 'CS11002FB31'(!)        = ''              | ''                 | 'CS11002FB31'           | 'R0402'             | '(R0402-0201)'                 | '100'     | '1%'    | '1/16W'  | 'IO'       | 'RES CHIP 100 1/16W +-1%(0402)CYN'                 | 'CHIP0402'     | ''          | ''            | '20120528'
 '100'        | '1%'      | '1/16W'  | '0402LF'  | 'CHIP'   | 'CS11002FB31SEL1'(!)    = ''              | ''                 | 'CS11002FB31SEL1'       | 'R0402'             | '(R0402-0201)'                 | '100'     | '1%'    | '1/16W'  | 'DISCRETE' | 'RES CHIP 100 1/16W +-1%(0402)CYNSELA'             | 'CHIP0402'     | ''          | ''            | '20120528'
 '100'        | '1%'      | '1/16W'  | '0402LF'  | 'EMPTY'  | 'CS11002FB31SEL1'(!)    = ''              | ''                 | 'CS11002FB31SEL1'       | 'R0402'             | '(R0402-0201)'                 | '100'     | '1%'    | '1/16W'  | 'IO'       | 'RES CHIP 100 1/16W +-1%(0402)CYNSELA'             | 'CHIP0402'     | ''          | ''            | '20120528'
 '100'        | '5%'      | '1/16W'  | '0402LF'  | 'CHIP'   | 'CS11002JB22'(!)        = ''              | ''                 | 'CS11002JB22'           | 'R0402'             | '(R0402-0201)'                 | '100'     | '5%'    | '1/16W'  | 'DISCRETE' | 'RES CHIP 100 1/16W +-5%(0402)CYN'                 | 'CHIP0402'     | ''          | ''            | '20120528'
 '100'        | '5%'      | '1/16W'  | '0402LF'  | 'EMPTY'  | 'CS11002JB22'(!)        = ''              | ''                 | 'CS11002JB22'           | 'R0402'             | '(R0402-0201)'                 | '100'     | '5%'    | '1/16W'  | 'IO'       | 'RES CHIP 100 1/16W +-5%(0402)CYN'                 | 'CHIP0402'     | ''          | ''            | '20120528'
 '100'        | '5%'      | '1/16W'  | '0402LF'  | 'CHIP'   | 'CS11002JB22SEL1'(!)    = ''              | ''                 | 'CS11002JB22SEL1'       | 'R0402'             | '(R0402-0201)'                 | '100'     | '5%'    | '1/16W'  | 'DISCRETE' | 'RES CHIP 100 1/16W +-5%(0402)CYN SELA'            | 'CHIP0402'     | ''          | ''            | '20120528'
 '100'        | '5%'      | '1/16W'  | '0402LF'  | 'EMPTY'  | 'CS11002JB22SEL1'(!)    = ''              | ''                 | 'CS11002JB22SEL1'       | 'R0402'             | '(R0402-0201)'                 | '100'     | '5%'    | '1/16W'  | 'IO'       | 'RES CHIP 100 1/16W +-5%(0402)CYN SELA'            | 'CHIP0402'     | ''          | ''            | '20120528'
 '100'        | '1%'      | '1/2W'   | '1206LF'  | 'CHIP'   | 'CS11007F204'(!)        = ''              | ''                 | 'CS11007F204'           | 'R1206XI'           | '(SMR1206AW)'                  | '100'     | '1%'    | '1/2W'   | 'DISCRETE' | 'RES CHIP 100 1/2W +-1%(1206)WTC'                  | 'CHIP1206'     | ''          | ''            | '20221027'
 '100'        | '1%'      | '1/2W'   | '1206LF'  | 'EMPTY'  | 'CS11007F204'(!)        = ''              | ''                 | 'CS11007F204'           | 'R1206XI'           | '(SMR1206AW)'                  | '100'     | '1%'    | '1/2W'   | 'IO'       | 'RES CHIP 100 1/2W +-1%(1206)WTC'                  | 'CHIP1206'     | ''          | ''            | '20221027'
 '100'        | '1%'      | '1/2W'   | '1206LF'  | 'CHIP'   | 'CS11007F204SEL1'(!)    = ''              | ''                 | 'CS11007F204SEL1'       | 'R1206XI'           | '(SMR1206AW)'                  | '100'     | '1%'    | '1/2W'   | 'DISCRETE' | 'RES CHIP 100 1/2W +-1%(1206)WTCSELA'              | 'CHIP1206'     | ''          | ''            | '20221027'
 '100'        | '1%'      | '1/2W'   | '1206LF'  | 'EMPTY'  | 'CS11007F204SEL1'(!)    = ''              | ''                 | 'CS11007F204SEL1'       | 'R1206XI'           | '(SMR1206AW)'                  | '100'     | '1%'    | '1/2W'   | 'IO'       | 'RES CHIP 100 1/2W +-1%(1206)WTCSELA'              | 'CHIP1206'     | ''          | ''            | '20221027'
 '100'        | '5%'      | '1/2W'   | '1206LF'  | 'CHIP'   | 'CS11007J202'(!)        = ''              | ''                 | 'CS11007J202'           | 'R1206XN'           | '(SMR1206AW)'                  | '100'     | '5%'    | '1/2W'   | 'DISCRETE' | 'RES CHIP 100 1/2W +-5%(1206)SR RLC'               | 'CHIPR1206'    | ''          | ''            | '20200909'
 '100'        | '5%'      | '1/2W'   | '1206LF'  | 'EMPTY'  | 'CS11007J202'(!)        = ''              | ''                 | 'CS11007J202'           | 'R1206XN'           | '(SMR1206AW)'                  | '100'     | '5%'    | '1/2W'   | 'IO'       | 'RES CHIP 100 1/2W +-5%(1206)SR RLC'               | 'CHIPR1206'    | ''          | ''            | '20200909'
 '100'        | '5%'      | '1/2W'   | '1206LF'  | 'CHIP'   | 'CS11007J202SEL1'(!)    = ''              | ''                 | 'CS11007J202SEL1'       | 'R1206XN'           | '(SMR1206AW)'                  | '100'     | '5%'    | '1/2W'   | 'DISCRETE' | 'RES CHIP 100 1/2W +-5%(1206)SR RLCSELA'           | 'CHIPR1206'    | ''          | ''            | '20200909'
 '100'        | '5%'      | '1/2W'   | '1206LF'  | 'EMPTY'  | 'CS11007J202SEL1'(!)    = ''              | ''                 | 'CS11007J202SEL1'       | 'R1206XN'           | '(SMR1206AW)'                  | '100'     | '5%'    | '1/2W'   | 'IO'       | 'RES CHIP 100 1/2W +-5%(1206)SR RLCSELA'           | 'CHIPR1206'    | ''          | ''            | '20200909'
 '113'        | '1%'      | '1/16W'  | '0402LF'  | 'CHIP'   | 'CS11132FB09'(!)        = ''              | ''                 | 'CS11132FB09'           | 'R0402'             | '(R0402-0201)'                 | '113'     | '1%'    | '1/16W'  | 'DISCRETE' | 'RES CHIP 113 1/16W +-1%(0402)WTC'                 | 'CHIP0402'     | ''          | ''            | '20141016'
 '113'        | '1%'      | '1/16W'  | '0402LF'  | 'EMPTY'  | 'CS11132FB09'(!)        = ''              | ''                 | 'CS11132FB09'           | 'R0402'             | '(R0402-0201)'                 | '113'     | '1%'    | '1/16W'  | 'IO'       | 'RES CHIP 113 1/16W +-1%(0402)WTC'                 | 'CHIP0402'     | ''          | ''            | '20141016'
 '113'        | '1%'      | '1/16W'  | '0402LF'  | 'CHIP'   | 'CS11132FB09SEL1'(!)    = ''              | ''                 | 'CS11132FB09SEL1'       | 'R0402'             | '(R0402-0201)'                 | '113'     | '1%'    | '1/16W'  | 'DISCRETE' | 'RES CHIP 113 1/16W +-1%(0402)WTCSELA'             | 'CHIP0402'     | ''          | ''            | '20141016'
 '113'        | '1%'      | '1/16W'  | '0402LF'  | 'EMPTY'  | 'CS11132FB09SEL1'(!)    = ''              | ''                 | 'CS11132FB09SEL1'       | 'R0402'             | '(R0402-0201)'                 | '113'     | '1%'    | '1/16W'  | 'IO'       | 'RES CHIP 113 1/16W +-1%(0402)WTCSELA'             | 'CHIP0402'     | ''          | ''            | '20141016'
 '130'        | '1%'      | '1/16W'  | '0402LF'  | 'CHIP'   | 'CS11302FB05'(!)        = ''              | ''                 | 'CS11302FB05'           | 'R0402'             | '(R0402-0201)'                 | '130'     | '1%'    | '1/16W'  | 'DISCRETE' | 'RES CHIP 130 1/16W +-1%(0402)CYN'                 | 'CHIP0402'     | ''          | ''            | '20100621'
 '130'        | '1%'      | '1/16W'  | '0402LF'  | 'EMPTY'  | 'CS11302FB05'(!)        = ''              | ''                 | 'CS11302FB05'           | 'R0402'             | '(R0402-0201)'                 | '130'     | '1%'    | '1/16W'  | 'IO'       | 'RES CHIP 130 1/16W +-1%(0402)CYN'                 | 'CHIP0402'     | ''          | ''            | '20100621'
 '130'        | '1%'      | '1/16W'  | '0402LF'  | 'CHIP'   | 'CS11302FB05SEL1'(!)    = ''              | ''                 | 'CS11302FB05SEL1'       | 'R0402'             | '(R0402-0201)'                 | '130'     | '1%'    | '1/16W'  | 'DISCRETE' | 'RES CHIP 130 1/16W +-1%(0402)CYNSELA'             | 'CHIP0402'     | ''          | ''            | '20100621'
 '130'        | '1%'      | '1/16W'  | '0402LF'  | 'EMPTY'  | 'CS11302FB05SEL1'(!)    = ''              | ''                 | 'CS11302FB05SEL1'       | 'R0402'             | '(R0402-0201)'                 | '130'     | '1%'    | '1/16W'  | 'IO'       | 'RES CHIP 130 1/16W +-1%(0402)CYNSELA'             | 'CHIP0402'     | ''          | ''            | '20100621'
 '150'        | '1%'      | '1/16W'  | '0402LF'  | 'CHIP'   | 'CS11502FB18'(!)        = ''              | ''                 | 'CS11502FB18'           | 'R0402'             | '(R0402-0201)'                 | '150'     | '1%'    | '1/16W'  | 'DISCRETE' | 'RES CHIP 150 1/16W +-1%(0402)CYN'                 | 'CHIP0402'     | ''          | ''            | '20100621'
 '150'        | '1%'      | '1/16W'  | '0402LF'  | 'EMPTY'  | 'CS11502FB18'(!)        = ''              | ''                 | 'CS11502FB18'           | 'R0402'             | '(R0402-0201)'                 | '150'     | '1%'    | '1/16W'  | 'IO'       | 'RES CHIP 150 1/16W +-1%(0402)CYN'                 | 'CHIP0402'     | ''          | ''            | '20100621'
 '150'        | '1%'      | '1/16W'  | '0402LF'  | 'CHIP'   | 'CS11502FB18SEL1'(!)    = ''              | ''                 | 'CS11502FB18SEL1'       | 'R0402'             | '(R0402-0201)'                 | '150'     | '1%'    | '1/16W'  | 'DISCRETE' | 'RES CHIP 150 1/16W +-1%(0402)CYNSELA'             | 'CHIP0402'     | ''          | ''            | '20100621'
 '150'        | '1%'      | '1/16W'  | '0402LF'  | 'EMPTY'  | 'CS11502FB18SEL1'(!)    = ''              | ''                 | 'CS11502FB18SEL1'       | 'R0402'             | '(R0402-0201)'                 | '150'     | '1%'    | '1/16W'  | 'IO'       | 'RES CHIP 150 1/16W +-1%(0402)CYNSELA'             | 'CHIP0402'     | ''          | ''            | '20100621'

END_PART

END.

